G04 ================== begin FILE IDENTIFICATION RECORD ==================*
G04 Layout Name:  13130-1b.brd*
G04 Film Name:    TSILK*
G04 File Format:  Gerber RS274X*
G04 File Origin:  Cadence Allegro 16.5-S037*
G04 Origin Date:  Thu Nov 13 17:26:28 2014*
G04 *
G04 Layer:  VIA CLASS/FILMMASKTOP*
G04 Layer:  REF DES/ASSEMBLY_TOP*
G04 Layer:  PACKAGE GEOMETRY/SILKSCREEN_TOP*
G04 Layer:  DRAWING FORMAT/LAYER_PCB_STORY*
G04 Layer:  DRAWING FORMAT/LAYER_SILK_T*
G04 Layer:  BOARD GEOMETRY/SILKSCREEN_TOP*
G04 *
G04 Offset:    (0.00 0.00)*
G04 Mirror:    No*
G04 Mode:      Positive*
G04 Rotation:  0*
G04 FullContactRelief:  No*
G04 UndefLineWidth:     6.00*
G04 ================== end FILE IDENTIFICATION RECORD ====================*
%FSLAX35Y35*MOIN*%
%IR0*IPPOS*OFA0.00000B0.00000*MIA0B0*SFA1.00000B1.00000*%
%ADD10C,.024*%
%ADD11C,.01*%
%ADD12C,.02*%
%ADD13C,.012*%
%ADD14C,.013*%
%ADD15C,.015*%
%ADD16C,.016*%
%ADD17C,.006*%
%ADD18C,.005*%
%ADD19C,.008*%
%ADD20C,.009*%
G75*
%LPD*%
G75*
G36*
G01X22329Y178992D02*
X31129D01*
Y186992D01*
X22329D01*
Y178992D01*
G37*
G36*
G01X54847Y133624D02*
X56728Y131744D01*
Y135505D01*
X54847Y133624D01*
G37*
G36*
G01X66406Y91685D02*
X67950Y90141D01*
Y93229D01*
X66406Y91685D01*
G37*
G36*
G01X71155Y238586D02*
X69500Y240241D01*
Y236931D01*
X71155Y238586D01*
G37*
G36*
G01X96764Y70575D02*
X94545Y68356D01*
Y72794D01*
X96764Y70575D01*
G37*
G36*
G01X122350Y46850D02*
X121150Y45650D01*
X123500D01*
X123550D01*
X123500Y45700D01*
X122350Y46850D01*
G37*
G36*
G01X112350Y155850D02*
Y150150D01*
X115350D01*
Y155850D01*
X112350D01*
G37*
G36*
G01X113000Y168350D02*
Y162650D01*
X116000D01*
Y168350D01*
X113000D01*
G37*
G36*
G01X135104Y248448D02*
X130895D01*
X133000Y250552D01*
X135104Y248448D01*
G37*
G36*
G01X151500Y239500D02*
X153500Y241500D01*
X149500D01*
X151500Y239500D01*
G37*
G36*
G01X170713Y78884D02*
X173213Y76384D01*
Y81384D01*
X170713Y78884D01*
G37*
G36*
G01X178700Y123900D02*
Y115900D01*
X181500D01*
Y123900D01*
X178700D01*
G37*
G36*
G01X217198Y104571D02*
Y121771D01*
X198298D01*
Y104571D01*
X217198D01*
G37*
G36*
G01X199053Y122121D02*
Y104621D01*
X216443D01*
Y122121D01*
X199053D01*
G37*
G36*
G01X191350Y152750D02*
X202650D01*
Y169950D01*
X191350D01*
Y152750D01*
G37*
G36*
G01X219250Y86150D02*
X207950D01*
Y68950D01*
X219250D01*
Y86150D01*
G37*
G36*
G01X203850Y173350D02*
X202650Y172150D01*
X205000D01*
X205050D01*
X205000Y172200D01*
X203850Y173350D01*
G37*
G36*
G01X226050Y48550D02*
X224850Y47350D01*
X227200D01*
X227250D01*
X227200Y47400D01*
X226050Y48550D01*
G37*
G36*
G01X232098Y107871D02*
Y103871D01*
X230098Y105871D01*
X232098Y107871D01*
G37*
G36*
G01X225050Y171150D02*
X226250Y172350D01*
X223900D01*
X223850D01*
X223900Y172300D01*
X225050Y171150D01*
G37*
G36*
G01X232644Y195836D02*
X231412Y197068D01*
X232644Y198300D01*
Y195836D01*
G37*
G36*
G01X257350Y182650D02*
X256150Y183850D01*
Y181500D01*
Y181450D01*
X256200Y181500D01*
X257350Y182650D01*
G37*
G36*
G01X274400Y46500D02*
Y54500D01*
X271600D01*
Y46500D01*
X274400D01*
G37*
G36*
G01X288650Y75850D02*
X289850Y74650D01*
Y77000D01*
Y77050D01*
X289800Y77000D01*
X288650Y75850D01*
G37*
G36*
G01X284800Y251555D02*
Y232545D01*
X298800D01*
Y251555D01*
X284800D01*
G37*
G36*
G01X312162Y99131D02*
G03I-1850J0D01*
G37*
G36*
G01Y107511D02*
G03I-1850J0D01*
G37*
G36*
G01Y201151D02*
G03I-1850J0D01*
G37*
G36*
G01Y209531D02*
G03I-1850J0D01*
G37*
G36*
G01X320582Y99131D02*
G03I-1850J0D01*
G37*
G36*
G01Y209531D02*
G03I-1850J0D01*
G37*
G36*
G01X437842Y99131D02*
G03I-1850J0D01*
G37*
G36*
G01X446262D02*
G03I-1850J0D01*
G37*
G36*
G01X445925Y94872D02*
X448619Y97566D01*
X445925D01*
Y94872D01*
G37*
G36*
G01X446262Y107511D02*
G03I-1850J0D01*
G37*
G36*
G01Y201151D02*
G03I-1850J0D01*
G37*
G36*
G01X437842Y209531D02*
G03I-1850J0D01*
G37*
G36*
G01X446262D02*
G03I-1850J0D01*
G37*
G36*
G01X443150Y272150D02*
X444350Y273350D01*
X442000D01*
X441950D01*
X442000Y273300D01*
X443150Y272150D01*
G37*
G36*
G01X757921Y34616D02*
Y10980D01*
X502821D01*
Y34616D01*
X757921D01*
G37*
G36*
G01X496016Y250780D02*
Y274416D01*
X751116D01*
Y250780D01*
X496016D01*
G37*
G36*
G01X524350Y63150D02*
X523150Y64350D01*
Y62000D01*
Y61950D01*
X523200Y62000D01*
X524350Y63150D01*
G37*
G36*
G01X533060Y226335D02*
X532110Y227285D01*
Y225385D01*
X533060Y226335D01*
G37*
G36*
G01X550236Y195575D02*
X552455Y197794D01*
Y193356D01*
X550236Y195575D01*
G37*
G36*
G01X579000Y205745D02*
X593000D01*
Y224755D01*
X579000D01*
Y205745D01*
G37*
G36*
G01X596451Y180806D02*
X598951Y183306D01*
X593951D01*
X596451Y180806D01*
G37*
G36*
G01X631465Y122316D02*
X633965Y124816D01*
X628965D01*
X631465Y122316D01*
G37*
G36*
G01X626250Y187650D02*
X625050Y188850D01*
Y186500D01*
Y186450D01*
X625100Y186500D01*
X626250Y187650D01*
G37*
G36*
G01X649350Y185150D02*
X648150Y186350D01*
Y184000D01*
Y183950D01*
X648200Y184000D01*
X649350Y185150D01*
G37*
G36*
G01X648950Y159200D02*
Y162600D01*
X650650Y160900D01*
X648950Y159200D01*
G37*
G36*
G01X653800Y203650D02*
Y207650D01*
X649800Y203650D01*
X653800D01*
G37*
G36*
G01X667700Y113850D02*
X666000Y112150D01*
Y115550D01*
X667700Y113850D01*
G37*
G36*
G01Y141850D02*
X666000Y140150D01*
Y143550D01*
X667700Y141850D01*
G37*
G36*
G01X682100Y161050D02*
Y170950D01*
X678900D01*
Y161050D01*
X682100D01*
G37*
G36*
G01X697750Y198350D02*
Y209650D01*
X680550D01*
Y198350D01*
X697750D01*
G37*
G36*
G01X727290Y65715D02*
X726340Y64765D01*
X728240D01*
X727290Y65715D01*
G37*
G36*
G01X733754Y141863D02*
Y145113D01*
X737004D01*
X733754Y141863D01*
G37*
G36*
G01X785000Y130000D02*
X783000Y128000D01*
X787000D01*
X785000Y130000D01*
G37*
G36*
G01X861200Y221550D02*
X827500D01*
Y222550D01*
X860200D01*
Y418450D01*
X861200D01*
Y221550D01*
G37*
G54D10*
X119760Y191419D03*
X115760D03*
X123760D03*
X185546Y192509D03*
X180546D03*
X175546D03*
X323882Y71643D03*
X318882D03*
X328882D03*
G54D20*
G01X40900Y114100D02*
X37700D01*
G01X70900Y93500D02*
X74100D01*
G01X70400Y136000D02*
X67200D01*
G01X93600Y170500D02*
X90400D01*
G01X96020Y255400D02*
X92820D01*
G01X110600Y127500D02*
X107400D01*
G01X105100D02*
X101900D01*
G01X106600Y212500D02*
Y215700D01*
G01Y233800D02*
Y237000D01*
G01X116100Y127500D02*
X112900D01*
G01X122600Y217500D02*
X119400D01*
G01X188800Y140100D02*
X185600D01*
G01X174500Y215100D02*
Y211900D01*
G01X172600Y204900D02*
Y201700D01*
G01X193000Y178600D02*
Y175400D01*
G01X191000Y199100D02*
Y195900D01*
G01X215600Y173600D02*
X212400D01*
G01X211400Y202000D02*
X208200D01*
G01X471700Y256100D02*
Y252900D01*
G01Y251100D02*
Y247900D01*
G01X505400Y222000D02*
X508600D01*
G01X514100D02*
X510900D01*
G01X519100D02*
X515900D01*
G01X523000Y229400D02*
Y232600D01*
G01Y234400D02*
Y237600D01*
G01X554500Y234400D02*
Y237600D01*
G01X603700Y233000D02*
X606900D01*
G01X675800Y50007D02*
X672600D01*
G01X678000Y154900D02*
Y158100D01*
G01X722100Y58500D02*
X718900D01*
G01X717100D02*
X713900D01*
G01X721500Y86600D02*
Y83400D01*
G01X728500Y57400D02*
Y60600D01*
G01Y52400D02*
Y55600D01*
G01X733900Y104700D02*
X730700D01*
G01X738400Y236000D02*
X741600D01*
G01X749100Y63500D02*
X745900D01*
G01X748200Y108300D02*
X751400D01*
G01X766100Y152500D02*
X762900D01*
G01X778500Y10400D02*
Y13600D01*
G01Y5400D02*
Y8600D01*
G01X803000Y259000D02*
Y262200D01*
G01Y264000D02*
Y267200D01*
G01Y269000D02*
Y272200D01*
G54D11*
G01X20429Y178792D02*
Y171992D01*
G01X99010Y273350D02*
Y267250D01*
G01X178950Y124450D02*
X175000D01*
G01X274150Y45950D02*
X278100D01*
G01X284600Y252650D02*
X278200D01*
G01X559900Y72350D02*
X564100D01*
G01X593200Y204650D02*
X599600D01*
G01X615350Y135100D02*
Y130900D01*
G01X642150Y165400D02*
Y169600D01*
G01X682100Y159450D02*
X686700D01*
G54D12*
G01X10636Y-27865D02*
G02I-12000J0D01*
G01X14636D02*
X-17364D01*
G01X5486D02*
G02I-6850J0D01*
G01X-1364Y-43865D02*
Y-11865D01*
G01X14636Y-43865D02*
Y-123865D01*
G01D02*
X1309236D01*
G01X14636Y-79365D02*
X1309236D01*
G01X14636Y-43865D02*
X1309236D01*
G01X102812Y118400D02*
X119987D01*
G01X208000Y87251D02*
X201350D01*
G01X202600Y151649D02*
X209250D01*
G01X216848Y102971D02*
X223798D01*
G01X521736Y-43865D02*
Y-123865D01*
G01X659236Y-43865D02*
Y-123865D01*
G01X698851Y209600D02*
Y216250D01*
G01X774236Y-43865D02*
Y-123865D01*
G01X773600Y234312D02*
Y251487D01*
G01X941736Y-43865D02*
Y-123865D01*
G01X1111736Y-43865D02*
Y-123865D01*
G01X1309236Y-43865D02*
Y-123865D01*
G01X1341236Y-27865D02*
X1309236D01*
G01X1337236D02*
G02I-12000J0D01*
G01X1332086D02*
G02I-6850J0D01*
G01X1325236Y-43865D02*
Y-11865D01*
G54D13*
G01X22400Y100500D02*
X17600D01*
G01X34600Y95100D02*
X29800D01*
G01X23700Y113100D02*
X28500D01*
G01X30800D02*
X35600D01*
G01X22500Y144100D02*
Y148900D01*
G01Y137000D02*
Y141800D01*
G01X26150Y165200D02*
X30950D01*
G01X47750Y253100D02*
Y257900D01*
G01X61000Y119600D02*
Y120900D01*
G01Y116100D02*
Y117400D01*
G01X61100Y135000D02*
X59800D01*
G01X64600D02*
X63300D01*
G01X63600Y173000D02*
Y174300D01*
G01Y169500D02*
Y170800D01*
G01X59100Y261400D02*
Y256600D01*
G01X71600Y56000D02*
X76400D01*
G01X76700Y92300D02*
X78000D01*
G01X80200D02*
X81500D01*
G01X117500Y198900D02*
Y194100D01*
G01Y206400D02*
Y201600D01*
G01X141300Y64550D02*
X138300Y67550D01*
G01Y147450D02*
X141300Y150450D01*
G01X132900Y216400D02*
X128100D01*
G01X140000D02*
X135200D01*
G01X147100D02*
X142300D01*
G01X156500Y58600D02*
Y63400D01*
G01X167000Y212000D02*
X168300D01*
G01X163500D02*
X164800D01*
G01X186900Y256500D02*
X182100D01*
G01X186100Y268000D02*
X190900D01*
G01X178600D02*
X183400D01*
G01X194400Y256500D02*
X189600D01*
G01X209100Y268000D02*
X213900D01*
G01X216600D02*
X221400D01*
G01X225500Y193400D02*
Y188600D01*
G01X235900Y223500D02*
X231100D01*
G01X228400D02*
X223600D01*
G01X226100Y251000D02*
X230900D01*
G01X239100Y204300D02*
X234300D01*
G01X246200D02*
X241400D01*
G01X243400Y223500D02*
X238600D01*
G01X250900D02*
X246100D01*
G01X233600Y251000D02*
X238400D01*
G01X248200D02*
X253000D01*
G01X241100D02*
X245900D01*
G01X255300D02*
X260100D01*
G01X281011Y263386D02*
G02I-4200J0D01*
G01X301011D02*
G02I-4200J0D01*
G01X341400Y59500D02*
X336600D01*
G01X348900D02*
X344100D01*
G01X374600Y55500D02*
X379400D01*
G01X462113Y45276D02*
G02I-4200J0D01*
G01X460500Y164600D02*
Y159800D01*
G01Y157500D02*
Y152700D01*
G01X482113Y45276D02*
G02I-4200J0D01*
G01X585400Y233000D02*
X580600D01*
G01X592900D02*
X588100D01*
G01X614600Y51007D02*
X619400D01*
G01X622100D02*
X626900D01*
G01X632400Y233500D02*
X627600D01*
G01X639900D02*
X635100D01*
G01X658600Y51007D02*
X663400D01*
G01X661000Y102600D02*
Y107400D01*
G01Y95100D02*
Y99900D01*
G01Y130600D02*
Y135400D01*
G01Y123100D02*
Y127900D01*
G01X665700Y51007D02*
X670500D01*
G01X777400Y253800D02*
Y258600D01*
G01X808432Y27032D02*
G02I-4400J0D01*
G01X798432D02*
G02I-4400J0D01*
G01X808432Y37032D02*
G02I-4400J0D01*
G01Y47032D02*
G02I-4400J0D01*
G01X798432Y37032D02*
G02I-4400J0D01*
G01Y47032D02*
G02I-4400J0D01*
G01X808432Y57032D02*
G02I-4400J0D01*
G01X798432D02*
G02I-4400J0D01*
G01X808432Y67032D02*
G02I-4400J0D01*
G01X798432D02*
G02I-4400J0D01*
G01X791000Y111600D02*
Y116400D01*
G01Y120600D02*
Y125400D01*
G01X801100Y231800D02*
Y227000D01*
G01Y224700D02*
Y219900D01*
G54D14*
G01X506071Y1698D02*
X504571D01*
G01X747866Y283698D02*
X749366D01*
G54D15*
G01X0Y72440D02*
Y103149D01*
G01Y210235D02*
Y240944D01*
G01Y348031D02*
Y378739D01*
G01Y485826D02*
Y516535D01*
G01X133465Y290550D02*
X102756D01*
G01X133465Y298424D02*
X102756D01*
G01X330314Y290551D02*
X299606D01*
G01X330314Y298425D02*
X299606D01*
G01X527166Y290550D02*
X496457D01*
G01X527166Y298424D02*
X496457D01*
G01X724016Y290550D02*
X693308D01*
G01X724016Y298424D02*
X693308D01*
G01X724250Y194650D02*
X720300D01*
G01X826771Y103149D02*
Y72440D01*
G01Y240944D02*
Y210235D01*
G01Y378739D02*
Y348031D01*
G01Y516535D02*
Y485826D01*
G54D16*
G01X244300Y168000D02*
Y162150D01*
G01X792732Y73032D02*
X787732D01*
Y68032D01*
G54D17*
G01X70851Y-113865D02*
Y-96365D01*
G01X80021D02*
Y-113865D01*
G01Y-105115D02*
X70851D01*
G01X92936Y-113865D02*
X91626Y-113573D01*
X90316Y-112407D01*
X89442Y-110365D01*
X89006Y-108032D01*
X89442Y-105698D01*
X90316Y-103657D01*
X91626Y-102490D01*
X92936Y-102199D01*
X94246Y-102490D01*
X95556Y-103657D01*
X96429Y-105698D01*
X96648Y-108032D01*
X96429Y-110365D01*
X95556Y-112407D01*
X94246Y-113573D01*
X92936Y-113865D01*
G01X106724D02*
Y-102199D01*
G01Y-105115D02*
X107598Y-103657D01*
X108908Y-102490D01*
X110654Y-102199D01*
X112182Y-102490D01*
X113493Y-103657D01*
X114148Y-105698D01*
Y-113865D01*
G01X124661Y-105990D02*
X131648D01*
X130993Y-103948D01*
X129901Y-102782D01*
X128373Y-102199D01*
X126844Y-102490D01*
X125534Y-103365D01*
X124661Y-105407D01*
X124224Y-107157D01*
Y-108907D01*
X124661Y-110657D01*
X125753Y-112407D01*
X127063Y-113573D01*
X128591Y-113865D01*
X130119Y-113282D01*
X131648Y-111532D01*
G01X140851Y-119115D02*
X142161Y-119698D01*
X143908Y-119115D01*
X144999Y-117949D01*
X145873Y-116490D01*
X147182Y-111824D01*
X150021Y-102199D01*
G01X143034D02*
X147182Y-111824D01*
G01X182182Y-104532D02*
X183056Y-103657D01*
X183711Y-102199D01*
X184148Y-100156D01*
X183711Y-98407D01*
X182838Y-97240D01*
X181309Y-96365D01*
X175414D01*
Y-113865D01*
X182619D01*
X184148Y-112699D01*
X185021Y-110948D01*
X185458Y-108907D01*
X185021Y-106865D01*
X183711Y-105115D01*
X182182Y-104532D01*
X175414D01*
G01X201866Y-113865D02*
Y-102199D01*
G01Y-104240D02*
X200993Y-103074D01*
X199682Y-102490D01*
X198154Y-102199D01*
X196626Y-102782D01*
X195316Y-103948D01*
X194442Y-105698D01*
X194006Y-108032D01*
X194442Y-110365D01*
X195316Y-112115D01*
X196626Y-113282D01*
X198154Y-113865D01*
X199682Y-113573D01*
X200993Y-112699D01*
X201866Y-111532D01*
G01X219366Y-96365D02*
Y-113865D01*
G01Y-111241D02*
X218493Y-112699D01*
X217182Y-113573D01*
X215654Y-113865D01*
X213908Y-113282D01*
X212598Y-111824D01*
X211724Y-110074D01*
X211506Y-108032D01*
X211724Y-105990D01*
X212598Y-104240D01*
X213908Y-102782D01*
X215654Y-102199D01*
X217182Y-102490D01*
X218274Y-103074D01*
X219366Y-104240D01*
G01X229879Y-118240D02*
X231408Y-119407D01*
X233154Y-119698D01*
X234682Y-119407D01*
X235993Y-117949D01*
X236866Y-115907D01*
Y-102199D01*
G01Y-104532D02*
X235993Y-103365D01*
X234682Y-102490D01*
X233154Y-102199D01*
X231408Y-102782D01*
X230316Y-103948D01*
X229442Y-105990D01*
X229006Y-108032D01*
X229224Y-109782D01*
X230098Y-111824D01*
X231408Y-113282D01*
X233154Y-113865D01*
X234464Y-113573D01*
X235993Y-112407D01*
X236866Y-111241D01*
G01X247161Y-105990D02*
X254148D01*
X253493Y-103948D01*
X252401Y-102782D01*
X250873Y-102199D01*
X249344Y-102490D01*
X248034Y-103365D01*
X247161Y-105407D01*
X246724Y-107157D01*
Y-108907D01*
X247161Y-110657D01*
X248253Y-112407D01*
X249563Y-113573D01*
X251091Y-113865D01*
X252619Y-113282D01*
X254148Y-111532D01*
G01X264879Y-113865D02*
Y-102199D01*
G01Y-104532D02*
X265971Y-103365D01*
X267063Y-102490D01*
X268591Y-102199D01*
X269682Y-102490D01*
X270993Y-103365D01*
G01X298569Y-113865D02*
Y-96365D01*
X303809D01*
X305556Y-97240D01*
X306866Y-99282D01*
X307303Y-101615D01*
X306866Y-103948D01*
X305774Y-105698D01*
X303809Y-106574D01*
X298569D01*
G01X324366Y-113865D02*
Y-102199D01*
G01Y-104240D02*
X323493Y-103074D01*
X322182Y-102490D01*
X320654Y-102199D01*
X319126Y-102782D01*
X317816Y-103948D01*
X316942Y-105698D01*
X316506Y-108032D01*
X316942Y-110365D01*
X317816Y-112115D01*
X319126Y-113282D01*
X320654Y-113865D01*
X322182Y-113573D01*
X323493Y-112699D01*
X324366Y-111532D01*
G01X334224Y-113865D02*
Y-102199D01*
G01Y-105115D02*
X335098Y-103657D01*
X336408Y-102490D01*
X338154Y-102199D01*
X339682Y-102490D01*
X340993Y-103657D01*
X341648Y-105698D01*
Y-113865D01*
G01X355436Y-96365D02*
Y-113865D01*
G01X352379Y-102199D02*
X358493D01*
G01X369224Y-113865D02*
Y-96365D01*
G01Y-104823D02*
X370316Y-103365D01*
X371408Y-102490D01*
X373154Y-102199D01*
X374464Y-102490D01*
X375993Y-103657D01*
X376648Y-105407D01*
Y-113865D01*
G01X387161Y-105990D02*
X394148D01*
X393493Y-103948D01*
X392401Y-102782D01*
X390873Y-102199D01*
X389344Y-102490D01*
X388034Y-103365D01*
X387161Y-105407D01*
X386724Y-107157D01*
Y-108907D01*
X387161Y-110657D01*
X388253Y-112407D01*
X389563Y-113573D01*
X391091Y-113865D01*
X392619Y-113282D01*
X394148Y-111532D01*
G01X404879Y-113865D02*
Y-102199D01*
G01Y-104532D02*
X405971Y-103365D01*
X407063Y-102490D01*
X408591Y-102199D01*
X409682Y-102490D01*
X410993Y-103365D01*
G01X437259Y-113865D02*
Y-96365D01*
X442936Y-110948D01*
X448613Y-96365D01*
Y-113865D01*
G01X462182Y-104532D02*
X463056Y-103657D01*
X463711Y-102199D01*
X464148Y-100156D01*
X463711Y-98407D01*
X462838Y-97240D01*
X461309Y-96365D01*
X455414D01*
Y-113865D01*
X462619D01*
X464148Y-112699D01*
X465021Y-110948D01*
X465458Y-108907D01*
X465021Y-106865D01*
X463711Y-105115D01*
X462182Y-104532D01*
X455414D01*
G01X227259Y-68865D02*
Y-51365D01*
X232936Y-65948D01*
X238613Y-51365D01*
Y-68865D01*
G01X250436D02*
X249126Y-68573D01*
X247816Y-67407D01*
X246942Y-65365D01*
X246506Y-63032D01*
X246942Y-60698D01*
X247816Y-58657D01*
X249126Y-57490D01*
X250436Y-57199D01*
X251746Y-57490D01*
X253056Y-58657D01*
X253929Y-60698D01*
X254148Y-63032D01*
X253929Y-65365D01*
X253056Y-67407D01*
X251746Y-68573D01*
X250436Y-68865D01*
G01X271866Y-51365D02*
Y-68865D01*
G01Y-66241D02*
X270993Y-67699D01*
X269682Y-68573D01*
X268154Y-68865D01*
X266408Y-68282D01*
X265098Y-66824D01*
X264224Y-65074D01*
X264006Y-63032D01*
X264224Y-60990D01*
X265098Y-59240D01*
X266408Y-57782D01*
X268154Y-57199D01*
X269682Y-57490D01*
X270774Y-58074D01*
X271866Y-59240D01*
G01X282161Y-60990D02*
X289148D01*
X288493Y-58948D01*
X287401Y-57782D01*
X285873Y-57199D01*
X284344Y-57490D01*
X283034Y-58365D01*
X282161Y-60407D01*
X281724Y-62157D01*
Y-63907D01*
X282161Y-65657D01*
X283253Y-67407D01*
X284563Y-68573D01*
X286091Y-68865D01*
X287619Y-68282D01*
X289148Y-66532D01*
G01X302936Y-68865D02*
Y-51365D01*
G01X542319Y-68865D02*
Y-51365D01*
X547559D01*
X549306Y-52240D01*
X550616Y-54282D01*
X551053Y-56615D01*
X550616Y-58948D01*
X549524Y-60698D01*
X547559Y-61574D01*
X542319D01*
G01X568989Y-52824D02*
X567679Y-51948D01*
X566151Y-51365D01*
X564404D01*
X562439Y-52240D01*
X560911Y-53698D01*
X559819Y-55449D01*
X558946Y-58365D01*
X558727Y-60990D01*
X559164Y-63615D01*
X559819Y-65365D01*
X561129Y-67115D01*
X562658Y-68282D01*
X564186Y-68865D01*
X565714D01*
X567243Y-68282D01*
X568553Y-67407D01*
X569645Y-66241D01*
G01X583432Y-59532D02*
X584306Y-58657D01*
X584961Y-57199D01*
X585398Y-55156D01*
X584961Y-53407D01*
X584088Y-52240D01*
X582559Y-51365D01*
X576664D01*
Y-68865D01*
X583869D01*
X585398Y-67699D01*
X586271Y-65948D01*
X586708Y-63907D01*
X586271Y-61865D01*
X584961Y-60115D01*
X583432Y-59532D01*
X576664D01*
G01X592636Y-74698D02*
X605736D01*
G01X611664Y-68865D02*
Y-51365D01*
X621708Y-68865D01*
Y-51365D01*
G01X634186Y-68865D02*
X632439Y-68573D01*
X630911Y-67407D01*
X629601Y-65657D01*
X628727Y-63615D01*
X628291Y-61282D01*
Y-58948D01*
X628727Y-56615D01*
X629601Y-54573D01*
X630911Y-52824D01*
X632439Y-51657D01*
X634186Y-51365D01*
X635932Y-51657D01*
X637461Y-52824D01*
X638771Y-54573D01*
X639645Y-56615D01*
X640081Y-58948D01*
Y-61282D01*
X639645Y-63615D01*
X638771Y-65657D01*
X637461Y-67407D01*
X635932Y-68573D01*
X634186Y-68865D01*
G01X555436Y-113865D02*
Y-96365D01*
X552816Y-99865D01*
G01Y-113865D02*
X558056D01*
G01X568133Y-110365D02*
X569442Y-112407D01*
X571189Y-113573D01*
X573154Y-113865D01*
X574901Y-113573D01*
X576648Y-112115D01*
X577739Y-110365D01*
X577958Y-108615D01*
X577521Y-106574D01*
X575993Y-105115D01*
X574464Y-104532D01*
X572499D01*
G01X574464D02*
X575774Y-103657D01*
X576866Y-102199D01*
X577303Y-100449D01*
X576866Y-98698D01*
X575774Y-97240D01*
X573809Y-96365D01*
X571844Y-96657D01*
X569879Y-97824D01*
G01X590436Y-113865D02*
Y-96365D01*
X587816Y-99865D01*
G01Y-113865D02*
X593056D01*
G01X603133Y-110365D02*
X604442Y-112407D01*
X606189Y-113573D01*
X608154Y-113865D01*
X609901Y-113573D01*
X611648Y-112115D01*
X612739Y-110365D01*
X612958Y-108615D01*
X612521Y-106574D01*
X610993Y-105115D01*
X609464Y-104532D01*
X607499D01*
G01X609464D02*
X610774Y-103657D01*
X611866Y-102199D01*
X612303Y-100449D01*
X611866Y-98698D01*
X610774Y-97240D01*
X608809Y-96365D01*
X606844Y-96657D01*
X604879Y-97824D01*
G01X625436Y-96365D02*
X623689Y-96948D01*
X622379Y-98407D01*
X621506Y-100156D01*
X620851Y-102490D01*
X620633Y-105115D01*
X620851Y-107740D01*
X621506Y-110074D01*
X622379Y-111824D01*
X623689Y-113282D01*
X625436Y-113865D01*
X627182Y-113282D01*
X628493Y-111824D01*
X629366Y-110074D01*
X630021Y-107740D01*
X630239Y-105115D01*
X630021Y-102490D01*
X629366Y-100156D01*
X628493Y-98407D01*
X627182Y-96948D01*
X625436Y-96365D01*
G01X685027Y-51365D02*
X690486Y-68865D01*
X695945Y-51365D01*
G01X712353Y-68865D02*
X703619D01*
Y-51365D01*
X712353D01*
G01X708859Y-59823D02*
X703619D01*
G01X721119Y-68865D02*
Y-51365D01*
X726578D01*
X728324Y-52240D01*
X729416Y-53407D01*
X729853Y-55740D01*
X729416Y-58074D01*
X728106Y-59532D01*
X726578Y-60407D01*
X721119D01*
G01X726578D02*
X729853Y-68865D01*
G01X742986Y-69448D02*
X742549Y-69157D01*
Y-68573D01*
X742986Y-68282D01*
X743423Y-68573D01*
Y-69157D01*
X742986Y-69448D01*
G01X707986Y-113865D02*
Y-96365D01*
X705366Y-99865D01*
G01Y-113865D02*
X710606D01*
G01X727232Y-104532D02*
X728106Y-103657D01*
X728761Y-102199D01*
X729198Y-100156D01*
X728761Y-98407D01*
X727888Y-97240D01*
X726359Y-96365D01*
X720464D01*
Y-113865D01*
X727669D01*
X729198Y-112699D01*
X730071Y-110948D01*
X730508Y-108907D01*
X730071Y-106865D01*
X728761Y-105115D01*
X727232Y-104532D01*
X720464D01*
G01X822936Y-96365D02*
Y-113865D01*
G01X817914Y-96365D02*
X827958D01*
G01X835851Y-111532D02*
X837598Y-112990D01*
X839563Y-113865D01*
X841309D01*
X843056Y-112990D01*
X844366Y-111532D01*
X845021Y-109490D01*
X844584Y-107449D01*
X843493Y-105698D01*
X841528Y-104532D01*
X838908Y-103948D01*
X837379Y-102782D01*
X836724Y-100740D01*
X837161Y-98698D01*
X838253Y-97240D01*
X839781Y-96365D01*
X841309D01*
X842838Y-96948D01*
X844148Y-98407D01*
G01X855316Y-96365D02*
X860556D01*
G01X857936D02*
Y-113865D01*
G01X855316D02*
X860556D01*
G01X871069Y-96365D02*
Y-113865D01*
X879803D01*
G01X888133D02*
Y-96365D01*
G01X896429D02*
X888133Y-107157D01*
G01X897739Y-113865D02*
X891844Y-102199D01*
G01X818569Y-51365D02*
Y-68865D01*
X827303D01*
G01X844366D02*
Y-57199D01*
G01Y-59240D02*
X843493Y-58074D01*
X842182Y-57490D01*
X840654Y-57199D01*
X839126Y-57782D01*
X837816Y-58948D01*
X836942Y-60698D01*
X836506Y-63032D01*
X836942Y-65365D01*
X837816Y-67115D01*
X839126Y-68282D01*
X840654Y-68865D01*
X842182Y-68573D01*
X843493Y-67699D01*
X844366Y-66532D01*
G01X853351Y-74115D02*
X854661Y-74698D01*
X856408Y-74115D01*
X857499Y-72949D01*
X858373Y-71490D01*
X859682Y-66824D01*
X862521Y-57199D01*
G01X855534D02*
X859682Y-66824D01*
G01X872161Y-60990D02*
X879148D01*
X878493Y-58948D01*
X877401Y-57782D01*
X875873Y-57199D01*
X874344Y-57490D01*
X873034Y-58365D01*
X872161Y-60407D01*
X871724Y-62157D01*
Y-63907D01*
X872161Y-65657D01*
X873253Y-67407D01*
X874563Y-68573D01*
X876091Y-68865D01*
X877619Y-68282D01*
X879148Y-66532D01*
G01X889879Y-68865D02*
Y-57199D01*
G01Y-59532D02*
X890971Y-58365D01*
X892063Y-57490D01*
X893591Y-57199D01*
X894682Y-57490D01*
X895993Y-58365D01*
G01X943619Y-110365D02*
X944711Y-112115D01*
X946021Y-113282D01*
X947549Y-113865D01*
X949296Y-113282D01*
X950606Y-112115D01*
X951916Y-110365D01*
X952353Y-108032D01*
Y-96365D01*
G01X965486Y-113865D02*
X963739Y-113573D01*
X962211Y-112407D01*
X960901Y-110657D01*
X960027Y-108615D01*
X959591Y-106282D01*
Y-103948D01*
X960027Y-101615D01*
X960901Y-99573D01*
X962211Y-97824D01*
X963739Y-96657D01*
X965486Y-96365D01*
X967232Y-96657D01*
X968761Y-97824D01*
X970071Y-99573D01*
X970945Y-101615D01*
X971381Y-103948D01*
Y-106282D01*
X970945Y-108615D01*
X970071Y-110657D01*
X968761Y-112407D01*
X967232Y-113573D01*
X965486Y-113865D01*
G01X978401Y-111532D02*
X980148Y-112990D01*
X982113Y-113865D01*
X983859D01*
X985606Y-112990D01*
X986916Y-111532D01*
X987571Y-109490D01*
X987134Y-107449D01*
X986043Y-105698D01*
X984078Y-104532D01*
X981458Y-103948D01*
X979929Y-102782D01*
X979274Y-100740D01*
X979711Y-98698D01*
X980803Y-97240D01*
X982331Y-96365D01*
X983859D01*
X985388Y-96948D01*
X986698Y-98407D01*
G01X1004853Y-113865D02*
X996119D01*
Y-96365D01*
X1004853D01*
G01X1001359Y-104823D02*
X996119D01*
G01X1013619Y-113865D02*
Y-96365D01*
X1018859D01*
X1020606Y-97240D01*
X1021916Y-99282D01*
X1022353Y-101615D01*
X1021916Y-103948D01*
X1020824Y-105698D01*
X1018859Y-106574D01*
X1013619D01*
G01X1030901Y-113865D02*
Y-96365D01*
G01X1040071D02*
Y-113865D01*
G01Y-105115D02*
X1030901D01*
G01X1066119Y-96365D02*
Y-113865D01*
X1074853D01*
G01X1082527D02*
X1087986Y-96365D01*
X1093445Y-113865D01*
G01X1091479Y-107740D02*
X1084492D01*
G01X1100683Y-96365D02*
Y-108907D01*
X1101556Y-111532D01*
X1103303Y-113282D01*
X1105486Y-113865D01*
X1107669Y-113282D01*
X1109416Y-111532D01*
X1110289Y-108907D01*
Y-96365D01*
G01X960683Y-68865D02*
Y-51365D01*
X965049D01*
X966796Y-52240D01*
X968106Y-53407D01*
X969198Y-55156D01*
X970071Y-57199D01*
X970289Y-60115D01*
X970071Y-63032D01*
X969198Y-65074D01*
X968106Y-66824D01*
X966796Y-67990D01*
X965049Y-68865D01*
X960683D01*
G01X979711Y-60990D02*
X986698D01*
X986043Y-58948D01*
X984951Y-57782D01*
X983423Y-57199D01*
X981894Y-57490D01*
X980584Y-58365D01*
X979711Y-60407D01*
X979274Y-62157D01*
Y-63907D01*
X979711Y-65657D01*
X980803Y-67407D01*
X982113Y-68573D01*
X983641Y-68865D01*
X985169Y-68282D01*
X986698Y-66532D01*
G01X997211Y-66824D02*
X998303Y-67990D01*
X999831Y-68865D01*
X1001141D01*
X1002451Y-68282D01*
X1003324Y-67407D01*
X1003761Y-66241D01*
X1003543Y-64490D01*
X1002669Y-63615D01*
X998739Y-61865D01*
X997866Y-59823D01*
X998303Y-58365D01*
X999176Y-57490D01*
X1000486Y-57199D01*
X1001796Y-57490D01*
X1003106Y-58365D01*
G01X1017986Y-57199D02*
Y-68865D01*
G01Y-52532D02*
X1017549Y-52240D01*
Y-51657D01*
X1017986Y-51365D01*
X1018423Y-51657D01*
Y-52240D01*
X1017986Y-52532D01*
G01X1032429Y-73240D02*
X1033958Y-74407D01*
X1035704Y-74698D01*
X1037232Y-74407D01*
X1038543Y-72949D01*
X1039416Y-70907D01*
Y-57199D01*
G01Y-59532D02*
X1038543Y-58365D01*
X1037232Y-57490D01*
X1035704Y-57199D01*
X1033958Y-57782D01*
X1032866Y-58948D01*
X1031992Y-60990D01*
X1031556Y-63032D01*
X1031774Y-64782D01*
X1032648Y-66824D01*
X1033958Y-68282D01*
X1035704Y-68865D01*
X1037014Y-68573D01*
X1038543Y-67407D01*
X1039416Y-66241D01*
G01X1049274Y-68865D02*
Y-57199D01*
G01Y-60115D02*
X1050148Y-58657D01*
X1051458Y-57490D01*
X1053204Y-57199D01*
X1054732Y-57490D01*
X1056043Y-58657D01*
X1056698Y-60698D01*
Y-68865D01*
G01X1067211Y-60990D02*
X1074198D01*
X1073543Y-58948D01*
X1072451Y-57782D01*
X1070923Y-57199D01*
X1069394Y-57490D01*
X1068084Y-58365D01*
X1067211Y-60407D01*
X1066774Y-62157D01*
Y-63907D01*
X1067211Y-65657D01*
X1068303Y-67407D01*
X1069613Y-68573D01*
X1071141Y-68865D01*
X1072669Y-68282D01*
X1074198Y-66532D01*
G01X1084929Y-68865D02*
Y-57199D01*
G01Y-59532D02*
X1086021Y-58365D01*
X1087113Y-57490D01*
X1088641Y-57199D01*
X1089732Y-57490D01*
X1091043Y-58365D01*
G01X1131686Y-113865D02*
Y-96365D01*
X1129066Y-99865D01*
G01Y-113865D02*
X1134306D01*
G01X1149186D02*
Y-96365D01*
X1146566Y-99865D01*
G01Y-113865D02*
X1151806D01*
G01X1162756Y-114448D02*
X1170616Y-96365D01*
G01X1184186Y-113865D02*
Y-96365D01*
X1181566Y-99865D01*
G01Y-113865D02*
X1186806D01*
G01X1196883Y-110365D02*
X1198192Y-112407D01*
X1199939Y-113573D01*
X1201904Y-113865D01*
X1203651Y-113573D01*
X1205398Y-112115D01*
X1206489Y-110365D01*
X1206708Y-108615D01*
X1206271Y-106574D01*
X1204743Y-105115D01*
X1203214Y-104532D01*
X1201249D01*
G01X1203214D02*
X1204524Y-103657D01*
X1205616Y-102199D01*
X1206053Y-100449D01*
X1205616Y-98698D01*
X1204524Y-97240D01*
X1202559Y-96365D01*
X1200594Y-96657D01*
X1198629Y-97824D01*
G01X1215256Y-114448D02*
X1223116Y-96365D01*
G01X1232538Y-99282D02*
X1233848Y-97532D01*
X1235376Y-96657D01*
X1237123Y-96365D01*
X1239306Y-96948D01*
X1240834Y-98407D01*
X1241271Y-100156D01*
X1241053Y-101907D01*
X1240179Y-103365D01*
X1235813Y-106282D01*
X1233848Y-108323D01*
X1232538Y-111241D01*
X1232101Y-113865D01*
X1241271D01*
G01X1254186Y-96365D02*
X1252439Y-96948D01*
X1251129Y-98407D01*
X1250256Y-100156D01*
X1249601Y-102490D01*
X1249383Y-105115D01*
X1249601Y-107740D01*
X1250256Y-110074D01*
X1251129Y-111824D01*
X1252439Y-113282D01*
X1254186Y-113865D01*
X1255932Y-113282D01*
X1257243Y-111824D01*
X1258116Y-110074D01*
X1258771Y-107740D01*
X1258989Y-105115D01*
X1258771Y-102490D01*
X1258116Y-100156D01*
X1257243Y-98407D01*
X1255932Y-96948D01*
X1254186Y-96365D01*
G01X1271686Y-113865D02*
Y-96365D01*
X1269066Y-99865D01*
G01Y-113865D02*
X1274306D01*
G01X1291806D02*
Y-96365D01*
X1283727Y-108907D01*
X1294645D01*
G01X1179383Y-68865D02*
Y-51365D01*
X1183749D01*
X1185496Y-52240D01*
X1186806Y-53407D01*
X1187898Y-55156D01*
X1188771Y-57199D01*
X1188989Y-60115D01*
X1188771Y-63032D01*
X1187898Y-65074D01*
X1186806Y-66824D01*
X1185496Y-67990D01*
X1183749Y-68865D01*
X1179383D01*
G01X1205616D02*
Y-57199D01*
G01Y-59240D02*
X1204743Y-58074D01*
X1203432Y-57490D01*
X1201904Y-57199D01*
X1200376Y-57782D01*
X1199066Y-58948D01*
X1198192Y-60698D01*
X1197756Y-63032D01*
X1198192Y-65365D01*
X1199066Y-67115D01*
X1200376Y-68282D01*
X1201904Y-68865D01*
X1203432Y-68573D01*
X1204743Y-67699D01*
X1205616Y-66532D01*
G01X1219186Y-51365D02*
Y-68865D01*
G01X1216129Y-57199D02*
X1222243D01*
G01X1233411Y-60990D02*
X1240398D01*
X1239743Y-58948D01*
X1238651Y-57782D01*
X1237123Y-57199D01*
X1235594Y-57490D01*
X1234284Y-58365D01*
X1233411Y-60407D01*
X1232974Y-62157D01*
Y-63907D01*
X1233411Y-65657D01*
X1234503Y-67407D01*
X1235813Y-68573D01*
X1237341Y-68865D01*
X1238869Y-68282D01*
X1240398Y-66532D01*
G01X1967Y136500D02*
Y139000D01*
X2967D01*
X3300Y138875D01*
X3550Y138583D01*
X3633Y138250D01*
X3550Y137917D01*
X3342Y137667D01*
X2967Y137542D01*
X1967D01*
G01X6817Y138792D02*
X6567Y138917D01*
X6275Y139000D01*
X5942D01*
X5567Y138875D01*
X5275Y138667D01*
X5067Y138417D01*
X4900Y138000D01*
X4858Y137625D01*
X4942Y137250D01*
X5067Y137000D01*
X5317Y136750D01*
X5608Y136583D01*
X5900Y136500D01*
X6192D01*
X6483Y136583D01*
X6733Y136708D01*
X6942Y136875D01*
G01X9000Y136500D02*
Y139000D01*
X8500Y138500D01*
G01Y136500D02*
X9500D01*
G01X12100D02*
X12392Y136542D01*
X12725Y136667D01*
X12933Y136875D01*
X13017Y137167D01*
X12933Y137458D01*
X12683Y137708D01*
X12308Y137833D01*
X11892D01*
X11642Y137917D01*
X11433Y138125D01*
X11350Y138417D01*
X11475Y138708D01*
X11767Y138917D01*
X12100Y139000D01*
X12433Y138917D01*
X12725Y138708D01*
X12850Y138417D01*
X12767Y138125D01*
X12558Y137917D01*
X12308Y137833D01*
X11892D01*
X11517Y137708D01*
X11267Y137458D01*
X11183Y137167D01*
X11267Y136875D01*
X11475Y136667D01*
X11808Y136542D01*
X12100Y136500D01*
G01X15200D02*
X15492Y136542D01*
X15825Y136667D01*
X16033Y136875D01*
X16117Y137167D01*
X16033Y137458D01*
X15783Y137708D01*
X15408Y137833D01*
X14992D01*
X14742Y137917D01*
X14533Y138125D01*
X14450Y138417D01*
X14575Y138708D01*
X14867Y138917D01*
X15200Y139000D01*
X15533Y138917D01*
X15825Y138708D01*
X15950Y138417D01*
X15867Y138125D01*
X15658Y137917D01*
X15408Y137833D01*
X14992D01*
X14617Y137708D01*
X14367Y137458D01*
X14283Y137167D01*
X14367Y136875D01*
X14575Y136667D01*
X14908Y136542D01*
X15200Y136500D01*
G01X1967Y140500D02*
Y143000D01*
X2967D01*
X3300Y142875D01*
X3550Y142583D01*
X3633Y142250D01*
X3550Y141917D01*
X3342Y141667D01*
X2967Y141542D01*
X1967D01*
G01X6817Y142792D02*
X6567Y142917D01*
X6275Y143000D01*
X5942D01*
X5567Y142875D01*
X5275Y142667D01*
X5067Y142417D01*
X4900Y142000D01*
X4858Y141625D01*
X4942Y141250D01*
X5067Y141000D01*
X5317Y140750D01*
X5608Y140583D01*
X5900Y140500D01*
X6192D01*
X6483Y140583D01*
X6733Y140708D01*
X6942Y140875D01*
G01X9000Y140500D02*
Y143000D01*
X8500Y142500D01*
G01Y140500D02*
X9500D01*
G01X12100D02*
X12392Y140542D01*
X12725Y140667D01*
X12933Y140875D01*
X13017Y141167D01*
X12933Y141458D01*
X12683Y141708D01*
X12308Y141833D01*
X11892D01*
X11642Y141917D01*
X11433Y142125D01*
X11350Y142417D01*
X11475Y142708D01*
X11767Y142917D01*
X12100Y143000D01*
X12433Y142917D01*
X12725Y142708D01*
X12850Y142417D01*
X12767Y142125D01*
X12558Y141917D01*
X12308Y141833D01*
X11892D01*
X11517Y141708D01*
X11267Y141458D01*
X11183Y141167D01*
X11267Y140875D01*
X11475Y140667D01*
X11808Y140542D01*
X12100Y140500D01*
G01X15117D02*
X15200Y141042D01*
X15325Y141500D01*
X15492Y141917D01*
X15700Y142375D01*
X16033Y143000D01*
X14367D01*
G01X2117Y177000D02*
Y179500D01*
X3158D01*
X3492Y179375D01*
X3700Y179208D01*
X3783Y178875D01*
X3700Y178542D01*
X3450Y178333D01*
X3158Y178208D01*
X2117D01*
G01X3158D02*
X3783Y177000D01*
G01X6550D02*
Y179500D01*
X5008Y177708D01*
X7092D01*
G01X2117Y181500D02*
Y184000D01*
X3158D01*
X3492Y183875D01*
X3700Y183708D01*
X3783Y183375D01*
X3700Y183042D01*
X3450Y182833D01*
X3158Y182708D01*
X2117D01*
G01X3158D02*
X3783Y181500D01*
G01X6050D02*
X6342Y181542D01*
X6675Y181667D01*
X6883Y181875D01*
X6967Y182167D01*
X6883Y182458D01*
X6633Y182708D01*
X6258Y182833D01*
X5842D01*
X5592Y182917D01*
X5383Y183125D01*
X5300Y183417D01*
X5425Y183708D01*
X5717Y183917D01*
X6050Y184000D01*
X6383Y183917D01*
X6675Y183708D01*
X6800Y183417D01*
X6717Y183125D01*
X6508Y182917D01*
X6258Y182833D01*
X5842D01*
X5467Y182708D01*
X5217Y182458D01*
X5133Y182167D01*
X5217Y181875D01*
X5425Y181667D01*
X5758Y181542D01*
X6050Y181500D01*
G01X2017Y207000D02*
Y209500D01*
X3058D01*
X3392Y209375D01*
X3600Y209208D01*
X3683Y208875D01*
X3600Y208542D01*
X3350Y208333D01*
X3058Y208208D01*
X2017D01*
G01X3058D02*
X3683Y207000D01*
G01X5950D02*
Y209500D01*
X5450Y209000D01*
G01Y207000D02*
X6450D01*
G01X9550D02*
Y209500D01*
X8008Y207708D01*
X10092D01*
G01X12650Y207000D02*
Y209500D01*
X11108Y207708D01*
X13192D01*
G01X1617Y203000D02*
Y205500D01*
X2658D01*
X2992Y205375D01*
X3200Y205208D01*
X3283Y204875D01*
X3200Y204542D01*
X2950Y204333D01*
X2658Y204208D01*
X1617D01*
G01X2658D02*
X3283Y203000D01*
G01X4842Y203292D02*
X5133Y203083D01*
X5467Y203000D01*
X5800Y203083D01*
X6092Y203333D01*
X6300Y203708D01*
X6383Y204083D01*
Y204542D01*
X6300Y204917D01*
X6092Y205250D01*
X5842Y205417D01*
X5550Y205500D01*
X5217Y205417D01*
X4967Y205250D01*
X4800Y205000D01*
X4717Y204667D01*
X4800Y204375D01*
X5008Y204083D01*
X5258Y203917D01*
X5550Y203875D01*
X5883Y203958D01*
X6133Y204167D01*
X6383Y204542D01*
G01X1617Y199000D02*
Y201500D01*
X2658D01*
X2992Y201375D01*
X3200Y201208D01*
X3283Y200875D01*
X3200Y200542D01*
X2950Y200333D01*
X2658Y200208D01*
X1617D01*
G01X2658D02*
X3283Y199000D01*
G01X5467D02*
X5550Y199542D01*
X5675Y200000D01*
X5842Y200417D01*
X6050Y200875D01*
X6383Y201500D01*
X4717D01*
G01X10000Y90467D02*
X7500D01*
Y91467D01*
X7625Y91800D01*
X7917Y92050D01*
X8250Y92133D01*
X8583Y92050D01*
X8833Y91842D01*
X8958Y91467D01*
Y90467D01*
G01X10000Y93567D02*
X7500D01*
Y94608D01*
X7625Y94942D01*
X7792Y95150D01*
X8125Y95233D01*
X8458Y95150D01*
X8667Y94900D01*
X8792Y94608D01*
Y93567D01*
G01Y94608D02*
X10000Y95233D01*
G01Y97500D02*
X7500D01*
X8000Y97000D01*
G01X10000D02*
Y98000D01*
G01Y100600D02*
X7500D01*
X8000Y100100D01*
G01X10000D02*
Y101100D01*
G01Y104200D02*
X7500D01*
X9292Y102658D01*
Y104742D01*
G01X6000Y90517D02*
X3500D01*
Y91517D01*
X3625Y91850D01*
X3917Y92100D01*
X4250Y92183D01*
X4583Y92100D01*
X4833Y91892D01*
X4958Y91517D01*
Y90517D01*
G01X3708Y95367D02*
X3583Y95117D01*
X3500Y94825D01*
Y94492D01*
X3625Y94117D01*
X3833Y93825D01*
X4083Y93617D01*
X4500Y93450D01*
X4875Y93408D01*
X5250Y93492D01*
X5500Y93617D01*
X5750Y93867D01*
X5917Y94158D01*
X6000Y94450D01*
Y94742D01*
X5917Y95033D01*
X5792Y95283D01*
X5625Y95492D01*
G01X5708Y96842D02*
X5917Y97133D01*
X6000Y97467D01*
X5917Y97800D01*
X5667Y98092D01*
X5292Y98300D01*
X4917Y98383D01*
X4458D01*
X4083Y98300D01*
X3750Y98092D01*
X3583Y97842D01*
X3500Y97550D01*
X3583Y97217D01*
X3750Y96967D01*
X4000Y96800D01*
X4333Y96717D01*
X4625Y96800D01*
X4917Y97008D01*
X5083Y97258D01*
X5125Y97550D01*
X5042Y97883D01*
X4833Y98133D01*
X4458Y98383D01*
G01X6000Y100650D02*
X3500D01*
X4000Y100150D01*
G01X6000D02*
Y101150D01*
G01X15017Y90500D02*
Y93000D01*
X16017D01*
X16350Y92875D01*
X16600Y92583D01*
X16683Y92250D01*
X16600Y91917D01*
X16392Y91667D01*
X16017Y91542D01*
X15017D01*
G01X19867Y92792D02*
X19617Y92917D01*
X19325Y93000D01*
X18992D01*
X18617Y92875D01*
X18325Y92667D01*
X18117Y92417D01*
X17950Y92000D01*
X17908Y91625D01*
X17992Y91250D01*
X18117Y91000D01*
X18367Y90750D01*
X18658Y90583D01*
X18950Y90500D01*
X19242D01*
X19533Y90583D01*
X19783Y90708D01*
X19992Y90875D01*
G01X21342Y90792D02*
X21633Y90583D01*
X21967Y90500D01*
X22300Y90583D01*
X22592Y90833D01*
X22800Y91208D01*
X22883Y91583D01*
Y92042D01*
X22800Y92417D01*
X22592Y92750D01*
X22342Y92917D01*
X22050Y93000D01*
X21717Y92917D01*
X21467Y92750D01*
X21300Y92500D01*
X21217Y92167D01*
X21300Y91875D01*
X21508Y91583D01*
X21758Y91417D01*
X22050Y91375D01*
X22383Y91458D01*
X22633Y91667D01*
X22883Y92042D01*
G01X25150Y93000D02*
X24817Y92917D01*
X24567Y92708D01*
X24400Y92458D01*
X24275Y92125D01*
X24233Y91750D01*
X24275Y91375D01*
X24400Y91042D01*
X24567Y90792D01*
X24817Y90583D01*
X25150Y90500D01*
X25483Y90583D01*
X25733Y90792D01*
X25900Y91042D01*
X26025Y91375D01*
X26067Y91750D01*
X26025Y92125D01*
X25900Y92458D01*
X25733Y92708D01*
X25483Y92917D01*
X25150Y93000D01*
G01X9567Y85500D02*
Y88000D01*
X10567D01*
X10900Y87875D01*
X11150Y87583D01*
X11233Y87250D01*
X11150Y86917D01*
X10942Y86667D01*
X10567Y86542D01*
X9567D01*
G01X12667Y85500D02*
Y88000D01*
X13708D01*
X14042Y87875D01*
X14250Y87708D01*
X14333Y87375D01*
X14250Y87042D01*
X14000Y86833D01*
X13708Y86708D01*
X12667D01*
G01X13708D02*
X14333Y85500D01*
G01X16600D02*
Y88000D01*
X16100Y87500D01*
G01Y85500D02*
X17100D01*
G01X19700D02*
Y88000D01*
X19200Y87500D01*
G01Y85500D02*
X20200D01*
G01X22008Y86542D02*
X22300Y86833D01*
X22550Y87000D01*
X22883Y87083D01*
X23175Y87000D01*
X23383Y86833D01*
X23550Y86583D01*
X23592Y86292D01*
X23550Y86042D01*
X23383Y85792D01*
X23133Y85583D01*
X22842Y85500D01*
X22508Y85583D01*
X22217Y85833D01*
X22050Y86208D01*
X22008Y86625D01*
X22092Y87167D01*
X22217Y87458D01*
X22425Y87750D01*
X22717Y87958D01*
X23008Y88000D01*
X23300Y87917D01*
X23508Y87708D01*
G01X9567Y81500D02*
Y84000D01*
X10567D01*
X10900Y83875D01*
X11150Y83583D01*
X11233Y83250D01*
X11150Y82917D01*
X10942Y82667D01*
X10567Y82542D01*
X9567D01*
G01X12667Y81500D02*
Y84000D01*
X13708D01*
X14042Y83875D01*
X14250Y83708D01*
X14333Y83375D01*
X14250Y83042D01*
X14000Y82833D01*
X13708Y82708D01*
X12667D01*
G01X13708D02*
X14333Y81500D01*
G01X16600D02*
Y84000D01*
X16100Y83500D01*
G01Y81500D02*
X17100D01*
G01X19700D02*
Y84000D01*
X19200Y83500D01*
G01Y81500D02*
X20200D01*
G01X22800D02*
Y84000D01*
X22300Y83500D01*
G01Y81500D02*
X23300D01*
G01X4500Y120967D02*
X2000D01*
Y121967D01*
X2125Y122300D01*
X2417Y122550D01*
X2750Y122633D01*
X3083Y122550D01*
X3333Y122342D01*
X3458Y121967D01*
Y120967D01*
G01X4500Y124067D02*
X2000D01*
Y125108D01*
X2125Y125442D01*
X2292Y125650D01*
X2625Y125733D01*
X2958Y125650D01*
X3167Y125400D01*
X3292Y125108D01*
Y124067D01*
G01Y125108D02*
X4500Y125733D01*
G01X2417Y127208D02*
X2167Y127458D01*
X2042Y127750D01*
X2000Y128083D01*
X2083Y128500D01*
X2292Y128792D01*
X2542Y128875D01*
X2792Y128833D01*
X3000Y128667D01*
X3417Y127833D01*
X3708Y127458D01*
X4125Y127208D01*
X4500Y127125D01*
Y128875D01*
G01X2000Y131100D02*
X2083Y130767D01*
X2292Y130517D01*
X2542Y130350D01*
X2875Y130225D01*
X3250Y130183D01*
X3625Y130225D01*
X3958Y130350D01*
X4208Y130517D01*
X4417Y130767D01*
X4500Y131100D01*
X4417Y131433D01*
X4208Y131683D01*
X3958Y131850D01*
X3625Y131975D01*
X3250Y132017D01*
X2875Y131975D01*
X2542Y131850D01*
X2292Y131683D01*
X2083Y131433D01*
X2000Y131100D01*
G01X4208Y133492D02*
X4417Y133783D01*
X4500Y134117D01*
X4417Y134450D01*
X4167Y134742D01*
X3792Y134950D01*
X3417Y135033D01*
X2958D01*
X2583Y134950D01*
X2250Y134742D01*
X2083Y134492D01*
X2000Y134200D01*
X2083Y133867D01*
X2250Y133617D01*
X2500Y133450D01*
X2833Y133367D01*
X3125Y133450D01*
X3417Y133658D01*
X3583Y133908D01*
X3625Y134200D01*
X3542Y134533D01*
X3333Y134783D01*
X2958Y135033D01*
G01X16500Y107017D02*
X14000D01*
Y108017D01*
X14125Y108350D01*
X14417Y108600D01*
X14750Y108683D01*
X15083Y108600D01*
X15333Y108392D01*
X15458Y108017D01*
Y107017D01*
G01X14208Y111867D02*
X14083Y111617D01*
X14000Y111325D01*
Y110992D01*
X14125Y110617D01*
X14333Y110325D01*
X14583Y110117D01*
X15000Y109950D01*
X15375Y109908D01*
X15750Y109992D01*
X16000Y110117D01*
X16250Y110367D01*
X16417Y110658D01*
X16500Y110950D01*
Y111242D01*
X16417Y111533D01*
X16292Y111783D01*
X16125Y111992D01*
G01X16500Y113967D02*
X15958Y114050D01*
X15500Y114175D01*
X15083Y114342D01*
X14625Y114550D01*
X14000Y114883D01*
Y113217D01*
G01X16500Y117150D02*
X16458Y117442D01*
X16333Y117775D01*
X16125Y117983D01*
X15833Y118067D01*
X15542Y117983D01*
X15292Y117733D01*
X15167Y117358D01*
Y116942D01*
X15083Y116692D01*
X14875Y116483D01*
X14583Y116400D01*
X14292Y116525D01*
X14083Y116817D01*
X14000Y117150D01*
X14083Y117483D01*
X14292Y117775D01*
X14583Y117900D01*
X14875Y117817D01*
X15083Y117608D01*
X15167Y117358D01*
Y116942D01*
X15292Y116567D01*
X15542Y116317D01*
X15833Y116233D01*
X16125Y116317D01*
X16333Y116525D01*
X16458Y116858D01*
X16500Y117150D01*
G01X4500Y107067D02*
X2000D01*
Y108067D01*
X2125Y108400D01*
X2417Y108650D01*
X2750Y108733D01*
X3083Y108650D01*
X3333Y108442D01*
X3458Y108067D01*
Y107067D01*
G01X2000Y110167D02*
X4500D01*
Y111833D01*
G01Y114100D02*
X4458Y114392D01*
X4333Y114725D01*
X4125Y114933D01*
X3833Y115017D01*
X3542Y114933D01*
X3292Y114683D01*
X3167Y114308D01*
Y113892D01*
X3083Y113642D01*
X2875Y113433D01*
X2583Y113350D01*
X2292Y113475D01*
X2083Y113767D01*
X2000Y114100D01*
X2083Y114433D01*
X2292Y114725D01*
X2583Y114850D01*
X2875Y114767D01*
X3083Y114558D01*
X3167Y114308D01*
Y113892D01*
X3292Y113517D01*
X3542Y113267D01*
X3833Y113183D01*
X4125Y113267D01*
X4333Y113475D01*
X4458Y113808D01*
X4500Y114100D01*
G01X8500Y107017D02*
X6000D01*
Y108017D01*
X6125Y108350D01*
X6417Y108600D01*
X6750Y108683D01*
X7083Y108600D01*
X7333Y108392D01*
X7458Y108017D01*
Y107017D01*
G01X6208Y111867D02*
X6083Y111617D01*
X6000Y111325D01*
Y110992D01*
X6125Y110617D01*
X6333Y110325D01*
X6583Y110117D01*
X7000Y109950D01*
X7375Y109908D01*
X7750Y109992D01*
X8000Y110117D01*
X8250Y110367D01*
X8417Y110658D01*
X8500Y110950D01*
Y111242D01*
X8417Y111533D01*
X8292Y111783D01*
X8125Y111992D01*
G01X8208Y113342D02*
X8417Y113633D01*
X8500Y113967D01*
X8417Y114300D01*
X8167Y114592D01*
X7792Y114800D01*
X7417Y114883D01*
X6958D01*
X6583Y114800D01*
X6250Y114592D01*
X6083Y114342D01*
X6000Y114050D01*
X6083Y113717D01*
X6250Y113467D01*
X6500Y113300D01*
X6833Y113217D01*
X7125Y113300D01*
X7417Y113508D01*
X7583Y113758D01*
X7625Y114050D01*
X7542Y114383D01*
X7333Y114633D01*
X6958Y114883D01*
G01X8500Y117650D02*
X6000D01*
X7792Y116108D01*
Y118192D01*
G01X12500Y107017D02*
X10000D01*
Y108017D01*
X10125Y108350D01*
X10417Y108600D01*
X10750Y108683D01*
X11083Y108600D01*
X11333Y108392D01*
X11458Y108017D01*
Y107017D01*
G01X10208Y111867D02*
X10083Y111617D01*
X10000Y111325D01*
Y110992D01*
X10125Y110617D01*
X10333Y110325D01*
X10583Y110117D01*
X11000Y109950D01*
X11375Y109908D01*
X11750Y109992D01*
X12000Y110117D01*
X12250Y110367D01*
X12417Y110658D01*
X12500Y110950D01*
Y111242D01*
X12417Y111533D01*
X12292Y111783D01*
X12125Y111992D01*
G01X12500Y114050D02*
X12458Y114342D01*
X12333Y114675D01*
X12125Y114883D01*
X11833Y114967D01*
X11542Y114883D01*
X11292Y114633D01*
X11167Y114258D01*
Y113842D01*
X11083Y113592D01*
X10875Y113383D01*
X10583Y113300D01*
X10292Y113425D01*
X10083Y113717D01*
X10000Y114050D01*
X10083Y114383D01*
X10292Y114675D01*
X10583Y114800D01*
X10875Y114717D01*
X11083Y114508D01*
X11167Y114258D01*
Y113842D01*
X11292Y113467D01*
X11542Y113217D01*
X11833Y113133D01*
X12125Y113217D01*
X12333Y113425D01*
X12458Y113758D01*
X12500Y114050D01*
G01X12125Y116233D02*
X12333Y116483D01*
X12458Y116775D01*
X12500Y117150D01*
X12417Y117525D01*
X12250Y117817D01*
X11958Y118025D01*
X11625Y118067D01*
X11292Y117983D01*
X11083Y117775D01*
X10917Y117483D01*
X10875Y117192D01*
X10917Y116900D01*
X11083Y116525D01*
X10000Y116650D01*
Y117775D01*
G01X8500Y120967D02*
X6000D01*
Y121967D01*
X6125Y122300D01*
X6417Y122550D01*
X6750Y122633D01*
X7083Y122550D01*
X7333Y122342D01*
X7458Y121967D01*
Y120967D01*
G01X8500Y124067D02*
X6000D01*
Y125108D01*
X6125Y125442D01*
X6292Y125650D01*
X6625Y125733D01*
X6958Y125650D01*
X7167Y125400D01*
X7292Y125108D01*
Y124067D01*
G01Y125108D02*
X8500Y125733D01*
G01X6417Y127208D02*
X6167Y127458D01*
X6042Y127750D01*
X6000Y128083D01*
X6083Y128500D01*
X6292Y128792D01*
X6542Y128875D01*
X6792Y128833D01*
X7000Y128667D01*
X7417Y127833D01*
X7708Y127458D01*
X8125Y127208D01*
X8500Y127125D01*
Y128875D01*
G01X6000Y131100D02*
X6083Y130767D01*
X6292Y130517D01*
X6542Y130350D01*
X6875Y130225D01*
X7250Y130183D01*
X7625Y130225D01*
X7958Y130350D01*
X8208Y130517D01*
X8417Y130767D01*
X8500Y131100D01*
X8417Y131433D01*
X8208Y131683D01*
X7958Y131850D01*
X7625Y131975D01*
X7250Y132017D01*
X6875Y131975D01*
X6542Y131850D01*
X6292Y131683D01*
X6083Y131433D01*
X6000Y131100D01*
G01X8000Y133283D02*
X8292Y133533D01*
X8458Y133867D01*
X8500Y134242D01*
X8458Y134575D01*
X8250Y134908D01*
X8000Y135117D01*
X7750Y135158D01*
X7458Y135075D01*
X7250Y134783D01*
X7167Y134492D01*
Y134117D01*
G01Y134492D02*
X7042Y134742D01*
X6833Y134950D01*
X6583Y135033D01*
X6333Y134950D01*
X6125Y134742D01*
X6000Y134367D01*
X6042Y133992D01*
X6208Y133617D01*
G01X12500Y120967D02*
X10000D01*
Y121967D01*
X10125Y122300D01*
X10417Y122550D01*
X10750Y122633D01*
X11083Y122550D01*
X11333Y122342D01*
X11458Y121967D01*
Y120967D01*
G01X12500Y124067D02*
X10000D01*
Y125108D01*
X10125Y125442D01*
X10292Y125650D01*
X10625Y125733D01*
X10958Y125650D01*
X11167Y125400D01*
X11292Y125108D01*
Y124067D01*
G01Y125108D02*
X12500Y125733D01*
G01X10417Y127208D02*
X10167Y127458D01*
X10042Y127750D01*
X10000Y128083D01*
X10083Y128500D01*
X10292Y128792D01*
X10542Y128875D01*
X10792Y128833D01*
X11000Y128667D01*
X11417Y127833D01*
X11708Y127458D01*
X12125Y127208D01*
X12500Y127125D01*
Y128875D01*
G01X10000Y131100D02*
X10083Y130767D01*
X10292Y130517D01*
X10542Y130350D01*
X10875Y130225D01*
X11250Y130183D01*
X11625Y130225D01*
X11958Y130350D01*
X12208Y130517D01*
X12417Y130767D01*
X12500Y131100D01*
X12417Y131433D01*
X12208Y131683D01*
X11958Y131850D01*
X11625Y131975D01*
X11250Y132017D01*
X10875Y131975D01*
X10542Y131850D01*
X10292Y131683D01*
X10083Y131433D01*
X10000Y131100D01*
G01X10417Y133408D02*
X10167Y133658D01*
X10042Y133950D01*
X10000Y134283D01*
X10083Y134700D01*
X10292Y134992D01*
X10542Y135075D01*
X10792Y135033D01*
X11000Y134867D01*
X11417Y134033D01*
X11708Y133658D01*
X12125Y133408D01*
X12500Y133325D01*
Y135075D01*
G01X16500Y120967D02*
X14000D01*
Y121967D01*
X14125Y122300D01*
X14417Y122550D01*
X14750Y122633D01*
X15083Y122550D01*
X15333Y122342D01*
X15458Y121967D01*
Y120967D01*
G01X16500Y124067D02*
X14000D01*
Y125108D01*
X14125Y125442D01*
X14292Y125650D01*
X14625Y125733D01*
X14958Y125650D01*
X15167Y125400D01*
X15292Y125108D01*
Y124067D01*
G01Y125108D02*
X16500Y125733D01*
G01X14417Y127208D02*
X14167Y127458D01*
X14042Y127750D01*
X14000Y128083D01*
X14083Y128500D01*
X14292Y128792D01*
X14542Y128875D01*
X14792Y128833D01*
X15000Y128667D01*
X15417Y127833D01*
X15708Y127458D01*
X16125Y127208D01*
X16500Y127125D01*
Y128875D01*
G01X14000Y131100D02*
X14083Y130767D01*
X14292Y130517D01*
X14542Y130350D01*
X14875Y130225D01*
X15250Y130183D01*
X15625Y130225D01*
X15958Y130350D01*
X16208Y130517D01*
X16417Y130767D01*
X16500Y131100D01*
X16417Y131433D01*
X16208Y131683D01*
X15958Y131850D01*
X15625Y131975D01*
X15250Y132017D01*
X14875Y131975D01*
X14542Y131850D01*
X14292Y131683D01*
X14083Y131433D01*
X14000Y131100D01*
G01X16500Y134200D02*
X14000D01*
X14500Y133700D01*
G01X16500D02*
Y134700D01*
G01X12567Y156233D02*
X13100Y156583D01*
X13500Y157167D01*
X13767Y157983D01*
X13500Y158683D01*
X12967Y159150D01*
X12033Y159500D01*
X8433D01*
Y152500D01*
X12833D01*
X13767Y152967D01*
X14300Y153667D01*
X14567Y154483D01*
X14300Y155300D01*
X13500Y156000D01*
X12567Y156233D01*
X8433D01*
G01X40500Y130000D02*
Y119500D01*
X42500D01*
Y115000D01*
X47500D01*
G01X3467Y163000D02*
Y165500D01*
X4467D01*
X4800Y165375D01*
X5050Y165083D01*
X5133Y164750D01*
X5050Y164417D01*
X4842Y164167D01*
X4467Y164042D01*
X3467D01*
G01X8317Y165292D02*
X8067Y165417D01*
X7775Y165500D01*
X7442D01*
X7067Y165375D01*
X6775Y165167D01*
X6567Y164917D01*
X6400Y164500D01*
X6358Y164125D01*
X6442Y163750D01*
X6567Y163500D01*
X6817Y163250D01*
X7108Y163083D01*
X7400Y163000D01*
X7692D01*
X7983Y163083D01*
X8233Y163208D01*
X8442Y163375D01*
G01X10500Y163000D02*
Y165500D01*
X10000Y165000D01*
G01Y163000D02*
X11000D01*
G01X13600D02*
X13892Y163042D01*
X14225Y163167D01*
X14433Y163375D01*
X14517Y163667D01*
X14433Y163958D01*
X14183Y164208D01*
X13808Y164333D01*
X13392D01*
X13142Y164417D01*
X12933Y164625D01*
X12850Y164917D01*
X12975Y165208D01*
X13267Y165417D01*
X13600Y165500D01*
X13933Y165417D01*
X14225Y165208D01*
X14350Y164917D01*
X14267Y164625D01*
X14058Y164417D01*
X13808Y164333D01*
X13392D01*
X13017Y164208D01*
X12767Y163958D01*
X12683Y163667D01*
X12767Y163375D01*
X12975Y163167D01*
X13308Y163042D01*
X13600Y163000D01*
G01X17200D02*
Y165500D01*
X15658Y163708D01*
X17742D01*
G01X10617Y168000D02*
Y170500D01*
X11658D01*
X11992Y170375D01*
X12200Y170208D01*
X12283Y169875D01*
X12200Y169542D01*
X11950Y169333D01*
X11658Y169208D01*
X10617D01*
G01X11658D02*
X12283Y168000D01*
G01X13633Y168500D02*
X13883Y168208D01*
X14217Y168042D01*
X14592Y168000D01*
X14925Y168042D01*
X15258Y168250D01*
X15467Y168500D01*
X15508Y168750D01*
X15425Y169042D01*
X15133Y169250D01*
X14842Y169333D01*
X14467D01*
G01X14842D02*
X15092Y169458D01*
X15300Y169667D01*
X15383Y169917D01*
X15300Y170167D01*
X15092Y170375D01*
X14717Y170500D01*
X14342Y170458D01*
X13967Y170292D01*
G01X8937Y179033D02*
X10729D01*
X11104Y179200D01*
X11354Y179533D01*
X11437Y179950D01*
X11354Y180367D01*
X11104Y180700D01*
X10729Y180867D01*
X8937D01*
G01X11437Y183050D02*
X8937D01*
X9437Y182550D01*
G01X11437D02*
Y183550D01*
G01X16000Y172567D02*
X13500D01*
Y173608D01*
X13625Y173942D01*
X13792Y174150D01*
X14125Y174233D01*
X14458Y174150D01*
X14667Y173900D01*
X14792Y173608D01*
Y172567D01*
G01Y173608D02*
X16000Y174233D01*
G01Y176500D02*
X13500D01*
X14000Y176000D01*
G01X16000D02*
Y177000D01*
G01Y179600D02*
X13500D01*
X14000Y179100D01*
G01X16000D02*
Y180100D01*
G01Y182067D02*
X13500D01*
Y183108D01*
X13625Y183442D01*
X13792Y183650D01*
X14125Y183733D01*
X14458Y183650D01*
X14667Y183400D01*
X14792Y183108D01*
Y182067D01*
G01Y183108D02*
X16000Y183733D01*
G01Y186000D02*
X13500D01*
X14000Y185500D01*
G01X16000D02*
Y186500D01*
G01X13917Y188308D02*
X13667Y188558D01*
X13542Y188850D01*
X13500Y189183D01*
X13583Y189600D01*
X13792Y189892D01*
X14042Y189975D01*
X14292Y189933D01*
X14500Y189767D01*
X14917Y188933D01*
X15208Y188558D01*
X15625Y188308D01*
X16000Y188225D01*
Y189975D01*
G01X4708Y194867D02*
X4583Y194617D01*
X4500Y194325D01*
Y193992D01*
X4625Y193617D01*
X4833Y193325D01*
X5083Y193117D01*
X5500Y192950D01*
X5875Y192908D01*
X6250Y192992D01*
X6500Y193117D01*
X6750Y193367D01*
X6917Y193658D01*
X7000Y193950D01*
Y194242D01*
X6917Y194533D01*
X6792Y194783D01*
X6625Y194992D01*
G01X7000Y197550D02*
X4500D01*
X6292Y196008D01*
Y198092D01*
G01X15000Y193117D02*
X12500D01*
Y194158D01*
X12625Y194492D01*
X12792Y194700D01*
X13125Y194783D01*
X13458Y194700D01*
X13667Y194450D01*
X13792Y194158D01*
Y193117D01*
G01Y194158D02*
X15000Y194783D01*
G01X13958Y196258D02*
X13667Y196550D01*
X13500Y196800D01*
X13417Y197133D01*
X13500Y197425D01*
X13667Y197633D01*
X13917Y197800D01*
X14208Y197842D01*
X14458Y197800D01*
X14708Y197633D01*
X14917Y197383D01*
X15000Y197092D01*
X14917Y196758D01*
X14667Y196467D01*
X14292Y196300D01*
X13875Y196258D01*
X13333Y196342D01*
X13042Y196467D01*
X12750Y196675D01*
X12542Y196967D01*
X12500Y197258D01*
X12583Y197550D01*
X12792Y197758D01*
G01X11000Y193117D02*
X8500D01*
Y194158D01*
X8625Y194492D01*
X8792Y194700D01*
X9125Y194783D01*
X9458Y194700D01*
X9667Y194450D01*
X9792Y194158D01*
Y193117D01*
G01Y194158D02*
X11000Y194783D01*
G01X10625Y196133D02*
X10833Y196383D01*
X10958Y196675D01*
X11000Y197050D01*
X10917Y197425D01*
X10750Y197717D01*
X10458Y197925D01*
X10125Y197967D01*
X9792Y197883D01*
X9583Y197675D01*
X9417Y197383D01*
X9375Y197092D01*
X9417Y196800D01*
X9583Y196425D01*
X8500Y196550D01*
Y197675D01*
G01X9817Y205292D02*
X9567Y205417D01*
X9275Y205500D01*
X8942D01*
X8567Y205375D01*
X8275Y205167D01*
X8067Y204917D01*
X7900Y204500D01*
X7858Y204125D01*
X7942Y203750D01*
X8067Y203500D01*
X8317Y203250D01*
X8608Y203083D01*
X8900Y203000D01*
X9192D01*
X9483Y203083D01*
X9733Y203208D01*
X9942Y203375D01*
G01X11083D02*
X11333Y203167D01*
X11625Y203042D01*
X12000Y203000D01*
X12375Y203083D01*
X12667Y203250D01*
X12875Y203542D01*
X12917Y203875D01*
X12833Y204208D01*
X12625Y204417D01*
X12333Y204583D01*
X12042Y204625D01*
X11750Y204583D01*
X11375Y204417D01*
X11500Y205500D01*
X12625D01*
G01X14308Y204042D02*
X14600Y204333D01*
X14850Y204500D01*
X15183Y204583D01*
X15475Y204500D01*
X15683Y204333D01*
X15850Y204083D01*
X15892Y203792D01*
X15850Y203542D01*
X15683Y203292D01*
X15433Y203083D01*
X15142Y203000D01*
X14808Y203083D01*
X14517Y203333D01*
X14350Y203708D01*
X14308Y204125D01*
X14392Y204667D01*
X14517Y204958D01*
X14725Y205250D01*
X15017Y205458D01*
X15308Y205500D01*
X15600Y205417D01*
X15808Y205208D01*
G01X9817Y201792D02*
X9567Y201917D01*
X9275Y202000D01*
X8942D01*
X8567Y201875D01*
X8275Y201667D01*
X8067Y201417D01*
X7900Y201000D01*
X7858Y200625D01*
X7942Y200250D01*
X8067Y200000D01*
X8317Y199750D01*
X8608Y199583D01*
X8900Y199500D01*
X9192D01*
X9483Y199583D01*
X9733Y199708D01*
X9942Y199875D01*
G01X11083D02*
X11333Y199667D01*
X11625Y199542D01*
X12000Y199500D01*
X12375Y199583D01*
X12667Y199750D01*
X12875Y200042D01*
X12917Y200375D01*
X12833Y200708D01*
X12625Y200917D01*
X12333Y201083D01*
X12042Y201125D01*
X11750Y201083D01*
X11375Y200917D01*
X11500Y202000D01*
X12625D01*
G01X15100Y199500D02*
X15392Y199542D01*
X15725Y199667D01*
X15933Y199875D01*
X16017Y200167D01*
X15933Y200458D01*
X15683Y200708D01*
X15308Y200833D01*
X14892D01*
X14642Y200917D01*
X14433Y201125D01*
X14350Y201417D01*
X14475Y201708D01*
X14767Y201917D01*
X15100Y202000D01*
X15433Y201917D01*
X15725Y201708D01*
X15850Y201417D01*
X15767Y201125D01*
X15558Y200917D01*
X15308Y200833D01*
X14892D01*
X14517Y200708D01*
X14267Y200458D01*
X14183Y200167D01*
X14267Y199875D01*
X14475Y199667D01*
X14808Y199542D01*
X15100Y199500D01*
G01X17517Y214000D02*
Y216500D01*
X18517D01*
X18850Y216375D01*
X19100Y216083D01*
X19183Y215750D01*
X19100Y215417D01*
X18892Y215167D01*
X18517Y215042D01*
X17517D01*
G01X22367Y216292D02*
X22117Y216417D01*
X21825Y216500D01*
X21492D01*
X21117Y216375D01*
X20825Y216167D01*
X20617Y215917D01*
X20450Y215500D01*
X20408Y215125D01*
X20492Y214750D01*
X20617Y214500D01*
X20867Y214250D01*
X21158Y214083D01*
X21450Y214000D01*
X21742D01*
X22033Y214083D01*
X22283Y214208D01*
X22492Y214375D01*
G01X25050Y214000D02*
Y216500D01*
X23508Y214708D01*
X25592D01*
G01X27650Y214000D02*
X27942Y214042D01*
X28275Y214167D01*
X28483Y214375D01*
X28567Y214667D01*
X28483Y214958D01*
X28233Y215208D01*
X27858Y215333D01*
X27442D01*
X27192Y215417D01*
X26983Y215625D01*
X26900Y215917D01*
X27025Y216208D01*
X27317Y216417D01*
X27650Y216500D01*
X27983Y216417D01*
X28275Y216208D01*
X28400Y215917D01*
X28317Y215625D01*
X28108Y215417D01*
X27858Y215333D01*
X27442D01*
X27067Y215208D01*
X26817Y214958D01*
X26733Y214667D01*
X26817Y214375D01*
X27025Y214167D01*
X27358Y214042D01*
X27650Y214000D01*
G01X17667Y226192D02*
X17417Y226317D01*
X17125Y226400D01*
X16792D01*
X16417Y226275D01*
X16125Y226067D01*
X15917Y225817D01*
X15750Y225400D01*
X15708Y225025D01*
X15792Y224650D01*
X15917Y224400D01*
X16167Y224150D01*
X16458Y223983D01*
X16750Y223900D01*
X17042D01*
X17333Y223983D01*
X17583Y224108D01*
X17792Y224275D01*
G01X20350Y223900D02*
Y226400D01*
X18808Y224608D01*
X20892D01*
G01X22867Y223900D02*
X22950Y224442D01*
X23075Y224900D01*
X23242Y225317D01*
X23450Y225775D01*
X23783Y226400D01*
X22117D01*
G01X17667Y222192D02*
X17417Y222317D01*
X17125Y222400D01*
X16792D01*
X16417Y222275D01*
X16125Y222067D01*
X15917Y221817D01*
X15750Y221400D01*
X15708Y221025D01*
X15792Y220650D01*
X15917Y220400D01*
X16167Y220150D01*
X16458Y219983D01*
X16750Y219900D01*
X17042D01*
X17333Y219983D01*
X17583Y220108D01*
X17792Y220275D01*
G01X18933D02*
X19183Y220067D01*
X19475Y219942D01*
X19850Y219900D01*
X20225Y219983D01*
X20517Y220150D01*
X20725Y220442D01*
X20767Y220775D01*
X20683Y221108D01*
X20475Y221317D01*
X20183Y221483D01*
X19892Y221525D01*
X19600Y221483D01*
X19225Y221317D01*
X19350Y222400D01*
X20475D01*
G01X22950D02*
X22617Y222317D01*
X22367Y222108D01*
X22200Y221858D01*
X22075Y221525D01*
X22033Y221150D01*
X22075Y220775D01*
X22200Y220442D01*
X22367Y220192D01*
X22617Y219983D01*
X22950Y219900D01*
X23283Y219983D01*
X23533Y220192D01*
X23700Y220442D01*
X23825Y220775D01*
X23867Y221150D01*
X23825Y221525D01*
X23700Y221858D01*
X23533Y222108D01*
X23283Y222317D01*
X22950Y222400D01*
G01X17667Y230192D02*
X17417Y230317D01*
X17125Y230400D01*
X16792D01*
X16417Y230275D01*
X16125Y230067D01*
X15917Y229817D01*
X15750Y229400D01*
X15708Y229025D01*
X15792Y228650D01*
X15917Y228400D01*
X16167Y228150D01*
X16458Y227983D01*
X16750Y227900D01*
X17042D01*
X17333Y227983D01*
X17583Y228108D01*
X17792Y228275D01*
G01X20350Y227900D02*
Y230400D01*
X18808Y228608D01*
X20892D01*
G01X23450Y227900D02*
Y230400D01*
X21908Y228608D01*
X23992D01*
G01X17667Y242192D02*
X17417Y242317D01*
X17125Y242400D01*
X16792D01*
X16417Y242275D01*
X16125Y242067D01*
X15917Y241817D01*
X15750Y241400D01*
X15708Y241025D01*
X15792Y240650D01*
X15917Y240400D01*
X16167Y240150D01*
X16458Y239983D01*
X16750Y239900D01*
X17042D01*
X17333Y239983D01*
X17583Y240108D01*
X17792Y240275D01*
G01X18933Y240400D02*
X19183Y240108D01*
X19517Y239942D01*
X19892Y239900D01*
X20225Y239942D01*
X20558Y240150D01*
X20767Y240400D01*
X20808Y240650D01*
X20725Y240942D01*
X20433Y241150D01*
X20142Y241233D01*
X19767D01*
G01X20142D02*
X20392Y241358D01*
X20600Y241567D01*
X20683Y241817D01*
X20600Y242067D01*
X20392Y242275D01*
X20017Y242400D01*
X19642Y242358D01*
X19267Y242192D01*
G01X22867Y239900D02*
X22950Y240442D01*
X23075Y240900D01*
X23242Y241317D01*
X23450Y241775D01*
X23783Y242400D01*
X22117D01*
G01X17667Y238192D02*
X17417Y238317D01*
X17125Y238400D01*
X16792D01*
X16417Y238275D01*
X16125Y238067D01*
X15917Y237817D01*
X15750Y237400D01*
X15708Y237025D01*
X15792Y236650D01*
X15917Y236400D01*
X16167Y236150D01*
X16458Y235983D01*
X16750Y235900D01*
X17042D01*
X17333Y235983D01*
X17583Y236108D01*
X17792Y236275D01*
G01X20350Y235900D02*
Y238400D01*
X18808Y236608D01*
X20892D01*
G01X22950Y238400D02*
X22617Y238317D01*
X22367Y238108D01*
X22200Y237858D01*
X22075Y237525D01*
X22033Y237150D01*
X22075Y236775D01*
X22200Y236442D01*
X22367Y236192D01*
X22617Y235983D01*
X22950Y235900D01*
X23283Y235983D01*
X23533Y236192D01*
X23700Y236442D01*
X23825Y236775D01*
X23867Y237150D01*
X23825Y237525D01*
X23700Y237858D01*
X23533Y238108D01*
X23283Y238317D01*
X22950Y238400D01*
G01X17667Y246192D02*
X17417Y246317D01*
X17125Y246400D01*
X16792D01*
X16417Y246275D01*
X16125Y246067D01*
X15917Y245817D01*
X15750Y245400D01*
X15708Y245025D01*
X15792Y244650D01*
X15917Y244400D01*
X16167Y244150D01*
X16458Y243983D01*
X16750Y243900D01*
X17042D01*
X17333Y243983D01*
X17583Y244108D01*
X17792Y244275D01*
G01X18933Y244400D02*
X19183Y244108D01*
X19517Y243942D01*
X19892Y243900D01*
X20225Y243942D01*
X20558Y244150D01*
X20767Y244400D01*
X20808Y244650D01*
X20725Y244942D01*
X20433Y245150D01*
X20142Y245233D01*
X19767D01*
G01X20142D02*
X20392Y245358D01*
X20600Y245567D01*
X20683Y245817D01*
X20600Y246067D01*
X20392Y246275D01*
X20017Y246400D01*
X19642Y246358D01*
X19267Y246192D01*
G01X23450Y243900D02*
Y246400D01*
X21908Y244608D01*
X23992D01*
G01X17667Y234192D02*
X17417Y234317D01*
X17125Y234400D01*
X16792D01*
X16417Y234275D01*
X16125Y234067D01*
X15917Y233817D01*
X15750Y233400D01*
X15708Y233025D01*
X15792Y232650D01*
X15917Y232400D01*
X16167Y232150D01*
X16458Y231983D01*
X16750Y231900D01*
X17042D01*
X17333Y231983D01*
X17583Y232108D01*
X17792Y232275D01*
G01X20350Y231900D02*
Y234400D01*
X18808Y232608D01*
X20892D01*
G01X22158Y233983D02*
X22408Y234233D01*
X22700Y234358D01*
X23033Y234400D01*
X23450Y234317D01*
X23742Y234108D01*
X23825Y233858D01*
X23783Y233608D01*
X23617Y233400D01*
X22783Y232983D01*
X22408Y232692D01*
X22158Y232275D01*
X22075Y231900D01*
X23825D01*
G01X14667Y258192D02*
X14417Y258317D01*
X14125Y258400D01*
X13792D01*
X13417Y258275D01*
X13125Y258067D01*
X12917Y257817D01*
X12750Y257400D01*
X12708Y257025D01*
X12792Y256650D01*
X12917Y256400D01*
X13167Y256150D01*
X13458Y255983D01*
X13750Y255900D01*
X14042D01*
X14333Y255983D01*
X14583Y256108D01*
X14792Y256275D01*
G01X16850Y255900D02*
Y258400D01*
X16350Y257900D01*
G01Y255900D02*
X17350D01*
G01X19950D02*
X20242Y255942D01*
X20575Y256067D01*
X20783Y256275D01*
X20867Y256567D01*
X20783Y256858D01*
X20533Y257108D01*
X20158Y257233D01*
X19742D01*
X19492Y257317D01*
X19283Y257525D01*
X19200Y257817D01*
X19325Y258108D01*
X19617Y258317D01*
X19950Y258400D01*
X20283Y258317D01*
X20575Y258108D01*
X20700Y257817D01*
X20617Y257525D01*
X20408Y257317D01*
X20158Y257233D01*
X19742D01*
X19367Y257108D01*
X19117Y256858D01*
X19033Y256567D01*
X19117Y256275D01*
X19325Y256067D01*
X19658Y255942D01*
X19950Y255900D01*
G01X22342Y256192D02*
X22633Y255983D01*
X22967Y255900D01*
X23300Y255983D01*
X23592Y256233D01*
X23800Y256608D01*
X23883Y256983D01*
Y257442D01*
X23800Y257817D01*
X23592Y258150D01*
X23342Y258317D01*
X23050Y258400D01*
X22717Y258317D01*
X22467Y258150D01*
X22300Y257900D01*
X22217Y257567D01*
X22300Y257275D01*
X22508Y256983D01*
X22758Y256817D01*
X23050Y256775D01*
X23383Y256858D01*
X23633Y257067D01*
X23883Y257442D01*
G01X14667Y254192D02*
X14417Y254317D01*
X14125Y254400D01*
X13792D01*
X13417Y254275D01*
X13125Y254067D01*
X12917Y253817D01*
X12750Y253400D01*
X12708Y253025D01*
X12792Y252650D01*
X12917Y252400D01*
X13167Y252150D01*
X13458Y251983D01*
X13750Y251900D01*
X14042D01*
X14333Y251983D01*
X14583Y252108D01*
X14792Y252275D01*
G01X16850Y251900D02*
Y254400D01*
X16350Y253900D01*
G01Y251900D02*
X17350D01*
G01X19242Y252192D02*
X19533Y251983D01*
X19867Y251900D01*
X20200Y251983D01*
X20492Y252233D01*
X20700Y252608D01*
X20783Y252983D01*
Y253442D01*
X20700Y253817D01*
X20492Y254150D01*
X20242Y254317D01*
X19950Y254400D01*
X19617Y254317D01*
X19367Y254150D01*
X19200Y253900D01*
X19117Y253567D01*
X19200Y253275D01*
X19408Y252983D01*
X19658Y252817D01*
X19950Y252775D01*
X20283Y252858D01*
X20533Y253067D01*
X20783Y253442D01*
G01X22258Y252942D02*
X22550Y253233D01*
X22800Y253400D01*
X23133Y253483D01*
X23425Y253400D01*
X23633Y253233D01*
X23800Y252983D01*
X23842Y252692D01*
X23800Y252442D01*
X23633Y252192D01*
X23383Y251983D01*
X23092Y251900D01*
X22758Y251983D01*
X22467Y252233D01*
X22300Y252608D01*
X22258Y253025D01*
X22342Y253567D01*
X22467Y253858D01*
X22675Y254150D01*
X22967Y254358D01*
X23258Y254400D01*
X23550Y254317D01*
X23758Y254108D01*
G01X14667Y262192D02*
X14417Y262317D01*
X14125Y262400D01*
X13792D01*
X13417Y262275D01*
X13125Y262067D01*
X12917Y261817D01*
X12750Y261400D01*
X12708Y261025D01*
X12792Y260650D01*
X12917Y260400D01*
X13167Y260150D01*
X13458Y259983D01*
X13750Y259900D01*
X14042D01*
X14333Y259983D01*
X14583Y260108D01*
X14792Y260275D01*
G01X16850Y259900D02*
Y262400D01*
X16350Y261900D01*
G01Y259900D02*
X17350D01*
G01X19950D02*
X20242Y259942D01*
X20575Y260067D01*
X20783Y260275D01*
X20867Y260567D01*
X20783Y260858D01*
X20533Y261108D01*
X20158Y261233D01*
X19742D01*
X19492Y261317D01*
X19283Y261525D01*
X19200Y261817D01*
X19325Y262108D01*
X19617Y262317D01*
X19950Y262400D01*
X20283Y262317D01*
X20575Y262108D01*
X20700Y261817D01*
X20617Y261525D01*
X20408Y261317D01*
X20158Y261233D01*
X19742D01*
X19367Y261108D01*
X19117Y260858D01*
X19033Y260567D01*
X19117Y260275D01*
X19325Y260067D01*
X19658Y259942D01*
X19950Y259900D01*
G01X23550D02*
Y262400D01*
X22008Y260608D01*
X24092D01*
G01X17667Y250192D02*
X17417Y250317D01*
X17125Y250400D01*
X16792D01*
X16417Y250275D01*
X16125Y250067D01*
X15917Y249817D01*
X15750Y249400D01*
X15708Y249025D01*
X15792Y248650D01*
X15917Y248400D01*
X16167Y248150D01*
X16458Y247983D01*
X16750Y247900D01*
X17042D01*
X17333Y247983D01*
X17583Y248108D01*
X17792Y248275D01*
G01X18933Y248400D02*
X19183Y248108D01*
X19517Y247942D01*
X19892Y247900D01*
X20225Y247942D01*
X20558Y248150D01*
X20767Y248400D01*
X20808Y248650D01*
X20725Y248942D01*
X20433Y249150D01*
X20142Y249233D01*
X19767D01*
G01X20142D02*
X20392Y249358D01*
X20600Y249567D01*
X20683Y249817D01*
X20600Y250067D01*
X20392Y250275D01*
X20017Y250400D01*
X19642Y250358D01*
X19267Y250192D01*
G01X22158Y249983D02*
X22408Y250233D01*
X22700Y250358D01*
X23033Y250400D01*
X23450Y250317D01*
X23742Y250108D01*
X23825Y249858D01*
X23783Y249608D01*
X23617Y249400D01*
X22783Y248983D01*
X22408Y248692D01*
X22158Y248275D01*
X22075Y247900D01*
X23825D01*
G01X14667Y266192D02*
X14417Y266317D01*
X14125Y266400D01*
X13792D01*
X13417Y266275D01*
X13125Y266067D01*
X12917Y265817D01*
X12750Y265400D01*
X12708Y265025D01*
X12792Y264650D01*
X12917Y264400D01*
X13167Y264150D01*
X13458Y263983D01*
X13750Y263900D01*
X14042D01*
X14333Y263983D01*
X14583Y264108D01*
X14792Y264275D01*
G01X16850Y263900D02*
Y266400D01*
X16350Y265900D01*
G01Y263900D02*
X17350D01*
G01X19950D02*
X20242Y263942D01*
X20575Y264067D01*
X20783Y264275D01*
X20867Y264567D01*
X20783Y264858D01*
X20533Y265108D01*
X20158Y265233D01*
X19742D01*
X19492Y265317D01*
X19283Y265525D01*
X19200Y265817D01*
X19325Y266108D01*
X19617Y266317D01*
X19950Y266400D01*
X20283Y266317D01*
X20575Y266108D01*
X20700Y265817D01*
X20617Y265525D01*
X20408Y265317D01*
X20158Y265233D01*
X19742D01*
X19367Y265108D01*
X19117Y264858D01*
X19033Y264567D01*
X19117Y264275D01*
X19325Y264067D01*
X19658Y263942D01*
X19950Y263900D01*
G01X23050D02*
Y266400D01*
X22550Y265900D01*
G01Y263900D02*
X23550D01*
G01X17071Y584373D02*
Y576573D01*
X4471D01*
Y584373D01*
X17071D01*
G01X13571Y577973D02*
X14171Y578073D01*
X14671Y578573D01*
X15071Y579073D01*
X15271Y579673D01*
X15371Y580473D01*
X15271Y581173D01*
X15071Y581873D01*
X14671Y582373D01*
X14171Y582773D01*
X13571Y582973D01*
X12871Y582773D01*
X12371Y582373D01*
X12071Y581873D01*
X11771Y581173D01*
X11671Y580473D01*
X11771Y579673D01*
X12071Y579073D01*
X12371Y578573D01*
X12871Y578073D01*
X13571Y577973D01*
G01X9571Y578773D02*
X9071Y578273D01*
X8471Y578073D01*
X7771Y577973D01*
X6971Y578073D01*
X6371Y578573D01*
X6171Y579073D01*
X6271Y579573D01*
X6571Y579973D01*
X8271Y580773D01*
X9071Y581373D01*
X9571Y582173D01*
X9671Y582973D01*
X6171D01*
G01X24967Y119500D02*
Y122000D01*
X25967D01*
X26300Y121875D01*
X26550Y121583D01*
X26633Y121250D01*
X26550Y120917D01*
X26342Y120667D01*
X25967Y120542D01*
X24967D01*
G01X28067Y119500D02*
Y122000D01*
X29108D01*
X29442Y121875D01*
X29650Y121708D01*
X29733Y121375D01*
X29650Y121042D01*
X29400Y120833D01*
X29108Y120708D01*
X28067D01*
G01X29108D02*
X29733Y119500D01*
G01X31208Y121583D02*
X31458Y121833D01*
X31750Y121958D01*
X32083Y122000D01*
X32500Y121917D01*
X32792Y121708D01*
X32875Y121458D01*
X32833Y121208D01*
X32667Y121000D01*
X31833Y120583D01*
X31458Y120292D01*
X31208Y119875D01*
X31125Y119500D01*
X32875D01*
G01X35100Y122000D02*
X34767Y121917D01*
X34517Y121708D01*
X34350Y121458D01*
X34225Y121125D01*
X34183Y120750D01*
X34225Y120375D01*
X34350Y120042D01*
X34517Y119792D01*
X34767Y119583D01*
X35100Y119500D01*
X35433Y119583D01*
X35683Y119792D01*
X35850Y120042D01*
X35975Y120375D01*
X36017Y120750D01*
X35975Y121125D01*
X35850Y121458D01*
X35683Y121708D01*
X35433Y121917D01*
X35100Y122000D01*
G01X37408Y120542D02*
X37700Y120833D01*
X37950Y121000D01*
X38283Y121083D01*
X38575Y121000D01*
X38783Y120833D01*
X38950Y120583D01*
X38992Y120292D01*
X38950Y120042D01*
X38783Y119792D01*
X38533Y119583D01*
X38242Y119500D01*
X37908Y119583D01*
X37617Y119833D01*
X37450Y120208D01*
X37408Y120625D01*
X37492Y121167D01*
X37617Y121458D01*
X37825Y121750D01*
X38117Y121958D01*
X38408Y122000D01*
X38700Y121917D01*
X38908Y121708D01*
G01X23050Y158350D02*
X21950D01*
G01X23050Y154050D02*
Y158350D01*
G01X21950Y154050D02*
X23050D01*
G01X21950Y158350D02*
Y154050D01*
G01X22500D02*
Y158350D01*
G01X21929Y182992D02*
X20229Y181292D01*
G01X31129Y178992D02*
Y186992D01*
G01X20229Y178992D02*
X31129D01*
G01X20229Y186992D02*
Y178992D01*
G01X32317Y198792D02*
X32067Y198917D01*
X31775Y199000D01*
X31442D01*
X31067Y198875D01*
X30775Y198667D01*
X30567Y198417D01*
X30400Y198000D01*
X30358Y197625D01*
X30442Y197250D01*
X30567Y197000D01*
X30817Y196750D01*
X31108Y196583D01*
X31400Y196500D01*
X31692D01*
X31983Y196583D01*
X32233Y196708D01*
X32442Y196875D01*
G01X33708Y197542D02*
X34000Y197833D01*
X34250Y198000D01*
X34583Y198083D01*
X34875Y198000D01*
X35083Y197833D01*
X35250Y197583D01*
X35292Y197292D01*
X35250Y197042D01*
X35083Y196792D01*
X34833Y196583D01*
X34542Y196500D01*
X34208Y196583D01*
X33917Y196833D01*
X33750Y197208D01*
X33708Y197625D01*
X33792Y198167D01*
X33917Y198458D01*
X34125Y198750D01*
X34417Y198958D01*
X34708Y199000D01*
X35000Y198917D01*
X35208Y198708D01*
G01X38100Y196500D02*
Y199000D01*
X36558Y197208D01*
X38642D01*
G01X20229Y184692D02*
X21929Y182992D01*
G01X31129Y186992D02*
X20229D01*
G01X32317Y202792D02*
X32067Y202917D01*
X31775Y203000D01*
X31442D01*
X31067Y202875D01*
X30775Y202667D01*
X30567Y202417D01*
X30400Y202000D01*
X30358Y201625D01*
X30442Y201250D01*
X30567Y201000D01*
X30817Y200750D01*
X31108Y200583D01*
X31400Y200500D01*
X31692D01*
X31983Y200583D01*
X32233Y200708D01*
X32442Y200875D01*
G01X33708Y201542D02*
X34000Y201833D01*
X34250Y202000D01*
X34583Y202083D01*
X34875Y202000D01*
X35083Y201833D01*
X35250Y201583D01*
X35292Y201292D01*
X35250Y201042D01*
X35083Y200792D01*
X34833Y200583D01*
X34542Y200500D01*
X34208Y200583D01*
X33917Y200833D01*
X33750Y201208D01*
X33708Y201625D01*
X33792Y202167D01*
X33917Y202458D01*
X34125Y202750D01*
X34417Y202958D01*
X34708Y203000D01*
X35000Y202917D01*
X35208Y202708D01*
G01X37600Y203000D02*
X37267Y202917D01*
X37017Y202708D01*
X36850Y202458D01*
X36725Y202125D01*
X36683Y201750D01*
X36725Y201375D01*
X36850Y201042D01*
X37017Y200792D01*
X37267Y200583D01*
X37600Y200500D01*
X37933Y200583D01*
X38183Y200792D01*
X38350Y201042D01*
X38475Y201375D01*
X38517Y201750D01*
X38475Y202125D01*
X38350Y202458D01*
X38183Y202708D01*
X37933Y202917D01*
X37600Y203000D01*
G01X34617Y211992D02*
X34367Y212117D01*
X34075Y212200D01*
X33742D01*
X33367Y212075D01*
X33075Y211867D01*
X32867Y211617D01*
X32700Y211200D01*
X32658Y210825D01*
X32742Y210450D01*
X32867Y210200D01*
X33117Y209950D01*
X33408Y209783D01*
X33700Y209700D01*
X33992D01*
X34283Y209783D01*
X34533Y209908D01*
X34742Y210075D01*
G01X35883D02*
X36133Y209867D01*
X36425Y209742D01*
X36800Y209700D01*
X37175Y209783D01*
X37467Y209950D01*
X37675Y210242D01*
X37717Y210575D01*
X37633Y210908D01*
X37425Y211117D01*
X37133Y211283D01*
X36842Y211325D01*
X36550Y211283D01*
X36175Y211117D01*
X36300Y212200D01*
X37425D01*
G01X38983Y210075D02*
X39233Y209867D01*
X39525Y209742D01*
X39900Y209700D01*
X40275Y209783D01*
X40567Y209950D01*
X40775Y210242D01*
X40817Y210575D01*
X40733Y210908D01*
X40525Y211117D01*
X40233Y211283D01*
X39942Y211325D01*
X39650Y211283D01*
X39275Y211117D01*
X39400Y212200D01*
X40525D01*
G01X34617Y208092D02*
X34367Y208217D01*
X34075Y208300D01*
X33742D01*
X33367Y208175D01*
X33075Y207967D01*
X32867Y207717D01*
X32700Y207300D01*
X32658Y206925D01*
X32742Y206550D01*
X32867Y206300D01*
X33117Y206050D01*
X33408Y205883D01*
X33700Y205800D01*
X33992D01*
X34283Y205883D01*
X34533Y206008D01*
X34742Y206175D01*
G01X35883D02*
X36133Y205967D01*
X36425Y205842D01*
X36800Y205800D01*
X37175Y205883D01*
X37467Y206050D01*
X37675Y206342D01*
X37717Y206675D01*
X37633Y207008D01*
X37425Y207217D01*
X37133Y207383D01*
X36842Y207425D01*
X36550Y207383D01*
X36175Y207217D01*
X36300Y208300D01*
X37425D01*
G01X39817Y205800D02*
X39900Y206342D01*
X40025Y206800D01*
X40192Y207217D01*
X40400Y207675D01*
X40733Y208300D01*
X39067D01*
G01X30517Y214000D02*
Y216500D01*
X31517D01*
X31850Y216375D01*
X32100Y216083D01*
X32183Y215750D01*
X32100Y215417D01*
X31892Y215167D01*
X31517Y215042D01*
X30517D01*
G01X33617Y214000D02*
Y216500D01*
X34658D01*
X34992Y216375D01*
X35200Y216208D01*
X35283Y215875D01*
X35200Y215542D01*
X34950Y215333D01*
X34658Y215208D01*
X33617D01*
G01X34658D02*
X35283Y214000D01*
G01X37467D02*
X37550Y214542D01*
X37675Y215000D01*
X37842Y215417D01*
X38050Y215875D01*
X38383Y216500D01*
X36717D01*
G01X40650D02*
X40317Y216417D01*
X40067Y216208D01*
X39900Y215958D01*
X39775Y215625D01*
X39733Y215250D01*
X39775Y214875D01*
X39900Y214542D01*
X40067Y214292D01*
X40317Y214083D01*
X40650Y214000D01*
X40983Y214083D01*
X41233Y214292D01*
X41400Y214542D01*
X41525Y214875D01*
X41567Y215250D01*
X41525Y215625D01*
X41400Y215958D01*
X41233Y216208D01*
X40983Y216417D01*
X40650Y216500D01*
G01X26027Y268687D02*
Y271187D01*
X27027D01*
X27360Y271062D01*
X27610Y270770D01*
X27693Y270437D01*
X27610Y270104D01*
X27402Y269854D01*
X27027Y269729D01*
X26027D01*
G01X29127Y268687D02*
Y271187D01*
X30168D01*
X30502Y271062D01*
X30710Y270895D01*
X30793Y270562D01*
X30710Y270229D01*
X30460Y270020D01*
X30168Y269895D01*
X29127D01*
G01X30168D02*
X30793Y268687D01*
G01X32143Y269187D02*
X32393Y268895D01*
X32727Y268729D01*
X33102Y268687D01*
X33435Y268729D01*
X33768Y268937D01*
X33977Y269187D01*
X34018Y269437D01*
X33935Y269729D01*
X33643Y269937D01*
X33352Y270020D01*
X32977D01*
G01X33352D02*
X33602Y270145D01*
X33810Y270354D01*
X33893Y270604D01*
X33810Y270854D01*
X33602Y271062D01*
X33227Y271187D01*
X32852Y271145D01*
X32477Y270979D01*
G01X35452Y268979D02*
X35743Y268770D01*
X36077Y268687D01*
X36410Y268770D01*
X36702Y269020D01*
X36910Y269395D01*
X36993Y269770D01*
Y270229D01*
X36910Y270604D01*
X36702Y270937D01*
X36452Y271104D01*
X36160Y271187D01*
X35827Y271104D01*
X35577Y270937D01*
X35410Y270687D01*
X35327Y270354D01*
X35410Y270062D01*
X35618Y269770D01*
X35868Y269604D01*
X36160Y269562D01*
X36493Y269645D01*
X36743Y269854D01*
X36993Y270229D01*
G01X26017Y264900D02*
Y267400D01*
X27017D01*
X27350Y267275D01*
X27600Y266983D01*
X27683Y266650D01*
X27600Y266317D01*
X27392Y266067D01*
X27017Y265942D01*
X26017D01*
G01X29117Y264900D02*
Y267400D01*
X30158D01*
X30492Y267275D01*
X30700Y267108D01*
X30783Y266775D01*
X30700Y266442D01*
X30450Y266233D01*
X30158Y266108D01*
X29117D01*
G01X30158D02*
X30783Y264900D01*
G01X33550D02*
Y267400D01*
X32008Y265608D01*
X34092D01*
G01X36150Y264900D02*
Y267400D01*
X35650Y266900D01*
G01Y264900D02*
X36650D01*
G01X26017Y261000D02*
Y263500D01*
X27017D01*
X27350Y263375D01*
X27600Y263083D01*
X27683Y262750D01*
X27600Y262417D01*
X27392Y262167D01*
X27017Y262042D01*
X26017D01*
G01X29117Y261000D02*
Y263500D01*
X30158D01*
X30492Y263375D01*
X30700Y263208D01*
X30783Y262875D01*
X30700Y262542D01*
X30450Y262333D01*
X30158Y262208D01*
X29117D01*
G01X30158D02*
X30783Y261000D01*
G01X33550D02*
Y263500D01*
X32008Y261708D01*
X34092D01*
G01X35233Y261375D02*
X35483Y261167D01*
X35775Y261042D01*
X36150Y261000D01*
X36525Y261083D01*
X36817Y261250D01*
X37025Y261542D01*
X37067Y261875D01*
X36983Y262208D01*
X36775Y262417D01*
X36483Y262583D01*
X36192Y262625D01*
X35900Y262583D01*
X35525Y262417D01*
X35650Y263500D01*
X36775D01*
G01X26017Y272400D02*
Y274900D01*
X27017D01*
X27350Y274775D01*
X27600Y274483D01*
X27683Y274150D01*
X27600Y273817D01*
X27392Y273567D01*
X27017Y273442D01*
X26017D01*
G01X29117Y272400D02*
Y274900D01*
X30158D01*
X30492Y274775D01*
X30700Y274608D01*
X30783Y274275D01*
X30700Y273942D01*
X30450Y273733D01*
X30158Y273608D01*
X29117D01*
G01X30158D02*
X30783Y272400D01*
G01X32133Y272900D02*
X32383Y272608D01*
X32717Y272442D01*
X33092Y272400D01*
X33425Y272442D01*
X33758Y272650D01*
X33967Y272900D01*
X34008Y273150D01*
X33925Y273442D01*
X33633Y273650D01*
X33342Y273733D01*
X32967D01*
G01X33342D02*
X33592Y273858D01*
X33800Y274067D01*
X33883Y274317D01*
X33800Y274567D01*
X33592Y274775D01*
X33217Y274900D01*
X32842Y274858D01*
X32467Y274692D01*
G01X35358Y273442D02*
X35650Y273733D01*
X35900Y273900D01*
X36233Y273983D01*
X36525Y273900D01*
X36733Y273733D01*
X36900Y273483D01*
X36942Y273192D01*
X36900Y272942D01*
X36733Y272692D01*
X36483Y272483D01*
X36192Y272400D01*
X35858Y272483D01*
X35567Y272733D01*
X35400Y273108D01*
X35358Y273525D01*
X35442Y274067D01*
X35567Y274358D01*
X35775Y274650D01*
X36067Y274858D01*
X36358Y274900D01*
X36650Y274817D01*
X36858Y274608D01*
G01X42000Y100067D02*
X39500D01*
Y101067D01*
X39625Y101400D01*
X39917Y101650D01*
X40250Y101733D01*
X40583Y101650D01*
X40833Y101442D01*
X40958Y101067D01*
Y100067D01*
G01X39500Y103083D02*
X41292D01*
X41667Y103250D01*
X41917Y103583D01*
X42000Y104000D01*
X41917Y104417D01*
X41667Y104750D01*
X41292Y104917D01*
X39500D01*
G01X42000Y107017D02*
X41458Y107100D01*
X41000Y107225D01*
X40583Y107392D01*
X40125Y107600D01*
X39500Y107933D01*
Y106267D01*
G01X42000Y223900D02*
X44500D01*
G01X42000Y222942D02*
Y224858D01*
G01X44500Y226167D02*
X42000D01*
Y227167D01*
X42125Y227500D01*
X42417Y227750D01*
X42750Y227833D01*
X43083Y227750D01*
X43333Y227542D01*
X43458Y227167D01*
Y226167D01*
G01X44125Y229183D02*
X44333Y229433D01*
X44458Y229725D01*
X44500Y230100D01*
X44417Y230475D01*
X44250Y230767D01*
X43958Y230975D01*
X43625Y231017D01*
X43292Y230933D01*
X43083Y230725D01*
X42917Y230433D01*
X42875Y230142D01*
X42917Y229850D01*
X43083Y229475D01*
X42000Y229600D01*
Y230725D01*
G01X46000Y223900D02*
X48500D01*
G01X46000Y222942D02*
Y224858D01*
G01X48500Y226167D02*
X46000D01*
Y227167D01*
X46125Y227500D01*
X46417Y227750D01*
X46750Y227833D01*
X47083Y227750D01*
X47333Y227542D01*
X47458Y227167D01*
Y226167D01*
G01Y229308D02*
X47167Y229600D01*
X47000Y229850D01*
X46917Y230183D01*
X47000Y230475D01*
X47167Y230683D01*
X47417Y230850D01*
X47708Y230892D01*
X47958Y230850D01*
X48208Y230683D01*
X48417Y230433D01*
X48500Y230142D01*
X48417Y229808D01*
X48167Y229517D01*
X47792Y229350D01*
X47375Y229308D01*
X46833Y229392D01*
X46542Y229517D01*
X46250Y229725D01*
X46042Y230017D01*
X46000Y230308D01*
X46083Y230600D01*
X46292Y230808D01*
G01X39400Y247500D02*
Y245000D01*
G01X38442Y247500D02*
X40358D01*
G01X41667Y245000D02*
Y247500D01*
X42667D01*
X43000Y247375D01*
X43250Y247083D01*
X43333Y246750D01*
X43250Y246417D01*
X43042Y246167D01*
X42667Y246042D01*
X41667D01*
G01X46100Y245000D02*
Y247500D01*
X44558Y245708D01*
X46642D01*
G01X40500Y229517D02*
X38000D01*
Y230517D01*
X38125Y230850D01*
X38417Y231100D01*
X38750Y231183D01*
X39083Y231100D01*
X39333Y230892D01*
X39458Y230517D01*
Y229517D01*
G01X40500Y232617D02*
X38000D01*
Y233658D01*
X38125Y233992D01*
X38292Y234200D01*
X38625Y234283D01*
X38958Y234200D01*
X39167Y233950D01*
X39292Y233658D01*
Y232617D01*
G01Y233658D02*
X40500Y234283D01*
G01X40125Y235633D02*
X40333Y235883D01*
X40458Y236175D01*
X40500Y236550D01*
X40417Y236925D01*
X40250Y237217D01*
X39958Y237425D01*
X39625Y237467D01*
X39292Y237383D01*
X39083Y237175D01*
X38917Y236883D01*
X38875Y236592D01*
X38917Y236300D01*
X39083Y235925D01*
X38000Y236050D01*
Y237175D01*
G01X38417Y238858D02*
X38167Y239108D01*
X38042Y239400D01*
X38000Y239733D01*
X38083Y240150D01*
X38292Y240442D01*
X38542Y240525D01*
X38792Y240483D01*
X39000Y240317D01*
X39417Y239483D01*
X39708Y239108D01*
X40125Y238858D01*
X40500Y238775D01*
Y240525D01*
G01X41267Y263292D02*
X41017Y263417D01*
X40725Y263500D01*
X40392D01*
X40017Y263375D01*
X39725Y263167D01*
X39517Y262917D01*
X39350Y262500D01*
X39308Y262125D01*
X39392Y261750D01*
X39517Y261500D01*
X39767Y261250D01*
X40058Y261083D01*
X40350Y261000D01*
X40642D01*
X40933Y261083D01*
X41183Y261208D01*
X41392Y261375D01*
G01X43450Y261000D02*
Y263500D01*
X42950Y263000D01*
G01Y261000D02*
X43950D01*
G01X45633Y261375D02*
X45883Y261167D01*
X46175Y261042D01*
X46550Y261000D01*
X46925Y261083D01*
X47217Y261250D01*
X47425Y261542D01*
X47467Y261875D01*
X47383Y262208D01*
X47175Y262417D01*
X46883Y262583D01*
X46592Y262625D01*
X46300Y262583D01*
X45925Y262417D01*
X46050Y263500D01*
X47175D01*
G01X49650Y261000D02*
X49942Y261042D01*
X50275Y261167D01*
X50483Y261375D01*
X50567Y261667D01*
X50483Y261958D01*
X50233Y262208D01*
X49858Y262333D01*
X49442D01*
X49192Y262417D01*
X48983Y262625D01*
X48900Y262917D01*
X49025Y263208D01*
X49317Y263417D01*
X49650Y263500D01*
X49983Y263417D01*
X50275Y263208D01*
X50400Y262917D01*
X50317Y262625D01*
X50108Y262417D01*
X49858Y262333D01*
X49442D01*
X49067Y262208D01*
X48817Y261958D01*
X48733Y261667D01*
X48817Y261375D01*
X49025Y261167D01*
X49358Y261042D01*
X49650Y261000D01*
G01X65767Y45792D02*
X65517Y45917D01*
X65225Y46000D01*
X64892D01*
X64517Y45875D01*
X64225Y45667D01*
X64017Y45417D01*
X63850Y45000D01*
X63808Y44625D01*
X63892Y44250D01*
X64017Y44000D01*
X64267Y43750D01*
X64558Y43583D01*
X64850Y43500D01*
X65142D01*
X65433Y43583D01*
X65683Y43708D01*
X65892Y43875D01*
G01X67033Y44000D02*
X67283Y43708D01*
X67617Y43542D01*
X67992Y43500D01*
X68325Y43542D01*
X68658Y43750D01*
X68867Y44000D01*
X68908Y44250D01*
X68825Y44542D01*
X68533Y44750D01*
X68242Y44833D01*
X67867D01*
G01X68242D02*
X68492Y44958D01*
X68700Y45167D01*
X68783Y45417D01*
X68700Y45667D01*
X68492Y45875D01*
X68117Y46000D01*
X67742Y45958D01*
X67367Y45792D01*
G01X70258Y45583D02*
X70508Y45833D01*
X70800Y45958D01*
X71133Y46000D01*
X71550Y45917D01*
X71842Y45708D01*
X71925Y45458D01*
X71883Y45208D01*
X71717Y45000D01*
X70883Y44583D01*
X70508Y44292D01*
X70258Y43875D01*
X70175Y43500D01*
X71925D01*
G01X74150D02*
Y46000D01*
X73650Y45500D01*
G01Y43500D02*
X74650D01*
G01X76500Y62500D02*
X69500D01*
Y57000D01*
X57500D01*
X55500Y59000D01*
Y69500D01*
G01X64000Y58967D02*
X61500D01*
Y59967D01*
X61625Y60300D01*
X61917Y60550D01*
X62250Y60633D01*
X62583Y60550D01*
X62833Y60342D01*
X62958Y59967D01*
Y58967D01*
G01X61708Y63817D02*
X61583Y63567D01*
X61500Y63275D01*
Y62942D01*
X61625Y62567D01*
X61833Y62275D01*
X62083Y62067D01*
X62500Y61900D01*
X62875Y61858D01*
X63250Y61942D01*
X63500Y62067D01*
X63750Y62317D01*
X63917Y62608D01*
X64000Y62900D01*
Y63192D01*
X63917Y63483D01*
X63792Y63733D01*
X63625Y63942D01*
G01X64000Y66000D02*
X61500D01*
X62000Y65500D01*
G01X64000D02*
Y66500D01*
G01X62958Y68308D02*
X62667Y68600D01*
X62500Y68850D01*
X62417Y69183D01*
X62500Y69475D01*
X62667Y69683D01*
X62917Y69850D01*
X63208Y69892D01*
X63458Y69850D01*
X63708Y69683D01*
X63917Y69433D01*
X64000Y69142D01*
X63917Y68808D01*
X63667Y68517D01*
X63292Y68350D01*
X62875Y68308D01*
X62333Y68392D01*
X62042Y68517D01*
X61750Y68725D01*
X61542Y69017D01*
X61500Y69308D01*
X61583Y69600D01*
X61792Y69808D01*
G01X64000Y72700D02*
X61500D01*
X63292Y71158D01*
Y73242D01*
G01X60000Y58967D02*
X57500D01*
Y59967D01*
X57625Y60300D01*
X57917Y60550D01*
X58250Y60633D01*
X58583Y60550D01*
X58833Y60342D01*
X58958Y59967D01*
Y58967D01*
G01X60000Y62067D02*
X57500D01*
Y63108D01*
X57625Y63442D01*
X57792Y63650D01*
X58125Y63733D01*
X58458Y63650D01*
X58667Y63400D01*
X58792Y63108D01*
Y62067D01*
G01Y63108D02*
X60000Y63733D01*
G01Y66000D02*
X57500D01*
X58000Y65500D01*
G01X60000D02*
Y66500D01*
G01X59708Y68392D02*
X59917Y68683D01*
X60000Y69017D01*
X59917Y69350D01*
X59667Y69642D01*
X59292Y69850D01*
X58917Y69933D01*
X58458D01*
X58083Y69850D01*
X57750Y69642D01*
X57583Y69392D01*
X57500Y69100D01*
X57583Y68767D01*
X57750Y68517D01*
X58000Y68350D01*
X58333Y68267D01*
X58625Y68350D01*
X58917Y68558D01*
X59083Y68808D01*
X59125Y69100D01*
X59042Y69433D01*
X58833Y69683D01*
X58458Y69933D01*
G01X59500Y71283D02*
X59792Y71533D01*
X59958Y71867D01*
X60000Y72242D01*
X59958Y72575D01*
X59750Y72908D01*
X59500Y73117D01*
X59250Y73158D01*
X58958Y73075D01*
X58750Y72783D01*
X58667Y72492D01*
Y72117D01*
G01Y72492D02*
X58542Y72742D01*
X58333Y72950D01*
X58083Y73033D01*
X57833Y72950D01*
X57625Y72742D01*
X57500Y72367D01*
X57542Y71992D01*
X57708Y71617D01*
G01X82500Y75000D02*
X58000D01*
G01X59017Y77000D02*
Y79500D01*
X60017D01*
X60350Y79375D01*
X60600Y79083D01*
X60683Y78750D01*
X60600Y78417D01*
X60392Y78167D01*
X60017Y78042D01*
X59017D01*
G01X62075Y77333D02*
X62408Y77125D01*
X62783Y77000D01*
X63117D01*
X63450Y77125D01*
X63700Y77333D01*
X63825Y77625D01*
X63742Y77917D01*
X63533Y78167D01*
X63158Y78333D01*
X62658Y78417D01*
X62367Y78583D01*
X62242Y78875D01*
X62325Y79167D01*
X62533Y79375D01*
X62825Y79500D01*
X63117D01*
X63408Y79417D01*
X63658Y79208D01*
G01X65217Y77000D02*
Y79500D01*
X66217D01*
X66550Y79375D01*
X66800Y79083D01*
X66883Y78750D01*
X66800Y78417D01*
X66592Y78167D01*
X66217Y78042D01*
X65217D01*
G01X69150Y77000D02*
Y79500D01*
X68650Y79000D01*
G01Y77000D02*
X69650D01*
G01X63500Y176967D02*
X61000D01*
Y177967D01*
X61125Y178300D01*
X61417Y178550D01*
X61750Y178633D01*
X62083Y178550D01*
X62333Y178342D01*
X62458Y177967D01*
Y176967D01*
G01X63500Y180067D02*
X61000D01*
Y181108D01*
X61125Y181442D01*
X61292Y181650D01*
X61625Y181733D01*
X61958Y181650D01*
X62167Y181400D01*
X62292Y181108D01*
Y180067D01*
G01Y181108D02*
X63500Y181733D01*
G01Y184000D02*
X61000D01*
X61500Y183500D01*
G01X63500D02*
Y184500D01*
G01X63208Y186392D02*
X63417Y186683D01*
X63500Y187017D01*
X63417Y187350D01*
X63167Y187642D01*
X62792Y187850D01*
X62417Y187933D01*
X61958D01*
X61583Y187850D01*
X61250Y187642D01*
X61083Y187392D01*
X61000Y187100D01*
X61083Y186767D01*
X61250Y186517D01*
X61500Y186350D01*
X61833Y186267D01*
X62125Y186350D01*
X62417Y186558D01*
X62583Y186808D01*
X62625Y187100D01*
X62542Y187433D01*
X62333Y187683D01*
X61958Y187933D01*
G01X63500Y190117D02*
X62958Y190200D01*
X62500Y190325D01*
X62083Y190492D01*
X61625Y190700D01*
X61000Y191033D01*
Y189367D01*
G01X52067Y188000D02*
Y195000D01*
X54733D01*
X55800Y194650D01*
X56600Y194183D01*
X57267Y193483D01*
X57800Y192667D01*
X57933Y191500D01*
X57800Y190333D01*
X57267Y189517D01*
X56600Y188816D01*
X55800Y188350D01*
X54733Y188000D01*
X52067D01*
G01X76500Y192000D02*
X71500D01*
Y195500D01*
X63500D01*
Y193500D01*
X59500D01*
Y186000D01*
X50500D01*
Y197000D01*
X58500D01*
G01D02*
Y215000D01*
G01X50817Y200792D02*
X50567Y200917D01*
X50275Y201000D01*
X49942D01*
X49567Y200875D01*
X49275Y200667D01*
X49067Y200417D01*
X48900Y200000D01*
X48858Y199625D01*
X48942Y199250D01*
X49067Y199000D01*
X49317Y198750D01*
X49608Y198583D01*
X49900Y198500D01*
X50192D01*
X50483Y198583D01*
X50733Y198708D01*
X50942Y198875D01*
G01X52208Y199542D02*
X52500Y199833D01*
X52750Y200000D01*
X53083Y200083D01*
X53375Y200000D01*
X53583Y199833D01*
X53750Y199583D01*
X53792Y199292D01*
X53750Y199042D01*
X53583Y198792D01*
X53333Y198583D01*
X53042Y198500D01*
X52708Y198583D01*
X52417Y198833D01*
X52250Y199208D01*
X52208Y199625D01*
X52292Y200167D01*
X52417Y200458D01*
X52625Y200750D01*
X52917Y200958D01*
X53208Y201000D01*
X53500Y200917D01*
X53708Y200708D01*
G01X55183Y199000D02*
X55433Y198708D01*
X55767Y198542D01*
X56142Y198500D01*
X56475Y198542D01*
X56808Y198750D01*
X57017Y199000D01*
X57058Y199250D01*
X56975Y199542D01*
X56683Y199750D01*
X56392Y199833D01*
X56017D01*
G01X56392D02*
X56642Y199958D01*
X56850Y200167D01*
X56933Y200417D01*
X56850Y200667D01*
X56642Y200875D01*
X56267Y201000D01*
X55892Y200958D01*
X55517Y200792D01*
G01X50817Y204792D02*
X50567Y204917D01*
X50275Y205000D01*
X49942D01*
X49567Y204875D01*
X49275Y204667D01*
X49067Y204417D01*
X48900Y204000D01*
X48858Y203625D01*
X48942Y203250D01*
X49067Y203000D01*
X49317Y202750D01*
X49608Y202583D01*
X49900Y202500D01*
X50192D01*
X50483Y202583D01*
X50733Y202708D01*
X50942Y202875D01*
G01X52083D02*
X52333Y202667D01*
X52625Y202542D01*
X53000Y202500D01*
X53375Y202583D01*
X53667Y202750D01*
X53875Y203042D01*
X53917Y203375D01*
X53833Y203708D01*
X53625Y203917D01*
X53333Y204083D01*
X53042Y204125D01*
X52750Y204083D01*
X52375Y203917D01*
X52500Y205000D01*
X53625D01*
G01X55392Y202792D02*
X55683Y202583D01*
X56017Y202500D01*
X56350Y202583D01*
X56642Y202833D01*
X56850Y203208D01*
X56933Y203583D01*
Y204042D01*
X56850Y204417D01*
X56642Y204750D01*
X56392Y204917D01*
X56100Y205000D01*
X55767Y204917D01*
X55517Y204750D01*
X55350Y204500D01*
X55267Y204167D01*
X55350Y203875D01*
X55558Y203583D01*
X55808Y203417D01*
X56100Y203375D01*
X56433Y203458D01*
X56683Y203667D01*
X56933Y204042D01*
G01X58500Y218517D02*
X56000D01*
Y219517D01*
X56125Y219850D01*
X56417Y220100D01*
X56750Y220183D01*
X57083Y220100D01*
X57333Y219892D01*
X57458Y219517D01*
Y218517D01*
G01X58500Y221617D02*
X56000D01*
Y222658D01*
X56125Y222992D01*
X56292Y223200D01*
X56625Y223283D01*
X56958Y223200D01*
X57167Y222950D01*
X57292Y222658D01*
Y221617D01*
G01Y222658D02*
X58500Y223283D01*
G01X58125Y224633D02*
X58333Y224883D01*
X58458Y225175D01*
X58500Y225550D01*
X58417Y225925D01*
X58250Y226217D01*
X57958Y226425D01*
X57625Y226467D01*
X57292Y226383D01*
X57083Y226175D01*
X56917Y225883D01*
X56875Y225592D01*
X56917Y225300D01*
X57083Y224925D01*
X56000Y225050D01*
Y226175D01*
G01X58125Y227733D02*
X58333Y227983D01*
X58458Y228275D01*
X58500Y228650D01*
X58417Y229025D01*
X58250Y229317D01*
X57958Y229525D01*
X57625Y229567D01*
X57292Y229483D01*
X57083Y229275D01*
X56917Y228983D01*
X56875Y228692D01*
X56917Y228400D01*
X57083Y228025D01*
X56000Y228150D01*
Y229275D01*
G01X59000Y254500D02*
Y241000D01*
G01X57500Y231517D02*
X55000D01*
Y232517D01*
X55125Y232850D01*
X55417Y233100D01*
X55750Y233183D01*
X56083Y233100D01*
X56333Y232892D01*
X56458Y232517D01*
Y231517D01*
G01X57500Y234617D02*
X55000D01*
Y235658D01*
X55125Y235992D01*
X55292Y236200D01*
X55625Y236283D01*
X55958Y236200D01*
X56167Y235950D01*
X56292Y235658D01*
Y234617D01*
G01Y235658D02*
X57500Y236283D01*
G01Y239050D02*
X55000D01*
X56792Y237508D01*
Y239592D01*
G01X57208Y240942D02*
X57417Y241233D01*
X57500Y241567D01*
X57417Y241900D01*
X57167Y242192D01*
X56792Y242400D01*
X56417Y242483D01*
X55958D01*
X55583Y242400D01*
X55250Y242192D01*
X55083Y241942D01*
X55000Y241650D01*
X55083Y241317D01*
X55250Y241067D01*
X55500Y240900D01*
X55833Y240817D01*
X56125Y240900D01*
X56417Y241108D01*
X56583Y241358D01*
X56625Y241650D01*
X56542Y241983D01*
X56333Y242233D01*
X55958Y242483D01*
G01X48708Y275767D02*
X48583Y275517D01*
X48500Y275225D01*
Y274892D01*
X48625Y274517D01*
X48833Y274225D01*
X49083Y274017D01*
X49500Y273850D01*
X49875Y273808D01*
X50250Y273892D01*
X50500Y274017D01*
X50750Y274267D01*
X50917Y274558D01*
X51000Y274850D01*
Y275142D01*
X50917Y275433D01*
X50792Y275683D01*
X50625Y275892D01*
G01X51000Y277950D02*
X48500D01*
X49000Y277450D01*
G01X51000D02*
Y278450D01*
G01Y280967D02*
X50458Y281050D01*
X50000Y281175D01*
X49583Y281342D01*
X49125Y281550D01*
X48500Y281883D01*
Y280217D01*
G01Y284150D02*
X48583Y283817D01*
X48792Y283567D01*
X49042Y283400D01*
X49375Y283275D01*
X49750Y283233D01*
X50125Y283275D01*
X50458Y283400D01*
X50708Y283567D01*
X50917Y283817D01*
X51000Y284150D01*
X50917Y284483D01*
X50708Y284733D01*
X50458Y284900D01*
X50125Y285025D01*
X49750Y285067D01*
X49375Y285025D01*
X49042Y284900D01*
X48792Y284733D01*
X48583Y284483D01*
X48500Y284150D01*
G01X55267Y266292D02*
X55017Y266417D01*
X54725Y266500D01*
X54392D01*
X54017Y266375D01*
X53725Y266167D01*
X53517Y265917D01*
X53350Y265500D01*
X53308Y265125D01*
X53392Y264750D01*
X53517Y264500D01*
X53767Y264250D01*
X54058Y264083D01*
X54350Y264000D01*
X54642D01*
X54933Y264083D01*
X55183Y264208D01*
X55392Y264375D01*
G01X57450Y264000D02*
Y266500D01*
X56950Y266000D01*
G01Y264000D02*
X57950D01*
G01X59633Y264375D02*
X59883Y264167D01*
X60175Y264042D01*
X60550Y264000D01*
X60925Y264083D01*
X61217Y264250D01*
X61425Y264542D01*
X61467Y264875D01*
X61383Y265208D01*
X61175Y265417D01*
X60883Y265583D01*
X60592Y265625D01*
X60300Y265583D01*
X59925Y265417D01*
X60050Y266500D01*
X61175D01*
G01X62942Y264292D02*
X63233Y264083D01*
X63567Y264000D01*
X63900Y264083D01*
X64192Y264333D01*
X64400Y264708D01*
X64483Y265083D01*
Y265542D01*
X64400Y265917D01*
X64192Y266250D01*
X63942Y266417D01*
X63650Y266500D01*
X63317Y266417D01*
X63067Y266250D01*
X62900Y266000D01*
X62817Y265667D01*
X62900Y265375D01*
X63108Y265083D01*
X63358Y264917D01*
X63650Y264875D01*
X63983Y264958D01*
X64233Y265167D01*
X64483Y265542D01*
G01X56517Y275000D02*
Y277500D01*
X57558D01*
X57892Y277375D01*
X58100Y277208D01*
X58183Y276875D01*
X58100Y276542D01*
X57850Y276333D01*
X57558Y276208D01*
X56517D01*
G01X57558D02*
X58183Y275000D01*
G01X59533Y275500D02*
X59783Y275208D01*
X60117Y275042D01*
X60492Y275000D01*
X60825Y275042D01*
X61158Y275250D01*
X61367Y275500D01*
X61408Y275750D01*
X61325Y276042D01*
X61033Y276250D01*
X60742Y276333D01*
X60367D01*
G01X60742D02*
X60992Y276458D01*
X61200Y276667D01*
X61283Y276917D01*
X61200Y277167D01*
X60992Y277375D01*
X60617Y277500D01*
X60242Y277458D01*
X59867Y277292D01*
G01X63550Y275000D02*
Y277500D01*
X63050Y277000D01*
G01Y275000D02*
X64050D01*
G01X65733Y275375D02*
X65983Y275167D01*
X66275Y275042D01*
X66650Y275000D01*
X67025Y275083D01*
X67317Y275250D01*
X67525Y275542D01*
X67567Y275875D01*
X67483Y276208D01*
X67275Y276417D01*
X66983Y276583D01*
X66692Y276625D01*
X66400Y276583D01*
X66025Y276417D01*
X66150Y277500D01*
X67275D01*
G01X53017Y279000D02*
Y281500D01*
X54058D01*
X54392Y281375D01*
X54600Y281208D01*
X54683Y280875D01*
X54600Y280542D01*
X54350Y280333D01*
X54058Y280208D01*
X53017D01*
G01X54058D02*
X54683Y279000D01*
G01X56033Y279500D02*
X56283Y279208D01*
X56617Y279042D01*
X56992Y279000D01*
X57325Y279042D01*
X57658Y279250D01*
X57867Y279500D01*
X57908Y279750D01*
X57825Y280042D01*
X57533Y280250D01*
X57242Y280333D01*
X56867D01*
G01X57242D02*
X57492Y280458D01*
X57700Y280667D01*
X57783Y280917D01*
X57700Y281167D01*
X57492Y281375D01*
X57117Y281500D01*
X56742Y281458D01*
X56367Y281292D01*
G01X60050Y281500D02*
X59717Y281417D01*
X59467Y281208D01*
X59300Y280958D01*
X59175Y280625D01*
X59133Y280250D01*
X59175Y279875D01*
X59300Y279542D01*
X59467Y279292D01*
X59717Y279083D01*
X60050Y279000D01*
X60383Y279083D01*
X60633Y279292D01*
X60800Y279542D01*
X60925Y279875D01*
X60967Y280250D01*
X60925Y280625D01*
X60800Y280958D01*
X60633Y281208D01*
X60383Y281417D01*
X60050Y281500D01*
G01X62233Y279375D02*
X62483Y279167D01*
X62775Y279042D01*
X63150Y279000D01*
X63525Y279083D01*
X63817Y279250D01*
X64025Y279542D01*
X64067Y279875D01*
X63983Y280208D01*
X63775Y280417D01*
X63483Y280583D01*
X63192Y280625D01*
X62900Y280583D01*
X62525Y280417D01*
X62650Y281500D01*
X63775D01*
G01X76500Y48500D02*
Y36000D01*
X101500D01*
G01X80900Y42017D02*
X78400D01*
Y43017D01*
X78525Y43350D01*
X78817Y43600D01*
X79150Y43683D01*
X79483Y43600D01*
X79733Y43392D01*
X79858Y43017D01*
Y42017D01*
G01X78608Y46867D02*
X78483Y46617D01*
X78400Y46325D01*
Y45992D01*
X78525Y45617D01*
X78733Y45325D01*
X78983Y45117D01*
X79400Y44950D01*
X79775Y44908D01*
X80150Y44992D01*
X80400Y45117D01*
X80650Y45367D01*
X80817Y45658D01*
X80900Y45950D01*
Y46242D01*
X80817Y46533D01*
X80692Y46783D01*
X80525Y46992D01*
G01Y48133D02*
X80733Y48383D01*
X80858Y48675D01*
X80900Y49050D01*
X80817Y49425D01*
X80650Y49717D01*
X80358Y49925D01*
X80025Y49967D01*
X79692Y49883D01*
X79483Y49675D01*
X79317Y49383D01*
X79275Y49092D01*
X79317Y48800D01*
X79483Y48425D01*
X78400Y48550D01*
Y49675D01*
G01X80900Y52150D02*
X78400D01*
X78900Y51650D01*
G01X80900D02*
Y52650D01*
G01X81000Y54967D02*
X78500D01*
Y55967D01*
X78625Y56300D01*
X78917Y56550D01*
X79250Y56633D01*
X79583Y56550D01*
X79833Y56342D01*
X79958Y55967D01*
Y54967D01*
G01X78708Y59817D02*
X78583Y59567D01*
X78500Y59275D01*
Y58942D01*
X78625Y58567D01*
X78833Y58275D01*
X79083Y58067D01*
X79500Y57900D01*
X79875Y57858D01*
X80250Y57942D01*
X80500Y58067D01*
X80750Y58317D01*
X80917Y58608D01*
X81000Y58900D01*
Y59192D01*
X80917Y59483D01*
X80792Y59733D01*
X80625Y59942D01*
G01X81000Y62000D02*
X78500D01*
X79000Y61500D01*
G01X81000D02*
Y62500D01*
G01Y65017D02*
X80458Y65100D01*
X80000Y65225D01*
X79583Y65392D01*
X79125Y65600D01*
X78500Y65933D01*
Y64267D01*
G01X81000Y68700D02*
X78500D01*
X80292Y67158D01*
Y69242D01*
G01X68000Y58967D02*
X65500D01*
Y59967D01*
X65625Y60300D01*
X65917Y60550D01*
X66250Y60633D01*
X66583Y60550D01*
X66833Y60342D01*
X66958Y59967D01*
Y58967D01*
G01X68000Y62067D02*
X65500D01*
Y63108D01*
X65625Y63442D01*
X65792Y63650D01*
X66125Y63733D01*
X66458Y63650D01*
X66667Y63400D01*
X66792Y63108D01*
Y62067D01*
G01Y63108D02*
X68000Y63733D01*
G01Y66000D02*
X65500D01*
X66000Y65500D01*
G01X68000D02*
Y66500D01*
G01X67708Y68392D02*
X67917Y68683D01*
X68000Y69017D01*
X67917Y69350D01*
X67667Y69642D01*
X67292Y69850D01*
X66917Y69933D01*
X66458D01*
X66083Y69850D01*
X65750Y69642D01*
X65583Y69392D01*
X65500Y69100D01*
X65583Y68767D01*
X65750Y68517D01*
X66000Y68350D01*
X66333Y68267D01*
X66625Y68350D01*
X66917Y68558D01*
X67083Y68808D01*
X67125Y69100D01*
X67042Y69433D01*
X66833Y69683D01*
X66458Y69933D01*
G01X65917Y71408D02*
X65667Y71658D01*
X65542Y71950D01*
X65500Y72283D01*
X65583Y72700D01*
X65792Y72992D01*
X66042Y73075D01*
X66292Y73033D01*
X66500Y72867D01*
X66917Y72033D01*
X67208Y71658D01*
X67625Y71408D01*
X68000Y71325D01*
Y73075D01*
G01X69967Y70500D02*
Y73000D01*
X70967D01*
X71300Y72875D01*
X71550Y72583D01*
X71633Y72250D01*
X71550Y71917D01*
X71342Y71667D01*
X70967Y71542D01*
X69967D01*
G01X74817Y72792D02*
X74567Y72917D01*
X74275Y73000D01*
X73942D01*
X73567Y72875D01*
X73275Y72667D01*
X73067Y72417D01*
X72900Y72000D01*
X72858Y71625D01*
X72942Y71250D01*
X73067Y71000D01*
X73317Y70750D01*
X73608Y70583D01*
X73900Y70500D01*
X74192D01*
X74483Y70583D01*
X74733Y70708D01*
X74942Y70875D01*
G01X77000Y70500D02*
Y73000D01*
X76500Y72500D01*
G01Y70500D02*
X77500D01*
G01X79183Y70875D02*
X79433Y70667D01*
X79725Y70542D01*
X80100Y70500D01*
X80475Y70583D01*
X80767Y70750D01*
X80975Y71042D01*
X81017Y71375D01*
X80933Y71708D01*
X80725Y71917D01*
X80433Y72083D01*
X80142Y72125D01*
X79850Y72083D01*
X79475Y71917D01*
X79600Y73000D01*
X80725D01*
G01X82408Y72583D02*
X82658Y72833D01*
X82950Y72958D01*
X83283Y73000D01*
X83700Y72917D01*
X83992Y72708D01*
X84075Y72458D01*
X84033Y72208D01*
X83867Y72000D01*
X83033Y71583D01*
X82658Y71292D01*
X82408Y70875D01*
X82325Y70500D01*
X84075D01*
G01X73467Y77000D02*
Y79500D01*
X74467D01*
X74800Y79375D01*
X75050Y79083D01*
X75133Y78750D01*
X75050Y78417D01*
X74842Y78167D01*
X74467Y78042D01*
X73467D01*
G01X76567Y77000D02*
Y79500D01*
X77608D01*
X77942Y79375D01*
X78150Y79208D01*
X78233Y78875D01*
X78150Y78542D01*
X77900Y78333D01*
X77608Y78208D01*
X76567D01*
G01X77608D02*
X78233Y77000D01*
G01X80500D02*
Y79500D01*
X80000Y79000D01*
G01Y77000D02*
X81000D01*
G01X83600Y79500D02*
X83267Y79417D01*
X83017Y79208D01*
X82850Y78958D01*
X82725Y78625D01*
X82683Y78250D01*
X82725Y77875D01*
X82850Y77542D01*
X83017Y77292D01*
X83267Y77083D01*
X83600Y77000D01*
X83933Y77083D01*
X84183Y77292D01*
X84350Y77542D01*
X84475Y77875D01*
X84517Y78250D01*
X84475Y78625D01*
X84350Y78958D01*
X84183Y79208D01*
X83933Y79417D01*
X83600Y79500D01*
G01X85908Y78042D02*
X86200Y78333D01*
X86450Y78500D01*
X86783Y78583D01*
X87075Y78500D01*
X87283Y78333D01*
X87450Y78083D01*
X87492Y77792D01*
X87450Y77542D01*
X87283Y77292D01*
X87033Y77083D01*
X86742Y77000D01*
X86408Y77083D01*
X86117Y77333D01*
X85950Y77708D01*
X85908Y78125D01*
X85992Y78667D01*
X86117Y78958D01*
X86325Y79250D01*
X86617Y79458D01*
X86908Y79500D01*
X87200Y79417D01*
X87408Y79208D01*
G01X81500Y169567D02*
X79000D01*
Y170567D01*
X79125Y170900D01*
X79417Y171150D01*
X79750Y171233D01*
X80083Y171150D01*
X80333Y170942D01*
X80458Y170567D01*
Y169567D01*
G01X79000Y172667D02*
X81500D01*
Y174333D01*
G01X80458Y175808D02*
X80167Y176100D01*
X80000Y176350D01*
X79917Y176683D01*
X80000Y176975D01*
X80167Y177183D01*
X80417Y177350D01*
X80708Y177392D01*
X80958Y177350D01*
X81208Y177183D01*
X81417Y176933D01*
X81500Y176642D01*
X81417Y176308D01*
X81167Y176017D01*
X80792Y175850D01*
X80375Y175808D01*
X79833Y175892D01*
X79542Y176017D01*
X79250Y176225D01*
X79042Y176517D01*
X79000Y176808D01*
X79083Y177100D01*
X79292Y177308D01*
G01X77500Y168967D02*
X75000D01*
Y169967D01*
X75125Y170300D01*
X75417Y170550D01*
X75750Y170633D01*
X76083Y170550D01*
X76333Y170342D01*
X76458Y169967D01*
Y168967D01*
G01X75208Y173817D02*
X75083Y173567D01*
X75000Y173275D01*
Y172942D01*
X75125Y172567D01*
X75333Y172275D01*
X75583Y172067D01*
X76000Y171900D01*
X76375Y171858D01*
X76750Y171942D01*
X77000Y172067D01*
X77250Y172317D01*
X77417Y172608D01*
X77500Y172900D01*
Y173192D01*
X77417Y173483D01*
X77292Y173733D01*
X77125Y173942D01*
G01X77500Y176000D02*
X75000D01*
X75500Y175500D01*
G01X77500D02*
Y176500D01*
G01Y179017D02*
X76958Y179100D01*
X76500Y179225D01*
X76083Y179392D01*
X75625Y179600D01*
X75000Y179933D01*
Y178267D01*
G01X76458Y181408D02*
X76167Y181700D01*
X76000Y181950D01*
X75917Y182283D01*
X76000Y182575D01*
X76167Y182783D01*
X76417Y182950D01*
X76708Y182992D01*
X76958Y182950D01*
X77208Y182783D01*
X77417Y182533D01*
X77500Y182242D01*
X77417Y181908D01*
X77167Y181617D01*
X76792Y181450D01*
X76375Y181408D01*
X75833Y181492D01*
X75542Y181617D01*
X75250Y181825D01*
X75042Y182117D01*
X75000Y182408D01*
X75083Y182700D01*
X75292Y182908D01*
G01X65517Y187500D02*
Y190000D01*
X66517D01*
X66850Y189875D01*
X67100Y189583D01*
X67183Y189250D01*
X67100Y188917D01*
X66892Y188667D01*
X66517Y188542D01*
X65517D01*
G01X68617Y187500D02*
Y190000D01*
X69658D01*
X69992Y189875D01*
X70200Y189708D01*
X70283Y189375D01*
X70200Y189042D01*
X69950Y188833D01*
X69658Y188708D01*
X68617D01*
G01X69658D02*
X70283Y187500D01*
G01X71842Y187792D02*
X72133Y187583D01*
X72467Y187500D01*
X72800Y187583D01*
X73092Y187833D01*
X73300Y188208D01*
X73383Y188583D01*
Y189042D01*
X73300Y189417D01*
X73092Y189750D01*
X72842Y189917D01*
X72550Y190000D01*
X72217Y189917D01*
X71967Y189750D01*
X71800Y189500D01*
X71717Y189167D01*
X71800Y188875D01*
X72008Y188583D01*
X72258Y188417D01*
X72550Y188375D01*
X72883Y188458D01*
X73133Y188667D01*
X73383Y189042D01*
G01X75650Y187500D02*
X75942Y187542D01*
X76275Y187667D01*
X76483Y187875D01*
X76567Y188167D01*
X76483Y188458D01*
X76233Y188708D01*
X75858Y188833D01*
X75442D01*
X75192Y188917D01*
X74983Y189125D01*
X74900Y189417D01*
X75025Y189708D01*
X75317Y189917D01*
X75650Y190000D01*
X75983Y189917D01*
X76275Y189708D01*
X76400Y189417D01*
X76317Y189125D01*
X76108Y188917D01*
X75858Y188833D01*
X75442D01*
X75067Y188708D01*
X74817Y188458D01*
X74733Y188167D01*
X74817Y187875D01*
X75025Y187667D01*
X75358Y187542D01*
X75650Y187500D01*
G01X67500Y260000D02*
X66500D01*
Y256000D01*
X65500D01*
G01X75000Y260500D02*
X82500D01*
G01X74600Y267917D02*
X72100D01*
Y268917D01*
X72225Y269250D01*
X72517Y269500D01*
X72850Y269583D01*
X73183Y269500D01*
X73433Y269292D01*
X73558Y268917D01*
Y267917D01*
G01X72308Y272767D02*
X72183Y272517D01*
X72100Y272225D01*
Y271892D01*
X72225Y271517D01*
X72433Y271225D01*
X72683Y271017D01*
X73100Y270850D01*
X73475Y270808D01*
X73850Y270892D01*
X74100Y271017D01*
X74350Y271267D01*
X74517Y271558D01*
X74600Y271850D01*
Y272142D01*
X74517Y272433D01*
X74392Y272683D01*
X74225Y272892D01*
G01X74600Y274950D02*
X72100D01*
X72600Y274450D01*
G01X74600D02*
Y275450D01*
G01X73558Y277258D02*
X73267Y277550D01*
X73100Y277800D01*
X73017Y278133D01*
X73100Y278425D01*
X73267Y278633D01*
X73517Y278800D01*
X73808Y278842D01*
X74058Y278800D01*
X74308Y278633D01*
X74517Y278383D01*
X74600Y278092D01*
X74517Y277758D01*
X74267Y277467D01*
X73892Y277300D01*
X73475Y277258D01*
X72933Y277342D01*
X72642Y277467D01*
X72350Y277675D01*
X72142Y277967D01*
X72100Y278258D01*
X72183Y278550D01*
X72392Y278758D01*
G01X70900Y268067D02*
X68400D01*
Y269067D01*
X68525Y269400D01*
X68817Y269650D01*
X69150Y269733D01*
X69483Y269650D01*
X69733Y269442D01*
X69858Y269067D01*
Y268067D01*
G01X68608Y272917D02*
X68483Y272667D01*
X68400Y272375D01*
Y272042D01*
X68525Y271667D01*
X68733Y271375D01*
X68983Y271167D01*
X69400Y271000D01*
X69775Y270958D01*
X70150Y271042D01*
X70400Y271167D01*
X70650Y271417D01*
X70817Y271708D01*
X70900Y272000D01*
Y272292D01*
X70817Y272583D01*
X70692Y272833D01*
X70525Y273042D01*
G01X70608Y274392D02*
X70817Y274683D01*
X70900Y275017D01*
X70817Y275350D01*
X70567Y275642D01*
X70192Y275850D01*
X69817Y275933D01*
X69358D01*
X68983Y275850D01*
X68650Y275642D01*
X68483Y275392D01*
X68400Y275100D01*
X68483Y274767D01*
X68650Y274517D01*
X68900Y274350D01*
X69233Y274267D01*
X69525Y274350D01*
X69817Y274558D01*
X69983Y274808D01*
X70025Y275100D01*
X69942Y275433D01*
X69733Y275683D01*
X69358Y275933D01*
G01X66817Y280600D02*
Y283100D01*
X67817D01*
X68150Y282975D01*
X68400Y282683D01*
X68483Y282350D01*
X68400Y282017D01*
X68192Y281767D01*
X67817Y281642D01*
X66817D01*
G01X71667Y282892D02*
X71417Y283017D01*
X71125Y283100D01*
X70792D01*
X70417Y282975D01*
X70125Y282767D01*
X69917Y282517D01*
X69750Y282100D01*
X69708Y281725D01*
X69792Y281350D01*
X69917Y281100D01*
X70167Y280850D01*
X70458Y280683D01*
X70750Y280600D01*
X71042D01*
X71333Y280683D01*
X71583Y280808D01*
X71792Y280975D01*
G01X73850Y280600D02*
Y283100D01*
X73350Y282600D01*
G01Y280600D02*
X74350D01*
G01X76867D02*
X76950Y281142D01*
X77075Y281600D01*
X77242Y282017D01*
X77450Y282475D01*
X77783Y283100D01*
X76117D01*
G01X66717Y284400D02*
Y286900D01*
X67717D01*
X68050Y286775D01*
X68300Y286483D01*
X68383Y286150D01*
X68300Y285817D01*
X68092Y285567D01*
X67717Y285442D01*
X66717D01*
G01X69817Y284400D02*
Y286900D01*
X70858D01*
X71192Y286775D01*
X71400Y286608D01*
X71483Y286275D01*
X71400Y285942D01*
X71150Y285733D01*
X70858Y285608D01*
X69817D01*
G01X70858D02*
X71483Y284400D01*
G01X73750D02*
Y286900D01*
X73250Y286400D01*
G01Y284400D02*
X74250D01*
G01X76058Y285442D02*
X76350Y285733D01*
X76600Y285900D01*
X76933Y285983D01*
X77225Y285900D01*
X77433Y285733D01*
X77600Y285483D01*
X77642Y285192D01*
X77600Y284942D01*
X77433Y284692D01*
X77183Y284483D01*
X76892Y284400D01*
X76558Y284483D01*
X76267Y284733D01*
X76100Y285108D01*
X76058Y285525D01*
X76142Y286067D01*
X76267Y286358D01*
X76475Y286650D01*
X76767Y286858D01*
X77058Y286900D01*
X77350Y286817D01*
X77558Y286608D01*
G01X91208Y39267D02*
X91083Y39017D01*
X91000Y38725D01*
Y38392D01*
X91125Y38017D01*
X91333Y37725D01*
X91583Y37517D01*
X92000Y37350D01*
X92375Y37308D01*
X92750Y37392D01*
X93000Y37517D01*
X93250Y37767D01*
X93417Y38058D01*
X93500Y38350D01*
Y38642D01*
X93417Y38933D01*
X93292Y39183D01*
X93125Y39392D01*
G01X93500Y41450D02*
X91000D01*
X91500Y40950D01*
G01X93500D02*
Y41950D01*
G01X91417Y43758D02*
X91167Y44008D01*
X91042Y44300D01*
X91000Y44633D01*
X91083Y45050D01*
X91292Y45342D01*
X91542Y45425D01*
X91792Y45383D01*
X92000Y45217D01*
X92417Y44383D01*
X92708Y44008D01*
X93125Y43758D01*
X93500Y43675D01*
Y45425D01*
G01X91417Y46858D02*
X91167Y47108D01*
X91042Y47400D01*
X91000Y47733D01*
X91083Y48150D01*
X91292Y48442D01*
X91542Y48525D01*
X91792Y48483D01*
X92000Y48317D01*
X92417Y47483D01*
X92708Y47108D01*
X93125Y46858D01*
X93500Y46775D01*
Y48525D01*
G01X84900Y42017D02*
X82400D01*
Y43017D01*
X82525Y43350D01*
X82817Y43600D01*
X83150Y43683D01*
X83483Y43600D01*
X83733Y43392D01*
X83858Y43017D01*
Y42017D01*
G01X82608Y46867D02*
X82483Y46617D01*
X82400Y46325D01*
Y45992D01*
X82525Y45617D01*
X82733Y45325D01*
X82983Y45117D01*
X83400Y44950D01*
X83775Y44908D01*
X84150Y44992D01*
X84400Y45117D01*
X84650Y45367D01*
X84817Y45658D01*
X84900Y45950D01*
Y46242D01*
X84817Y46533D01*
X84692Y46783D01*
X84525Y46992D01*
G01X84900Y49550D02*
X82400D01*
X84192Y48008D01*
Y50092D01*
G01X84900Y52650D02*
X82400D01*
X84192Y51108D01*
Y53192D01*
G01X88900Y42017D02*
X86400D01*
Y43017D01*
X86525Y43350D01*
X86817Y43600D01*
X87150Y43683D01*
X87483Y43600D01*
X87733Y43392D01*
X87858Y43017D01*
Y42017D01*
G01X86608Y46867D02*
X86483Y46617D01*
X86400Y46325D01*
Y45992D01*
X86525Y45617D01*
X86733Y45325D01*
X86983Y45117D01*
X87400Y44950D01*
X87775Y44908D01*
X88150Y44992D01*
X88400Y45117D01*
X88650Y45367D01*
X88817Y45658D01*
X88900Y45950D01*
Y46242D01*
X88817Y46533D01*
X88692Y46783D01*
X88525Y46992D01*
G01X88400Y48133D02*
X88692Y48383D01*
X88858Y48717D01*
X88900Y49092D01*
X88858Y49425D01*
X88650Y49758D01*
X88400Y49967D01*
X88150Y50008D01*
X87858Y49925D01*
X87650Y49633D01*
X87567Y49342D01*
Y48967D01*
G01Y49342D02*
X87442Y49592D01*
X87233Y49800D01*
X86983Y49883D01*
X86733Y49800D01*
X86525Y49592D01*
X86400Y49217D01*
X86442Y48842D01*
X86608Y48467D01*
G01X87858Y51358D02*
X87567Y51650D01*
X87400Y51900D01*
X87317Y52233D01*
X87400Y52525D01*
X87567Y52733D01*
X87817Y52900D01*
X88108Y52942D01*
X88358Y52900D01*
X88608Y52733D01*
X88817Y52483D01*
X88900Y52192D01*
X88817Y51858D01*
X88567Y51567D01*
X88192Y51400D01*
X87775Y51358D01*
X87233Y51442D01*
X86942Y51567D01*
X86650Y51775D01*
X86442Y52067D01*
X86400Y52358D01*
X86483Y52650D01*
X86692Y52858D01*
G01X85300Y54667D02*
X82800D01*
Y55667D01*
X82925Y56000D01*
X83217Y56250D01*
X83550Y56333D01*
X83883Y56250D01*
X84133Y56042D01*
X84258Y55667D01*
Y54667D01*
G01X83008Y59517D02*
X82883Y59267D01*
X82800Y58975D01*
Y58642D01*
X82925Y58267D01*
X83133Y57975D01*
X83383Y57767D01*
X83800Y57600D01*
X84175Y57558D01*
X84550Y57642D01*
X84800Y57767D01*
X85050Y58017D01*
X85217Y58308D01*
X85300Y58600D01*
Y58892D01*
X85217Y59183D01*
X85092Y59433D01*
X84925Y59642D01*
G01X85300Y61700D02*
X82800D01*
X83300Y61200D01*
G01X85300D02*
Y62200D01*
G01Y64717D02*
X84758Y64800D01*
X84300Y64925D01*
X83883Y65092D01*
X83425Y65300D01*
X82800Y65633D01*
Y63967D01*
G01X83217Y67108D02*
X82967Y67358D01*
X82842Y67650D01*
X82800Y67983D01*
X82883Y68400D01*
X83092Y68692D01*
X83342Y68775D01*
X83592Y68733D01*
X83800Y68567D01*
X84217Y67733D01*
X84508Y67358D01*
X84925Y67108D01*
X85300Y67025D01*
Y68775D01*
G01X89500Y54967D02*
X87000D01*
Y55967D01*
X87125Y56300D01*
X87417Y56550D01*
X87750Y56633D01*
X88083Y56550D01*
X88333Y56342D01*
X88458Y55967D01*
Y54967D01*
G01X89500Y58067D02*
X87000D01*
Y59108D01*
X87125Y59442D01*
X87292Y59650D01*
X87625Y59733D01*
X87958Y59650D01*
X88167Y59400D01*
X88292Y59108D01*
Y58067D01*
G01Y59108D02*
X89500Y59733D01*
G01Y62000D02*
X87000D01*
X87500Y61500D01*
G01X89500D02*
Y62500D01*
G01X89208Y64392D02*
X89417Y64683D01*
X89500Y65017D01*
X89417Y65350D01*
X89167Y65642D01*
X88792Y65850D01*
X88417Y65933D01*
X87958D01*
X87583Y65850D01*
X87250Y65642D01*
X87083Y65392D01*
X87000Y65100D01*
X87083Y64767D01*
X87250Y64517D01*
X87500Y64350D01*
X87833Y64267D01*
X88125Y64350D01*
X88417Y64558D01*
X88583Y64808D01*
X88625Y65100D01*
X88542Y65433D01*
X88333Y65683D01*
X87958Y65933D01*
G01X89500Y68200D02*
X89458Y68492D01*
X89333Y68825D01*
X89125Y69033D01*
X88833Y69117D01*
X88542Y69033D01*
X88292Y68783D01*
X88167Y68408D01*
Y67992D01*
X88083Y67742D01*
X87875Y67533D01*
X87583Y67450D01*
X87292Y67575D01*
X87083Y67867D01*
X87000Y68200D01*
X87083Y68533D01*
X87292Y68825D01*
X87583Y68950D01*
X87875Y68867D01*
X88083Y68658D01*
X88167Y68408D01*
Y67992D01*
X88292Y67617D01*
X88542Y67367D01*
X88833Y67283D01*
X89125Y67367D01*
X89333Y67575D01*
X89458Y67908D01*
X89500Y68200D01*
G01X91517Y50000D02*
Y52500D01*
X92558D01*
X92892Y52375D01*
X93100Y52208D01*
X93183Y51875D01*
X93100Y51542D01*
X92850Y51333D01*
X92558Y51208D01*
X91517D01*
G01X92558D02*
X93183Y50000D01*
G01X94658Y52083D02*
X94908Y52333D01*
X95200Y52458D01*
X95533Y52500D01*
X95950Y52417D01*
X96242Y52208D01*
X96325Y51958D01*
X96283Y51708D01*
X96117Y51500D01*
X95283Y51083D01*
X94908Y50792D01*
X94658Y50375D01*
X94575Y50000D01*
X96325D01*
G01X98467D02*
X98550Y50542D01*
X98675Y51000D01*
X98842Y51417D01*
X99050Y51875D01*
X99383Y52500D01*
X97717D01*
G01X101650D02*
X101317Y52417D01*
X101067Y52208D01*
X100900Y51958D01*
X100775Y51625D01*
X100733Y51250D01*
X100775Y50875D01*
X100900Y50542D01*
X101067Y50292D01*
X101317Y50083D01*
X101650Y50000D01*
X101983Y50083D01*
X102233Y50292D01*
X102400Y50542D01*
X102525Y50875D01*
X102567Y51250D01*
X102525Y51625D01*
X102400Y51958D01*
X102233Y52208D01*
X101983Y52417D01*
X101650Y52500D01*
G01X91517Y58000D02*
Y60500D01*
X92558D01*
X92892Y60375D01*
X93100Y60208D01*
X93183Y59875D01*
X93100Y59542D01*
X92850Y59333D01*
X92558Y59208D01*
X91517D01*
G01X92558D02*
X93183Y58000D01*
G01X94658Y60083D02*
X94908Y60333D01*
X95200Y60458D01*
X95533Y60500D01*
X95950Y60417D01*
X96242Y60208D01*
X96325Y59958D01*
X96283Y59708D01*
X96117Y59500D01*
X95283Y59083D01*
X94908Y58792D01*
X94658Y58375D01*
X94575Y58000D01*
X96325D01*
G01X98467D02*
X98550Y58542D01*
X98675Y59000D01*
X98842Y59417D01*
X99050Y59875D01*
X99383Y60500D01*
X97717D01*
G01X101567Y58000D02*
X101650Y58542D01*
X101775Y59000D01*
X101942Y59417D01*
X102150Y59875D01*
X102483Y60500D01*
X100817D01*
G01X91617Y54000D02*
Y56500D01*
X92658D01*
X92992Y56375D01*
X93200Y56208D01*
X93283Y55875D01*
X93200Y55542D01*
X92950Y55333D01*
X92658Y55208D01*
X91617D01*
G01X92658D02*
X93283Y54000D01*
G01X94758Y56083D02*
X95008Y56333D01*
X95300Y56458D01*
X95633Y56500D01*
X96050Y56417D01*
X96342Y56208D01*
X96425Y55958D01*
X96383Y55708D01*
X96217Y55500D01*
X95383Y55083D01*
X95008Y54792D01*
X94758Y54375D01*
X94675Y54000D01*
X96425D01*
G01X97858Y55042D02*
X98150Y55333D01*
X98400Y55500D01*
X98733Y55583D01*
X99025Y55500D01*
X99233Y55333D01*
X99400Y55083D01*
X99442Y54792D01*
X99400Y54542D01*
X99233Y54292D01*
X98983Y54083D01*
X98692Y54000D01*
X98358Y54083D01*
X98067Y54333D01*
X97900Y54708D01*
X97858Y55125D01*
X97942Y55667D01*
X98067Y55958D01*
X98275Y56250D01*
X98567Y56458D01*
X98858Y56500D01*
X99150Y56417D01*
X99358Y56208D01*
G01X101042Y54292D02*
X101333Y54083D01*
X101667Y54000D01*
X102000Y54083D01*
X102292Y54333D01*
X102500Y54708D01*
X102583Y55083D01*
Y55542D01*
X102500Y55917D01*
X102292Y56250D01*
X102042Y56417D01*
X101750Y56500D01*
X101417Y56417D01*
X101167Y56250D01*
X101000Y56000D01*
X100917Y55667D01*
X101000Y55375D01*
X101208Y55083D01*
X101458Y54917D01*
X101750Y54875D01*
X102083Y54958D01*
X102333Y55167D01*
X102583Y55542D01*
G01X93500Y62517D02*
X91000D01*
Y63558D01*
X91125Y63892D01*
X91292Y64100D01*
X91625Y64183D01*
X91958Y64100D01*
X92167Y63850D01*
X92292Y63558D01*
Y62517D01*
G01Y63558D02*
X93500Y64183D01*
G01X91417Y65658D02*
X91167Y65908D01*
X91042Y66200D01*
X91000Y66533D01*
X91083Y66950D01*
X91292Y67242D01*
X91542Y67325D01*
X91792Y67283D01*
X92000Y67117D01*
X92417Y66283D01*
X92708Y65908D01*
X93125Y65658D01*
X93500Y65575D01*
Y67325D01*
G01X92458Y68758D02*
X92167Y69050D01*
X92000Y69300D01*
X91917Y69633D01*
X92000Y69925D01*
X92167Y70133D01*
X92417Y70300D01*
X92708Y70342D01*
X92958Y70300D01*
X93208Y70133D01*
X93417Y69883D01*
X93500Y69592D01*
X93417Y69258D01*
X93167Y68967D01*
X92792Y68800D01*
X92375Y68758D01*
X91833Y68842D01*
X91542Y68967D01*
X91250Y69175D01*
X91042Y69467D01*
X91000Y69758D01*
X91083Y70050D01*
X91292Y70258D01*
G01X93500Y72567D02*
X92958Y72650D01*
X92500Y72775D01*
X92083Y72942D01*
X91625Y73150D01*
X91000Y73483D01*
Y71817D01*
G01X89017Y83500D02*
Y86000D01*
X90017D01*
X90350Y85875D01*
X90600Y85583D01*
X90683Y85250D01*
X90600Y84917D01*
X90392Y84667D01*
X90017Y84542D01*
X89017D01*
G01X93867Y85792D02*
X93617Y85917D01*
X93325Y86000D01*
X92992D01*
X92617Y85875D01*
X92325Y85667D01*
X92117Y85417D01*
X91950Y85000D01*
X91908Y84625D01*
X91992Y84250D01*
X92117Y84000D01*
X92367Y83750D01*
X92658Y83583D01*
X92950Y83500D01*
X93242D01*
X93533Y83583D01*
X93783Y83708D01*
X93992Y83875D01*
G01X95967Y83500D02*
X96050Y84042D01*
X96175Y84500D01*
X96342Y84917D01*
X96550Y85375D01*
X96883Y86000D01*
X95217D01*
G01X98233Y83875D02*
X98483Y83667D01*
X98775Y83542D01*
X99150Y83500D01*
X99525Y83583D01*
X99817Y83750D01*
X100025Y84042D01*
X100067Y84375D01*
X99983Y84708D01*
X99775Y84917D01*
X99483Y85083D01*
X99192Y85125D01*
X98900Y85083D01*
X98525Y84917D01*
X98650Y86000D01*
X99775D01*
G01X94000Y87517D02*
X91500D01*
Y88517D01*
X91625Y88850D01*
X91917Y89100D01*
X92250Y89183D01*
X92583Y89100D01*
X92833Y88892D01*
X92958Y88517D01*
Y87517D01*
G01X91708Y92367D02*
X91583Y92117D01*
X91500Y91825D01*
Y91492D01*
X91625Y91117D01*
X91833Y90825D01*
X92083Y90617D01*
X92500Y90450D01*
X92875Y90408D01*
X93250Y90492D01*
X93500Y90617D01*
X93750Y90867D01*
X93917Y91158D01*
X94000Y91450D01*
Y91742D01*
X93917Y92033D01*
X93792Y92283D01*
X93625Y92492D01*
G01Y93633D02*
X93833Y93883D01*
X93958Y94175D01*
X94000Y94550D01*
X93917Y94925D01*
X93750Y95217D01*
X93458Y95425D01*
X93125Y95467D01*
X92792Y95383D01*
X92583Y95175D01*
X92417Y94883D01*
X92375Y94592D01*
X92417Y94300D01*
X92583Y93925D01*
X91500Y94050D01*
Y95175D01*
G01Y97650D02*
X91583Y97317D01*
X91792Y97067D01*
X92042Y96900D01*
X92375Y96775D01*
X92750Y96733D01*
X93125Y96775D01*
X93458Y96900D01*
X93708Y97067D01*
X93917Y97317D01*
X94000Y97650D01*
X93917Y97983D01*
X93708Y98233D01*
X93458Y98400D01*
X93125Y98525D01*
X92750Y98567D01*
X92375Y98525D01*
X92042Y98400D01*
X91792Y98233D01*
X91583Y97983D01*
X91500Y97650D01*
G01X88967Y79500D02*
Y82000D01*
X89967D01*
X90300Y81875D01*
X90550Y81583D01*
X90633Y81250D01*
X90550Y80917D01*
X90342Y80667D01*
X89967Y80542D01*
X88967D01*
G01X92067Y79500D02*
Y82000D01*
X93108D01*
X93442Y81875D01*
X93650Y81708D01*
X93733Y81375D01*
X93650Y81042D01*
X93400Y80833D01*
X93108Y80708D01*
X92067D01*
G01X93108D02*
X93733Y79500D01*
G01X96000D02*
Y82000D01*
X95500Y81500D01*
G01Y79500D02*
X96500D01*
G01X99100Y82000D02*
X98767Y81917D01*
X98517Y81708D01*
X98350Y81458D01*
X98225Y81125D01*
X98183Y80750D01*
X98225Y80375D01*
X98350Y80042D01*
X98517Y79792D01*
X98767Y79583D01*
X99100Y79500D01*
X99433Y79583D01*
X99683Y79792D01*
X99850Y80042D01*
X99975Y80375D01*
X100017Y80750D01*
X99975Y81125D01*
X99850Y81458D01*
X99683Y81708D01*
X99433Y81917D01*
X99100Y82000D01*
G01X101283Y80000D02*
X101533Y79708D01*
X101867Y79542D01*
X102242Y79500D01*
X102575Y79542D01*
X102908Y79750D01*
X103117Y80000D01*
X103158Y80250D01*
X103075Y80542D01*
X102783Y80750D01*
X102492Y80833D01*
X102117D01*
G01X102492D02*
X102742Y80958D01*
X102950Y81167D01*
X103033Y81417D01*
X102950Y81667D01*
X102742Y81875D01*
X102367Y82000D01*
X101992Y81958D01*
X101617Y81792D01*
G01X87500Y90567D02*
X85000D01*
Y91567D01*
X85125Y91900D01*
X85417Y92150D01*
X85750Y92233D01*
X86083Y92150D01*
X86333Y91942D01*
X86458Y91567D01*
Y90567D01*
G01X85000Y93667D02*
X87500D01*
Y95333D01*
G01X87125Y96683D02*
X87333Y96933D01*
X87458Y97225D01*
X87500Y97600D01*
X87417Y97975D01*
X87250Y98267D01*
X86958Y98475D01*
X86625Y98517D01*
X86292Y98433D01*
X86083Y98225D01*
X85917Y97933D01*
X85875Y97642D01*
X85917Y97350D01*
X86083Y96975D01*
X85000Y97100D01*
Y98225D01*
G01X81000Y128000D02*
X100500D01*
Y122000D01*
G01X90017Y156500D02*
Y159000D01*
X91017D01*
X91350Y158875D01*
X91600Y158583D01*
X91683Y158250D01*
X91600Y157917D01*
X91392Y157667D01*
X91017Y157542D01*
X90017D01*
G01X94867Y158792D02*
X94617Y158917D01*
X94325Y159000D01*
X93992D01*
X93617Y158875D01*
X93325Y158667D01*
X93117Y158417D01*
X92950Y158000D01*
X92908Y157625D01*
X92992Y157250D01*
X93117Y157000D01*
X93367Y156750D01*
X93658Y156583D01*
X93950Y156500D01*
X94242D01*
X94533Y156583D01*
X94783Y156708D01*
X94992Y156875D01*
G01X97050Y156500D02*
X97342Y156542D01*
X97675Y156667D01*
X97883Y156875D01*
X97967Y157167D01*
X97883Y157458D01*
X97633Y157708D01*
X97258Y157833D01*
X96842D01*
X96592Y157917D01*
X96383Y158125D01*
X96300Y158417D01*
X96425Y158708D01*
X96717Y158917D01*
X97050Y159000D01*
X97383Y158917D01*
X97675Y158708D01*
X97800Y158417D01*
X97717Y158125D01*
X97508Y157917D01*
X97258Y157833D01*
X96842D01*
X96467Y157708D01*
X96217Y157458D01*
X96133Y157167D01*
X96217Y156875D01*
X96425Y156667D01*
X96758Y156542D01*
X97050Y156500D01*
G01X100150Y159000D02*
X99817Y158917D01*
X99567Y158708D01*
X99400Y158458D01*
X99275Y158125D01*
X99233Y157750D01*
X99275Y157375D01*
X99400Y157042D01*
X99567Y156792D01*
X99817Y156583D01*
X100150Y156500D01*
X100483Y156583D01*
X100733Y156792D01*
X100900Y157042D01*
X101025Y157375D01*
X101067Y157750D01*
X101025Y158125D01*
X100900Y158458D01*
X100733Y158708D01*
X100483Y158917D01*
X100150Y159000D01*
G01X89000Y169467D02*
X86500D01*
Y170467D01*
X86625Y170800D01*
X86917Y171050D01*
X87250Y171133D01*
X87583Y171050D01*
X87833Y170842D01*
X87958Y170467D01*
Y169467D01*
G01X86708Y174317D02*
X86583Y174067D01*
X86500Y173775D01*
Y173442D01*
X86625Y173067D01*
X86833Y172775D01*
X87083Y172567D01*
X87500Y172400D01*
X87875Y172358D01*
X88250Y172442D01*
X88500Y172567D01*
X88750Y172817D01*
X88917Y173108D01*
X89000Y173400D01*
Y173692D01*
X88917Y173983D01*
X88792Y174233D01*
X88625Y174442D01*
G01X89000Y176500D02*
X86500D01*
X87000Y176000D01*
G01X89000D02*
Y177000D01*
G01X88625Y178683D02*
X88833Y178933D01*
X88958Y179225D01*
X89000Y179600D01*
X88917Y179975D01*
X88750Y180267D01*
X88458Y180475D01*
X88125Y180517D01*
X87792Y180433D01*
X87583Y180225D01*
X87417Y179933D01*
X87375Y179642D01*
X87417Y179350D01*
X87583Y178975D01*
X86500Y179100D01*
Y180225D01*
G01Y182700D02*
X86583Y182367D01*
X86792Y182117D01*
X87042Y181950D01*
X87375Y181825D01*
X87750Y181783D01*
X88125Y181825D01*
X88458Y181950D01*
X88708Y182117D01*
X88917Y182367D01*
X89000Y182700D01*
X88917Y183033D01*
X88708Y183283D01*
X88458Y183450D01*
X88125Y183575D01*
X87750Y183617D01*
X87375Y183575D01*
X87042Y183450D01*
X86792Y183283D01*
X86583Y183033D01*
X86500Y182700D01*
G01X93000Y179017D02*
X90500D01*
Y180017D01*
X90625Y180350D01*
X90917Y180600D01*
X91250Y180683D01*
X91583Y180600D01*
X91833Y180392D01*
X91958Y180017D01*
Y179017D01*
G01X93000Y182117D02*
X90500D01*
Y183158D01*
X90625Y183492D01*
X90792Y183700D01*
X91125Y183783D01*
X91458Y183700D01*
X91667Y183450D01*
X91792Y183158D01*
Y182117D01*
G01Y183158D02*
X93000Y183783D01*
G01Y186050D02*
X92958Y186342D01*
X92833Y186675D01*
X92625Y186883D01*
X92333Y186967D01*
X92042Y186883D01*
X91792Y186633D01*
X91667Y186258D01*
Y185842D01*
X91583Y185592D01*
X91375Y185383D01*
X91083Y185300D01*
X90792Y185425D01*
X90583Y185717D01*
X90500Y186050D01*
X90583Y186383D01*
X90792Y186675D01*
X91083Y186800D01*
X91375Y186717D01*
X91583Y186508D01*
X91667Y186258D01*
Y185842D01*
X91792Y185467D01*
X92042Y185217D01*
X92333Y185133D01*
X92625Y185217D01*
X92833Y185425D01*
X92958Y185758D01*
X93000Y186050D01*
G01Y189150D02*
X90500D01*
X91000Y188650D01*
G01X93000D02*
Y189650D01*
G01X85500Y169467D02*
X83000D01*
Y170467D01*
X83125Y170800D01*
X83417Y171050D01*
X83750Y171133D01*
X84083Y171050D01*
X84333Y170842D01*
X84458Y170467D01*
Y169467D01*
G01X83208Y174317D02*
X83083Y174067D01*
X83000Y173775D01*
Y173442D01*
X83125Y173067D01*
X83333Y172775D01*
X83583Y172567D01*
X84000Y172400D01*
X84375Y172358D01*
X84750Y172442D01*
X85000Y172567D01*
X85250Y172817D01*
X85417Y173108D01*
X85500Y173400D01*
Y173692D01*
X85417Y173983D01*
X85292Y174233D01*
X85125Y174442D01*
G01X85500Y176500D02*
X83000D01*
X83500Y176000D01*
G01X85500D02*
Y177000D01*
G01Y180100D02*
X83000D01*
X84792Y178558D01*
Y180642D01*
G01X85208Y181992D02*
X85417Y182283D01*
X85500Y182617D01*
X85417Y182950D01*
X85167Y183242D01*
X84792Y183450D01*
X84417Y183533D01*
X83958D01*
X83583Y183450D01*
X83250Y183242D01*
X83083Y182992D01*
X83000Y182700D01*
X83083Y182367D01*
X83250Y182117D01*
X83500Y181950D01*
X83833Y181867D01*
X84125Y181950D01*
X84417Y182158D01*
X84583Y182408D01*
X84625Y182700D01*
X84542Y183033D01*
X84333Y183283D01*
X83958Y183533D01*
G01X100000Y198500D02*
X94500D01*
Y195000D01*
X87000D01*
Y192000D01*
X81000D01*
G01X91500Y275017D02*
X89000D01*
Y276017D01*
X89125Y276350D01*
X89417Y276600D01*
X89750Y276683D01*
X90083Y276600D01*
X90333Y276392D01*
X90458Y276017D01*
Y275017D01*
G01X91500Y278117D02*
X89000D01*
Y279158D01*
X89125Y279492D01*
X89292Y279700D01*
X89625Y279783D01*
X89958Y279700D01*
X90167Y279450D01*
X90292Y279158D01*
Y278117D01*
G01Y279158D02*
X91500Y279783D01*
G01X89417Y281258D02*
X89167Y281508D01*
X89042Y281800D01*
X89000Y282133D01*
X89083Y282550D01*
X89292Y282842D01*
X89542Y282925D01*
X89792Y282883D01*
X90000Y282717D01*
X90417Y281883D01*
X90708Y281508D01*
X91125Y281258D01*
X91500Y281175D01*
Y282925D01*
G01X91000Y284233D02*
X91292Y284483D01*
X91458Y284817D01*
X91500Y285192D01*
X91458Y285525D01*
X91250Y285858D01*
X91000Y286067D01*
X90750Y286108D01*
X90458Y286025D01*
X90250Y285733D01*
X90167Y285442D01*
Y285067D01*
G01Y285442D02*
X90042Y285692D01*
X89833Y285900D01*
X89583Y285983D01*
X89333Y285900D01*
X89125Y285692D01*
X89000Y285317D01*
X89042Y284942D01*
X89208Y284567D01*
G01X95500Y275017D02*
X93000D01*
Y276017D01*
X93125Y276350D01*
X93417Y276600D01*
X93750Y276683D01*
X94083Y276600D01*
X94333Y276392D01*
X94458Y276017D01*
Y275017D01*
G01X95500Y278117D02*
X93000D01*
Y279158D01*
X93125Y279492D01*
X93292Y279700D01*
X93625Y279783D01*
X93958Y279700D01*
X94167Y279450D01*
X94292Y279158D01*
Y278117D01*
G01Y279158D02*
X95500Y279783D01*
G01X93417Y281258D02*
X93167Y281508D01*
X93042Y281800D01*
X93000Y282133D01*
X93083Y282550D01*
X93292Y282842D01*
X93542Y282925D01*
X93792Y282883D01*
X94000Y282717D01*
X94417Y281883D01*
X94708Y281508D01*
X95125Y281258D01*
X95500Y281175D01*
Y282925D01*
G01Y285650D02*
X93000D01*
X94792Y284108D01*
Y286192D01*
G01X85900Y277117D02*
X83400D01*
Y278117D01*
X83525Y278450D01*
X83817Y278700D01*
X84150Y278783D01*
X84483Y278700D01*
X84733Y278492D01*
X84858Y278117D01*
Y277117D01*
G01X85900Y280217D02*
X83400D01*
Y281258D01*
X83525Y281592D01*
X83692Y281800D01*
X84025Y281883D01*
X84358Y281800D01*
X84567Y281550D01*
X84692Y281258D01*
Y280217D01*
G01Y281258D02*
X85900Y281883D01*
G01Y284150D02*
X83400D01*
X83900Y283650D01*
G01X85900D02*
Y284650D01*
G01Y287250D02*
X85858Y287542D01*
X85733Y287875D01*
X85525Y288083D01*
X85233Y288167D01*
X84942Y288083D01*
X84692Y287833D01*
X84567Y287458D01*
Y287042D01*
X84483Y286792D01*
X84275Y286583D01*
X83983Y286500D01*
X83692Y286625D01*
X83483Y286917D01*
X83400Y287250D01*
X83483Y287583D01*
X83692Y287875D01*
X83983Y288000D01*
X84275Y287917D01*
X84483Y287708D01*
X84567Y287458D01*
Y287042D01*
X84692Y286667D01*
X84942Y286417D01*
X85233Y286333D01*
X85525Y286417D01*
X85733Y286625D01*
X85858Y286958D01*
X85900Y287250D01*
G01X81900Y277117D02*
X79400D01*
Y278117D01*
X79525Y278450D01*
X79817Y278700D01*
X80150Y278783D01*
X80483Y278700D01*
X80733Y278492D01*
X80858Y278117D01*
Y277117D01*
G01X81900Y280217D02*
X79400D01*
Y281258D01*
X79525Y281592D01*
X79692Y281800D01*
X80025Y281883D01*
X80358Y281800D01*
X80567Y281550D01*
X80692Y281258D01*
Y280217D01*
G01Y281258D02*
X81900Y281883D01*
G01Y284150D02*
X79400D01*
X79900Y283650D01*
G01X81900D02*
Y284650D01*
G01Y287167D02*
X81358Y287250D01*
X80900Y287375D01*
X80483Y287542D01*
X80025Y287750D01*
X79400Y288083D01*
Y286417D01*
G01X101500Y36000D02*
X104000D01*
Y56500D01*
X109000D01*
G01X95708Y39267D02*
X95583Y39017D01*
X95500Y38725D01*
Y38392D01*
X95625Y38017D01*
X95833Y37725D01*
X96083Y37517D01*
X96500Y37350D01*
X96875Y37308D01*
X97250Y37392D01*
X97500Y37517D01*
X97750Y37767D01*
X97917Y38058D01*
X98000Y38350D01*
Y38642D01*
X97917Y38933D01*
X97792Y39183D01*
X97625Y39392D01*
G01X98000Y41450D02*
X95500D01*
X96000Y40950D01*
G01X98000D02*
Y41950D01*
G01X95917Y43758D02*
X95667Y44008D01*
X95542Y44300D01*
X95500Y44633D01*
X95583Y45050D01*
X95792Y45342D01*
X96042Y45425D01*
X96292Y45383D01*
X96500Y45217D01*
X96917Y44383D01*
X97208Y44008D01*
X97625Y43758D01*
X98000Y43675D01*
Y45425D01*
G01X95500Y47650D02*
X95583Y47317D01*
X95792Y47067D01*
X96042Y46900D01*
X96375Y46775D01*
X96750Y46733D01*
X97125Y46775D01*
X97458Y46900D01*
X97708Y47067D01*
X97917Y47317D01*
X98000Y47650D01*
X97917Y47983D01*
X97708Y48233D01*
X97458Y48400D01*
X97125Y48525D01*
X96750Y48567D01*
X96375Y48525D01*
X96042Y48400D01*
X95792Y48233D01*
X95583Y47983D01*
X95500Y47650D01*
G01X102500Y37517D02*
X100000D01*
Y38558D01*
X100125Y38892D01*
X100292Y39100D01*
X100625Y39183D01*
X100958Y39100D01*
X101167Y38850D01*
X101292Y38558D01*
Y37517D01*
G01Y38558D02*
X102500Y39183D01*
G01X100417Y40658D02*
X100167Y40908D01*
X100042Y41200D01*
X100000Y41533D01*
X100083Y41950D01*
X100292Y42242D01*
X100542Y42325D01*
X100792Y42283D01*
X101000Y42117D01*
X101417Y41283D01*
X101708Y40908D01*
X102125Y40658D01*
X102500Y40575D01*
Y42325D01*
G01Y44467D02*
X101958Y44550D01*
X101500Y44675D01*
X101083Y44842D01*
X100625Y45050D01*
X100000Y45383D01*
Y43717D01*
G01X102500Y48150D02*
X100000D01*
X101792Y46608D01*
Y48692D01*
G01X95500Y66500D02*
Y62500D01*
X117000D01*
Y56500D01*
X109000D01*
G01X104517Y58000D02*
Y60500D01*
X105558D01*
X105892Y60375D01*
X106100Y60208D01*
X106183Y59875D01*
X106100Y59542D01*
X105850Y59333D01*
X105558Y59208D01*
X104517D01*
G01X105558D02*
X106183Y58000D01*
G01X107658Y60083D02*
X107908Y60333D01*
X108200Y60458D01*
X108533Y60500D01*
X108950Y60417D01*
X109242Y60208D01*
X109325Y59958D01*
X109283Y59708D01*
X109117Y59500D01*
X108283Y59083D01*
X107908Y58792D01*
X107658Y58375D01*
X107575Y58000D01*
X109325D01*
G01X110758Y59042D02*
X111050Y59333D01*
X111300Y59500D01*
X111633Y59583D01*
X111925Y59500D01*
X112133Y59333D01*
X112300Y59083D01*
X112342Y58792D01*
X112300Y58542D01*
X112133Y58292D01*
X111883Y58083D01*
X111592Y58000D01*
X111258Y58083D01*
X110967Y58333D01*
X110800Y58708D01*
X110758Y59125D01*
X110842Y59667D01*
X110967Y59958D01*
X111175Y60250D01*
X111467Y60458D01*
X111758Y60500D01*
X112050Y60417D01*
X112258Y60208D01*
G01X114650Y58000D02*
X114942Y58042D01*
X115275Y58167D01*
X115483Y58375D01*
X115567Y58667D01*
X115483Y58958D01*
X115233Y59208D01*
X114858Y59333D01*
X114442D01*
X114192Y59417D01*
X113983Y59625D01*
X113900Y59917D01*
X114025Y60208D01*
X114317Y60417D01*
X114650Y60500D01*
X114983Y60417D01*
X115275Y60208D01*
X115400Y59917D01*
X115317Y59625D01*
X115108Y59417D01*
X114858Y59333D01*
X114442D01*
X114067Y59208D01*
X113817Y58958D01*
X113733Y58667D01*
X113817Y58375D01*
X114025Y58167D01*
X114358Y58042D01*
X114650Y58000D01*
G01X98500Y87517D02*
X96000D01*
Y88517D01*
X96125Y88850D01*
X96417Y89100D01*
X96750Y89183D01*
X97083Y89100D01*
X97333Y88892D01*
X97458Y88517D01*
Y87517D01*
G01X98500Y90617D02*
X96000D01*
Y91658D01*
X96125Y91992D01*
X96292Y92200D01*
X96625Y92283D01*
X96958Y92200D01*
X97167Y91950D01*
X97292Y91658D01*
Y90617D01*
G01Y91658D02*
X98500Y92283D01*
G01Y94467D02*
X97958Y94550D01*
X97500Y94675D01*
X97083Y94842D01*
X96625Y95050D01*
X96000Y95383D01*
Y93717D01*
G01X98208Y96942D02*
X98417Y97233D01*
X98500Y97567D01*
X98417Y97900D01*
X98167Y98192D01*
X97792Y98400D01*
X97417Y98483D01*
X96958D01*
X96583Y98400D01*
X96250Y98192D01*
X96083Y97942D01*
X96000Y97650D01*
X96083Y97317D01*
X96250Y97067D01*
X96500Y96900D01*
X96833Y96817D01*
X97125Y96900D01*
X97417Y97108D01*
X97583Y97358D01*
X97625Y97650D01*
X97542Y97983D01*
X97333Y98233D01*
X96958Y98483D01*
G01X109025Y79333D02*
X109358Y79125D01*
X109733Y79000D01*
X110067D01*
X110400Y79125D01*
X110650Y79333D01*
X110775Y79625D01*
X110692Y79917D01*
X110483Y80167D01*
X110108Y80333D01*
X109608Y80417D01*
X109317Y80583D01*
X109192Y80875D01*
X109275Y81167D01*
X109483Y81375D01*
X109775Y81500D01*
X110067D01*
X110358Y81417D01*
X110608Y81208D01*
G01X111750Y81500D02*
X112333Y79000D01*
X113000Y81500D01*
X113667Y79000D01*
X114250Y81500D01*
G01X115183Y79500D02*
X115433Y79208D01*
X115767Y79042D01*
X116142Y79000D01*
X116475Y79042D01*
X116808Y79250D01*
X117017Y79500D01*
X117058Y79750D01*
X116975Y80042D01*
X116683Y80250D01*
X116392Y80333D01*
X116017D01*
G01X116392D02*
X116642Y80458D01*
X116850Y80667D01*
X116933Y80917D01*
X116850Y81167D01*
X116642Y81375D01*
X116267Y81500D01*
X115892Y81458D01*
X115517Y81292D01*
G01X100500Y122000D02*
X118000D01*
G01X99217Y136000D02*
Y138500D01*
X100217D01*
X100550Y138375D01*
X100800Y138083D01*
X100883Y137750D01*
X100800Y137417D01*
X100592Y137167D01*
X100217Y137042D01*
X99217D01*
G01X104067Y138292D02*
X103817Y138417D01*
X103525Y138500D01*
X103192D01*
X102817Y138375D01*
X102525Y138167D01*
X102317Y137917D01*
X102150Y137500D01*
X102108Y137125D01*
X102192Y136750D01*
X102317Y136500D01*
X102567Y136250D01*
X102858Y136083D01*
X103150Y136000D01*
X103442D01*
X103733Y136083D01*
X103983Y136208D01*
X104192Y136375D01*
G01X106167Y136000D02*
X106250Y136542D01*
X106375Y137000D01*
X106542Y137417D01*
X106750Y137875D01*
X107083Y138500D01*
X105417D01*
G01X109267Y136000D02*
X109350Y136542D01*
X109475Y137000D01*
X109642Y137417D01*
X109850Y137875D01*
X110183Y138500D01*
X108517D01*
G01X107117Y158000D02*
Y160500D01*
X108117D01*
X108450Y160375D01*
X108700Y160083D01*
X108783Y159750D01*
X108700Y159417D01*
X108492Y159167D01*
X108117Y159042D01*
X107117D01*
G01X110217Y158000D02*
Y160500D01*
X111258D01*
X111592Y160375D01*
X111800Y160208D01*
X111883Y159875D01*
X111800Y159542D01*
X111550Y159333D01*
X111258Y159208D01*
X110217D01*
G01X111258D02*
X111883Y158000D01*
G01X113358Y160083D02*
X113608Y160333D01*
X113900Y160458D01*
X114233Y160500D01*
X114650Y160417D01*
X114942Y160208D01*
X115025Y159958D01*
X114983Y159708D01*
X114817Y159500D01*
X113983Y159083D01*
X113608Y158792D01*
X113358Y158375D01*
X113275Y158000D01*
X115025D01*
G01X117250Y160500D02*
X116917Y160417D01*
X116667Y160208D01*
X116500Y159958D01*
X116375Y159625D01*
X116333Y159250D01*
X116375Y158875D01*
X116500Y158542D01*
X116667Y158292D01*
X116917Y158083D01*
X117250Y158000D01*
X117583Y158083D01*
X117833Y158292D01*
X118000Y158542D01*
X118125Y158875D01*
X118167Y159250D01*
X118125Y159625D01*
X118000Y159958D01*
X117833Y160208D01*
X117583Y160417D01*
X117250Y160500D01*
G01X120350D02*
X120017Y160417D01*
X119767Y160208D01*
X119600Y159958D01*
X119475Y159625D01*
X119433Y159250D01*
X119475Y158875D01*
X119600Y158542D01*
X119767Y158292D01*
X120017Y158083D01*
X120350Y158000D01*
X120683Y158083D01*
X120933Y158292D01*
X121100Y158542D01*
X121225Y158875D01*
X121267Y159250D01*
X121225Y159625D01*
X121100Y159958D01*
X120933Y160208D01*
X120683Y160417D01*
X120350Y160500D01*
G01X97000Y178517D02*
X94500D01*
Y179517D01*
X94625Y179850D01*
X94917Y180100D01*
X95250Y180183D01*
X95583Y180100D01*
X95833Y179892D01*
X95958Y179517D01*
Y178517D01*
G01X94708Y183367D02*
X94583Y183117D01*
X94500Y182825D01*
Y182492D01*
X94625Y182117D01*
X94833Y181825D01*
X95083Y181617D01*
X95500Y181450D01*
X95875Y181408D01*
X96250Y181492D01*
X96500Y181617D01*
X96750Y181867D01*
X96917Y182158D01*
X97000Y182450D01*
Y182742D01*
X96917Y183033D01*
X96792Y183283D01*
X96625Y183492D01*
G01Y184633D02*
X96833Y184883D01*
X96958Y185175D01*
X97000Y185550D01*
X96917Y185925D01*
X96750Y186217D01*
X96458Y186425D01*
X96125Y186467D01*
X95792Y186383D01*
X95583Y186175D01*
X95417Y185883D01*
X95375Y185592D01*
X95417Y185300D01*
X95583Y184925D01*
X94500Y185050D01*
Y186175D01*
G01X97000Y189150D02*
X94500D01*
X96292Y187608D01*
Y189692D01*
G01X108817Y170500D02*
Y173000D01*
X109817D01*
X110150Y172875D01*
X110400Y172583D01*
X110483Y172250D01*
X110400Y171917D01*
X110192Y171667D01*
X109817Y171542D01*
X108817D01*
G01X111917Y170500D02*
Y173000D01*
X112958D01*
X113292Y172875D01*
X113500Y172708D01*
X113583Y172375D01*
X113500Y172042D01*
X113250Y171833D01*
X112958Y171708D01*
X111917D01*
G01X112958D02*
X113583Y170500D01*
G01X115850D02*
Y173000D01*
X115350Y172500D01*
G01Y170500D02*
X116350D01*
G01X118242Y170792D02*
X118533Y170583D01*
X118867Y170500D01*
X119200Y170583D01*
X119492Y170833D01*
X119700Y171208D01*
X119783Y171583D01*
Y172042D01*
X119700Y172417D01*
X119492Y172750D01*
X119242Y172917D01*
X118950Y173000D01*
X118617Y172917D01*
X118367Y172750D01*
X118200Y172500D01*
X118117Y172167D01*
X118200Y171875D01*
X118408Y171583D01*
X118658Y171417D01*
X118950Y171375D01*
X119283Y171458D01*
X119533Y171667D01*
X119783Y172042D01*
G01X122050Y170500D02*
Y173000D01*
X121550Y172500D01*
G01Y170500D02*
X122550D01*
G01X108467Y174500D02*
Y177000D01*
X109467D01*
X109800Y176875D01*
X110050Y176583D01*
X110133Y176250D01*
X110050Y175917D01*
X109842Y175667D01*
X109467Y175542D01*
X108467D01*
G01X111567Y174500D02*
Y177000D01*
X112608D01*
X112942Y176875D01*
X113150Y176708D01*
X113233Y176375D01*
X113150Y176042D01*
X112900Y175833D01*
X112608Y175708D01*
X111567D01*
G01X112608D02*
X113233Y174500D01*
G01X115500D02*
Y177000D01*
X115000Y176500D01*
G01Y174500D02*
X116000D01*
G01X117892Y174792D02*
X118183Y174583D01*
X118517Y174500D01*
X118850Y174583D01*
X119142Y174833D01*
X119350Y175208D01*
X119433Y175583D01*
Y176042D01*
X119350Y176417D01*
X119142Y176750D01*
X118892Y176917D01*
X118600Y177000D01*
X118267Y176917D01*
X118017Y176750D01*
X117850Y176500D01*
X117767Y176167D01*
X117850Y175875D01*
X118058Y175583D01*
X118308Y175417D01*
X118600Y175375D01*
X118933Y175458D01*
X119183Y175667D01*
X119433Y176042D01*
G01X122200Y174500D02*
Y177000D01*
X120658Y175208D01*
X122742D01*
G01X108517Y178500D02*
Y181000D01*
X109517D01*
X109850Y180875D01*
X110100Y180583D01*
X110183Y180250D01*
X110100Y179917D01*
X109892Y179667D01*
X109517Y179542D01*
X108517D01*
G01X111617Y178500D02*
Y181000D01*
X112658D01*
X112992Y180875D01*
X113200Y180708D01*
X113283Y180375D01*
X113200Y180042D01*
X112950Y179833D01*
X112658Y179708D01*
X111617D01*
G01X112658D02*
X113283Y178500D01*
G01X114842Y178792D02*
X115133Y178583D01*
X115467Y178500D01*
X115800Y178583D01*
X116092Y178833D01*
X116300Y179208D01*
X116383Y179583D01*
Y180042D01*
X116300Y180417D01*
X116092Y180750D01*
X115842Y180917D01*
X115550Y181000D01*
X115217Y180917D01*
X114967Y180750D01*
X114800Y180500D01*
X114717Y180167D01*
X114800Y179875D01*
X115008Y179583D01*
X115258Y179417D01*
X115550Y179375D01*
X115883Y179458D01*
X116133Y179667D01*
X116383Y180042D01*
G01X117733Y178875D02*
X117983Y178667D01*
X118275Y178542D01*
X118650Y178500D01*
X119025Y178583D01*
X119317Y178750D01*
X119525Y179042D01*
X119567Y179375D01*
X119483Y179708D01*
X119275Y179917D01*
X118983Y180083D01*
X118692Y180125D01*
X118400Y180083D01*
X118025Y179917D01*
X118150Y181000D01*
X119275D01*
G01X99017Y183500D02*
Y186000D01*
X100017D01*
X100350Y185875D01*
X100600Y185583D01*
X100683Y185250D01*
X100600Y184917D01*
X100392Y184667D01*
X100017Y184542D01*
X99017D01*
G01X103867Y185792D02*
X103617Y185917D01*
X103325Y186000D01*
X102992D01*
X102617Y185875D01*
X102325Y185667D01*
X102117Y185417D01*
X101950Y185000D01*
X101908Y184625D01*
X101992Y184250D01*
X102117Y184000D01*
X102367Y183750D01*
X102658Y183583D01*
X102950Y183500D01*
X103242D01*
X103533Y183583D01*
X103783Y183708D01*
X103992Y183875D01*
G01X105967Y183500D02*
X106050Y184042D01*
X106175Y184500D01*
X106342Y184917D01*
X106550Y185375D01*
X106883Y186000D01*
X105217D01*
G01X108233Y184000D02*
X108483Y183708D01*
X108817Y183542D01*
X109192Y183500D01*
X109525Y183542D01*
X109858Y183750D01*
X110067Y184000D01*
X110108Y184250D01*
X110025Y184542D01*
X109733Y184750D01*
X109442Y184833D01*
X109067D01*
G01X109442D02*
X109692Y184958D01*
X109900Y185167D01*
X109983Y185417D01*
X109900Y185667D01*
X109692Y185875D01*
X109317Y186000D01*
X108942Y185958D01*
X108567Y185792D01*
G01X110500Y196017D02*
X108000D01*
Y197017D01*
X108125Y197350D01*
X108417Y197600D01*
X108750Y197683D01*
X109083Y197600D01*
X109333Y197392D01*
X109458Y197017D01*
Y196017D01*
G01X110500Y199117D02*
X108000D01*
Y200158D01*
X108125Y200492D01*
X108292Y200700D01*
X108625Y200783D01*
X108958Y200700D01*
X109167Y200450D01*
X109292Y200158D01*
Y199117D01*
G01Y200158D02*
X110500Y200783D01*
G01Y202967D02*
X109958Y203050D01*
X109500Y203175D01*
X109083Y203342D01*
X108625Y203550D01*
X108000Y203883D01*
Y202217D01*
G01X110000Y205233D02*
X110292Y205483D01*
X110458Y205817D01*
X110500Y206192D01*
X110458Y206525D01*
X110250Y206858D01*
X110000Y207067D01*
X109750Y207108D01*
X109458Y207025D01*
X109250Y206733D01*
X109167Y206442D01*
Y206067D01*
G01Y206442D02*
X109042Y206692D01*
X108833Y206900D01*
X108583Y206983D01*
X108333Y206900D01*
X108125Y206692D01*
X108000Y206317D01*
X108042Y205942D01*
X108208Y205567D01*
G01X101500Y210500D02*
X112000D01*
Y212500D01*
X119500D01*
G01X98000Y216000D02*
Y210500D01*
X101500D01*
Y202500D01*
G01X98500Y230000D02*
Y218000D01*
G01Y238000D02*
Y233500D01*
G01X103000Y232000D02*
X114000D01*
Y221000D01*
X118000D01*
G01X99500Y262500D02*
X102000D01*
Y251000D01*
X103500D01*
G01X103017Y275000D02*
Y277500D01*
X104017D01*
X104350Y277375D01*
X104600Y277083D01*
X104683Y276750D01*
X104600Y276417D01*
X104392Y276167D01*
X104017Y276042D01*
X103017D01*
G01X107867Y277292D02*
X107617Y277417D01*
X107325Y277500D01*
X106992D01*
X106617Y277375D01*
X106325Y277167D01*
X106117Y276917D01*
X105950Y276500D01*
X105908Y276125D01*
X105992Y275750D01*
X106117Y275500D01*
X106367Y275250D01*
X106658Y275083D01*
X106950Y275000D01*
X107242D01*
X107533Y275083D01*
X107783Y275208D01*
X107992Y275375D01*
G01X109258Y276042D02*
X109550Y276333D01*
X109800Y276500D01*
X110133Y276583D01*
X110425Y276500D01*
X110633Y276333D01*
X110800Y276083D01*
X110842Y275792D01*
X110800Y275542D01*
X110633Y275292D01*
X110383Y275083D01*
X110092Y275000D01*
X109758Y275083D01*
X109467Y275333D01*
X109300Y275708D01*
X109258Y276125D01*
X109342Y276667D01*
X109467Y276958D01*
X109675Y277250D01*
X109967Y277458D01*
X110258Y277500D01*
X110550Y277417D01*
X110758Y277208D01*
G01X112358Y277083D02*
X112608Y277333D01*
X112900Y277458D01*
X113233Y277500D01*
X113650Y277417D01*
X113942Y277208D01*
X114025Y276958D01*
X113983Y276708D01*
X113817Y276500D01*
X112983Y276083D01*
X112608Y275792D01*
X112358Y275375D01*
X112275Y275000D01*
X114025D01*
G01X103017Y283000D02*
Y285500D01*
X104017D01*
X104350Y285375D01*
X104600Y285083D01*
X104683Y284750D01*
X104600Y284417D01*
X104392Y284167D01*
X104017Y284042D01*
X103017D01*
G01X106117Y283000D02*
Y285500D01*
X107158D01*
X107492Y285375D01*
X107700Y285208D01*
X107783Y284875D01*
X107700Y284542D01*
X107450Y284333D01*
X107158Y284208D01*
X106117D01*
G01X107158D02*
X107783Y283000D01*
G01X109258Y284042D02*
X109550Y284333D01*
X109800Y284500D01*
X110133Y284583D01*
X110425Y284500D01*
X110633Y284333D01*
X110800Y284083D01*
X110842Y283792D01*
X110800Y283542D01*
X110633Y283292D01*
X110383Y283083D01*
X110092Y283000D01*
X109758Y283083D01*
X109467Y283333D01*
X109300Y283708D01*
X109258Y284125D01*
X109342Y284667D01*
X109467Y284958D01*
X109675Y285250D01*
X109967Y285458D01*
X110258Y285500D01*
X110550Y285417D01*
X110758Y285208D01*
G01X113650Y283000D02*
Y285500D01*
X112108Y283708D01*
X114192D01*
G01X103067Y279000D02*
Y281500D01*
X104067D01*
X104400Y281375D01*
X104650Y281083D01*
X104733Y280750D01*
X104650Y280417D01*
X104442Y280167D01*
X104067Y280042D01*
X103067D01*
G01X107000Y279000D02*
X106667Y279042D01*
X106375Y279208D01*
X106125Y279458D01*
X105958Y279750D01*
X105875Y280083D01*
Y280417D01*
X105958Y280750D01*
X106125Y281042D01*
X106375Y281292D01*
X106667Y281458D01*
X107000Y281500D01*
X107333Y281458D01*
X107625Y281292D01*
X107875Y281042D01*
X108042Y280750D01*
X108125Y280417D01*
Y280083D01*
X108042Y279750D01*
X107875Y279458D01*
X107625Y279208D01*
X107333Y279042D01*
X107000Y279000D01*
G01X107333Y279667D02*
X107833Y279000D01*
G01X109308Y281083D02*
X109558Y281333D01*
X109850Y281458D01*
X110183Y281500D01*
X110600Y281417D01*
X110892Y281208D01*
X110975Y280958D01*
X110933Y280708D01*
X110767Y280500D01*
X109933Y280083D01*
X109558Y279792D01*
X109308Y279375D01*
X109225Y279000D01*
X110975D01*
G01X100000Y276067D02*
X97500D01*
Y277067D01*
X97625Y277400D01*
X97917Y277650D01*
X98250Y277733D01*
X98583Y277650D01*
X98833Y277442D01*
X98958Y277067D01*
Y276067D01*
G01X100000Y279083D02*
X97500D01*
Y279917D01*
X97625Y280250D01*
X97792Y280500D01*
X98042Y280708D01*
X98333Y280875D01*
X98750Y280917D01*
X99167Y280875D01*
X99458Y280708D01*
X99708Y280500D01*
X99875Y280250D01*
X100000Y279917D01*
Y279083D01*
G01Y283100D02*
X97500D01*
X98000Y282600D01*
G01X100000D02*
Y283600D01*
G01X127000Y125000D02*
X129000Y123000D01*
Y101500D01*
X126000Y98500D01*
Y79500D01*
X121000Y74500D01*
Y66500D01*
X117000Y62500D01*
Y64500D01*
X119000Y62500D01*
X117000D01*
G01X124500Y93017D02*
X122000D01*
Y94017D01*
X122125Y94350D01*
X122417Y94600D01*
X122750Y94683D01*
X123083Y94600D01*
X123333Y94392D01*
X123458Y94017D01*
Y93017D01*
G01X122000Y96950D02*
X124500D01*
G01X122000Y95992D02*
Y97908D01*
G01X122208Y100967D02*
X122083Y100717D01*
X122000Y100425D01*
Y100092D01*
X122125Y99717D01*
X122333Y99425D01*
X122583Y99217D01*
X123000Y99050D01*
X123375Y99008D01*
X123750Y99092D01*
X124000Y99217D01*
X124250Y99467D01*
X124417Y99758D01*
X124500Y100050D01*
Y100342D01*
X124417Y100633D01*
X124292Y100883D01*
X124125Y101092D01*
G01X124500Y103150D02*
X122000D01*
X122500Y102650D01*
G01X124500D02*
Y103650D01*
G01Y106517D02*
X122000D01*
Y107558D01*
X122125Y107892D01*
X122292Y108100D01*
X122625Y108183D01*
X122958Y108100D01*
X123167Y107850D01*
X123292Y107558D01*
Y106517D01*
G01Y107558D02*
X124500Y108183D01*
G01X122417Y109658D02*
X122167Y109908D01*
X122042Y110200D01*
X122000Y110533D01*
X122083Y110950D01*
X122292Y111242D01*
X122542Y111325D01*
X122792Y111283D01*
X123000Y111117D01*
X123417Y110283D01*
X123708Y109908D01*
X124125Y109658D01*
X124500Y109575D01*
Y111325D01*
G01Y113467D02*
X123958Y113550D01*
X123500Y113675D01*
X123083Y113842D01*
X122625Y114050D01*
X122000Y114383D01*
Y112717D01*
G01X122417Y115858D02*
X122167Y116108D01*
X122042Y116400D01*
X122000Y116733D01*
X122083Y117150D01*
X122292Y117442D01*
X122542Y117525D01*
X122792Y117483D01*
X123000Y117317D01*
X123417Y116483D01*
X123708Y116108D01*
X124125Y115858D01*
X124500Y115775D01*
Y117525D01*
G01X118000Y122000D02*
Y125000D01*
X127000D01*
Y133000D01*
X129000D01*
Y137500D01*
G01X120550Y136017D02*
X118050D01*
Y137058D01*
X118175Y137392D01*
X118342Y137600D01*
X118675Y137683D01*
X119008Y137600D01*
X119217Y137350D01*
X119342Y137058D01*
Y136017D01*
G01Y137058D02*
X120550Y137683D01*
G01Y140450D02*
X118050D01*
X119842Y138908D01*
Y140992D01*
G01X120550Y143050D02*
X120508Y143342D01*
X120383Y143675D01*
X120175Y143883D01*
X119883Y143967D01*
X119592Y143883D01*
X119342Y143633D01*
X119217Y143258D01*
Y142842D01*
X119133Y142592D01*
X118925Y142383D01*
X118633Y142300D01*
X118342Y142425D01*
X118133Y142717D01*
X118050Y143050D01*
X118133Y143383D01*
X118342Y143675D01*
X118633Y143800D01*
X118925Y143717D01*
X119133Y143508D01*
X119217Y143258D01*
Y142842D01*
X119342Y142467D01*
X119592Y142217D01*
X119883Y142133D01*
X120175Y142217D01*
X120383Y142425D01*
X120508Y142758D01*
X120550Y143050D01*
G01X120258Y145442D02*
X120467Y145733D01*
X120550Y146067D01*
X120467Y146400D01*
X120217Y146692D01*
X119842Y146900D01*
X119467Y146983D01*
X119008D01*
X118633Y146900D01*
X118300Y146692D01*
X118133Y146442D01*
X118050Y146150D01*
X118133Y145817D01*
X118300Y145567D01*
X118550Y145400D01*
X118883Y145317D01*
X119175Y145400D01*
X119467Y145608D01*
X119633Y145858D01*
X119675Y146150D01*
X119592Y146483D01*
X119383Y146733D01*
X119008Y146983D01*
G01X115350Y150150D02*
Y155850D01*
G01X112350Y150150D02*
X115350D01*
G01X112350Y155850D02*
Y150150D01*
G01X115350Y155850D02*
X112350D01*
G01X116000Y162650D02*
Y168350D01*
G01X113000Y162650D02*
X116000D01*
G01X113000Y168350D02*
Y162650D01*
G01X126200Y157117D02*
X123700D01*
Y158158D01*
X123825Y158492D01*
X123992Y158700D01*
X124325Y158783D01*
X124658Y158700D01*
X124867Y158450D01*
X124992Y158158D01*
Y157117D01*
G01Y158158D02*
X126200Y158783D01*
G01Y161550D02*
X123700D01*
X125492Y160008D01*
Y162092D01*
G01X125908Y163442D02*
X126117Y163733D01*
X126200Y164067D01*
X126117Y164400D01*
X125867Y164692D01*
X125492Y164900D01*
X125117Y164983D01*
X124658D01*
X124283Y164900D01*
X123950Y164692D01*
X123783Y164442D01*
X123700Y164150D01*
X123783Y163817D01*
X123950Y163567D01*
X124200Y163400D01*
X124533Y163317D01*
X124825Y163400D01*
X125117Y163608D01*
X125283Y163858D01*
X125325Y164150D01*
X125242Y164483D01*
X125033Y164733D01*
X124658Y164983D01*
G01X126200Y167250D02*
X123700D01*
X124200Y166750D01*
G01X126200D02*
Y167750D01*
G01X114517Y182500D02*
Y185000D01*
X115517D01*
X115850Y184875D01*
X116100Y184583D01*
X116183Y184250D01*
X116100Y183917D01*
X115892Y183667D01*
X115517Y183542D01*
X114517D01*
G01X119367Y184792D02*
X119117Y184917D01*
X118825Y185000D01*
X118492D01*
X118117Y184875D01*
X117825Y184667D01*
X117617Y184417D01*
X117450Y184000D01*
X117408Y183625D01*
X117492Y183250D01*
X117617Y183000D01*
X117867Y182750D01*
X118158Y182583D01*
X118450Y182500D01*
X118742D01*
X119033Y182583D01*
X119283Y182708D01*
X119492Y182875D01*
G01X120758Y183542D02*
X121050Y183833D01*
X121300Y184000D01*
X121633Y184083D01*
X121925Y184000D01*
X122133Y183833D01*
X122300Y183583D01*
X122342Y183292D01*
X122300Y183042D01*
X122133Y182792D01*
X121883Y182583D01*
X121592Y182500D01*
X121258Y182583D01*
X120967Y182833D01*
X120800Y183208D01*
X120758Y183625D01*
X120842Y184167D01*
X120967Y184458D01*
X121175Y184750D01*
X121467Y184958D01*
X121758Y185000D01*
X122050Y184917D01*
X122258Y184708D01*
G01X124650Y182500D02*
X124942Y182542D01*
X125275Y182667D01*
X125483Y182875D01*
X125567Y183167D01*
X125483Y183458D01*
X125233Y183708D01*
X124858Y183833D01*
X124442D01*
X124192Y183917D01*
X123983Y184125D01*
X123900Y184417D01*
X124025Y184708D01*
X124317Y184917D01*
X124650Y185000D01*
X124983Y184917D01*
X125275Y184708D01*
X125400Y184417D01*
X125317Y184125D01*
X125108Y183917D01*
X124858Y183833D01*
X124442D01*
X124067Y183708D01*
X123817Y183458D01*
X123733Y183167D01*
X123817Y182875D01*
X124025Y182667D01*
X124358Y182542D01*
X124650Y182500D01*
G01X116000Y168350D02*
X113000D01*
G01X121517Y178500D02*
Y181000D01*
X122517D01*
X122850Y180875D01*
X123100Y180583D01*
X123183Y180250D01*
X123100Y179917D01*
X122892Y179667D01*
X122517Y179542D01*
X121517D01*
G01X124617Y178500D02*
Y181000D01*
X125658D01*
X125992Y180875D01*
X126200Y180708D01*
X126283Y180375D01*
X126200Y180042D01*
X125950Y179833D01*
X125658Y179708D01*
X124617D01*
G01X125658D02*
X126283Y178500D01*
G01X127758Y179542D02*
X128050Y179833D01*
X128300Y180000D01*
X128633Y180083D01*
X128925Y180000D01*
X129133Y179833D01*
X129300Y179583D01*
X129342Y179292D01*
X129300Y179042D01*
X129133Y178792D01*
X128883Y178583D01*
X128592Y178500D01*
X128258Y178583D01*
X127967Y178833D01*
X127800Y179208D01*
X127758Y179625D01*
X127842Y180167D01*
X127967Y180458D01*
X128175Y180750D01*
X128467Y180958D01*
X128758Y181000D01*
X129050Y180917D01*
X129258Y180708D01*
G01X131650Y178500D02*
X131942Y178542D01*
X132275Y178667D01*
X132483Y178875D01*
X132567Y179167D01*
X132483Y179458D01*
X132233Y179708D01*
X131858Y179833D01*
X131442D01*
X131192Y179917D01*
X130983Y180125D01*
X130900Y180417D01*
X131025Y180708D01*
X131317Y180917D01*
X131650Y181000D01*
X131983Y180917D01*
X132275Y180708D01*
X132400Y180417D01*
X132317Y180125D01*
X132108Y179917D01*
X131858Y179833D01*
X131442D01*
X131067Y179708D01*
X130817Y179458D01*
X130733Y179167D01*
X130817Y178875D01*
X131025Y178667D01*
X131358Y178542D01*
X131650Y178500D01*
G01X114517Y186500D02*
Y189000D01*
X115517D01*
X115850Y188875D01*
X116100Y188583D01*
X116183Y188250D01*
X116100Y187917D01*
X115892Y187667D01*
X115517Y187542D01*
X114517D01*
G01X119367Y188792D02*
X119117Y188917D01*
X118825Y189000D01*
X118492D01*
X118117Y188875D01*
X117825Y188667D01*
X117617Y188417D01*
X117450Y188000D01*
X117408Y187625D01*
X117492Y187250D01*
X117617Y187000D01*
X117867Y186750D01*
X118158Y186583D01*
X118450Y186500D01*
X118742D01*
X119033Y186583D01*
X119283Y186708D01*
X119492Y186875D01*
G01X121467Y186500D02*
X121550Y187042D01*
X121675Y187500D01*
X121842Y187917D01*
X122050Y188375D01*
X122383Y189000D01*
X120717D01*
G01X124650D02*
X124317Y188917D01*
X124067Y188708D01*
X123900Y188458D01*
X123775Y188125D01*
X123733Y187750D01*
X123775Y187375D01*
X123900Y187042D01*
X124067Y186792D01*
X124317Y186583D01*
X124650Y186500D01*
X124983Y186583D01*
X125233Y186792D01*
X125400Y187042D01*
X125525Y187375D01*
X125567Y187750D01*
X125525Y188125D01*
X125400Y188458D01*
X125233Y188708D01*
X124983Y188917D01*
X124650Y189000D01*
G01X123000Y212500D02*
X126000D01*
Y211000D01*
X161500D01*
Y205000D01*
X166000D01*
Y199500D01*
X174500D01*
Y197500D01*
X184500D01*
Y195000D01*
G01X124467Y203000D02*
Y205500D01*
X125467D01*
X125800Y205375D01*
X126050Y205083D01*
X126133Y204750D01*
X126050Y204417D01*
X125842Y204167D01*
X125467Y204042D01*
X124467D01*
G01X129317Y205292D02*
X129067Y205417D01*
X128775Y205500D01*
X128442D01*
X128067Y205375D01*
X127775Y205167D01*
X127567Y204917D01*
X127400Y204500D01*
X127358Y204125D01*
X127442Y203750D01*
X127567Y203500D01*
X127817Y203250D01*
X128108Y203083D01*
X128400Y203000D01*
X128692D01*
X128983Y203083D01*
X129233Y203208D01*
X129442Y203375D01*
G01X131500Y203000D02*
Y205500D01*
X131000Y205000D01*
G01Y203000D02*
X132000D01*
G01X133683Y203500D02*
X133933Y203208D01*
X134267Y203042D01*
X134642Y203000D01*
X134975Y203042D01*
X135308Y203250D01*
X135517Y203500D01*
X135558Y203750D01*
X135475Y204042D01*
X135183Y204250D01*
X134892Y204333D01*
X134517D01*
G01X134892D02*
X135142Y204458D01*
X135350Y204667D01*
X135433Y204917D01*
X135350Y205167D01*
X135142Y205375D01*
X134767Y205500D01*
X134392Y205458D01*
X134017Y205292D01*
G01X137700Y205500D02*
X137367Y205417D01*
X137117Y205208D01*
X136950Y204958D01*
X136825Y204625D01*
X136783Y204250D01*
X136825Y203875D01*
X136950Y203542D01*
X137117Y203292D01*
X137367Y203083D01*
X137700Y203000D01*
X138033Y203083D01*
X138283Y203292D01*
X138450Y203542D01*
X138575Y203875D01*
X138617Y204250D01*
X138575Y204625D01*
X138450Y204958D01*
X138283Y205208D01*
X138033Y205417D01*
X137700Y205500D01*
G01X124467Y207000D02*
Y209500D01*
X125467D01*
X125800Y209375D01*
X126050Y209083D01*
X126133Y208750D01*
X126050Y208417D01*
X125842Y208167D01*
X125467Y208042D01*
X124467D01*
G01X129317Y209292D02*
X129067Y209417D01*
X128775Y209500D01*
X128442D01*
X128067Y209375D01*
X127775Y209167D01*
X127567Y208917D01*
X127400Y208500D01*
X127358Y208125D01*
X127442Y207750D01*
X127567Y207500D01*
X127817Y207250D01*
X128108Y207083D01*
X128400Y207000D01*
X128692D01*
X128983Y207083D01*
X129233Y207208D01*
X129442Y207375D01*
G01X131500Y207000D02*
Y209500D01*
X131000Y209000D01*
G01Y207000D02*
X132000D01*
G01X133808Y209083D02*
X134058Y209333D01*
X134350Y209458D01*
X134683Y209500D01*
X135100Y209417D01*
X135392Y209208D01*
X135475Y208958D01*
X135433Y208708D01*
X135267Y208500D01*
X134433Y208083D01*
X134058Y207792D01*
X133808Y207375D01*
X133725Y207000D01*
X135475D01*
G01X136992Y207292D02*
X137283Y207083D01*
X137617Y207000D01*
X137950Y207083D01*
X138242Y207333D01*
X138450Y207708D01*
X138533Y208083D01*
Y208542D01*
X138450Y208917D01*
X138242Y209250D01*
X137992Y209417D01*
X137700Y209500D01*
X137367Y209417D01*
X137117Y209250D01*
X136950Y209000D01*
X136867Y208667D01*
X136950Y208375D01*
X137158Y208083D01*
X137408Y207917D01*
X137700Y207875D01*
X138033Y207958D01*
X138283Y208167D01*
X138533Y208542D01*
G01X118517Y275500D02*
Y278000D01*
X119517D01*
X119850Y277875D01*
X120100Y277583D01*
X120183Y277250D01*
X120100Y276917D01*
X119892Y276667D01*
X119517Y276542D01*
X118517D01*
G01X123367Y277792D02*
X123117Y277917D01*
X122825Y278000D01*
X122492D01*
X122117Y277875D01*
X121825Y277667D01*
X121617Y277417D01*
X121450Y277000D01*
X121408Y276625D01*
X121492Y276250D01*
X121617Y276000D01*
X121867Y275750D01*
X122158Y275583D01*
X122450Y275500D01*
X122742D01*
X123033Y275583D01*
X123283Y275708D01*
X123492Y275875D01*
G01X125550Y275500D02*
Y278000D01*
X125050Y277500D01*
G01Y275500D02*
X126050D01*
G01X127858Y277583D02*
X128108Y277833D01*
X128400Y277958D01*
X128733Y278000D01*
X129150Y277917D01*
X129442Y277708D01*
X129525Y277458D01*
X129483Y277208D01*
X129317Y277000D01*
X128483Y276583D01*
X128108Y276292D01*
X127858Y275875D01*
X127775Y275500D01*
X129525D01*
G01X118567Y280000D02*
Y282500D01*
X119567D01*
X119900Y282375D01*
X120150Y282083D01*
X120233Y281750D01*
X120150Y281417D01*
X119942Y281167D01*
X119567Y281042D01*
X118567D01*
G01X123417Y282292D02*
X123167Y282417D01*
X122875Y282500D01*
X122542D01*
X122167Y282375D01*
X121875Y282167D01*
X121667Y281917D01*
X121500Y281500D01*
X121458Y281125D01*
X121542Y280750D01*
X121667Y280500D01*
X121917Y280250D01*
X122208Y280083D01*
X122500Y280000D01*
X122792D01*
X123083Y280083D01*
X123333Y280208D01*
X123542Y280375D01*
G01X124808Y281042D02*
X125100Y281333D01*
X125350Y281500D01*
X125683Y281583D01*
X125975Y281500D01*
X126183Y281333D01*
X126350Y281083D01*
X126392Y280792D01*
X126350Y280542D01*
X126183Y280292D01*
X125933Y280083D01*
X125642Y280000D01*
X125308Y280083D01*
X125017Y280333D01*
X124850Y280708D01*
X124808Y281125D01*
X124892Y281667D01*
X125017Y281958D01*
X125225Y282250D01*
X125517Y282458D01*
X125808Y282500D01*
X126100Y282417D01*
X126308Y282208D01*
G01X118567Y285000D02*
Y287500D01*
X119567D01*
X119900Y287375D01*
X120150Y287083D01*
X120233Y286750D01*
X120150Y286417D01*
X119942Y286167D01*
X119567Y286042D01*
X118567D01*
G01X121667Y287500D02*
Y285000D01*
X123333D01*
G01X124683Y285500D02*
X124933Y285208D01*
X125267Y285042D01*
X125642Y285000D01*
X125975Y285042D01*
X126308Y285250D01*
X126517Y285500D01*
X126558Y285750D01*
X126475Y286042D01*
X126183Y286250D01*
X125892Y286333D01*
X125517D01*
G01X125892D02*
X126142Y286458D01*
X126350Y286667D01*
X126433Y286917D01*
X126350Y287167D01*
X126142Y287375D01*
X125767Y287500D01*
X125392Y287458D01*
X125017Y287292D01*
G01X135500Y60517D02*
X133000D01*
Y61558D01*
X133125Y61892D01*
X133292Y62100D01*
X133625Y62183D01*
X133958Y62100D01*
X134167Y61850D01*
X134292Y61558D01*
Y60517D01*
G01Y61558D02*
X135500Y62183D01*
G01X133417Y63658D02*
X133167Y63908D01*
X133042Y64200D01*
X133000Y64533D01*
X133083Y64950D01*
X133292Y65242D01*
X133542Y65325D01*
X133792Y65283D01*
X134000Y65117D01*
X134417Y64283D01*
X134708Y63908D01*
X135125Y63658D01*
X135500Y63575D01*
Y65325D01*
G01X134458Y66758D02*
X134167Y67050D01*
X134000Y67300D01*
X133917Y67633D01*
X134000Y67925D01*
X134167Y68133D01*
X134417Y68300D01*
X134708Y68342D01*
X134958Y68300D01*
X135208Y68133D01*
X135417Y67883D01*
X135500Y67592D01*
X135417Y67258D01*
X135167Y66967D01*
X134792Y66800D01*
X134375Y66758D01*
X133833Y66842D01*
X133542Y66967D01*
X133250Y67175D01*
X133042Y67467D01*
X133000Y67758D01*
X133083Y68050D01*
X133292Y68258D01*
G01X135125Y69733D02*
X135333Y69983D01*
X135458Y70275D01*
X135500Y70650D01*
X135417Y71025D01*
X135250Y71317D01*
X134958Y71525D01*
X134625Y71567D01*
X134292Y71483D01*
X134083Y71275D01*
X133917Y70983D01*
X133875Y70692D01*
X133917Y70400D01*
X134083Y70025D01*
X133000Y70150D01*
Y71275D01*
G01X133708Y79167D02*
X133583Y78917D01*
X133500Y78625D01*
Y78292D01*
X133625Y77917D01*
X133833Y77625D01*
X134083Y77417D01*
X134500Y77250D01*
X134875Y77208D01*
X135250Y77292D01*
X135500Y77417D01*
X135750Y77667D01*
X135917Y77958D01*
X136000Y78250D01*
Y78542D01*
X135917Y78833D01*
X135792Y79083D01*
X135625Y79292D01*
G01X136000Y80392D02*
X133500D01*
X136000Y82308D01*
X133500D01*
G01X136000Y84950D02*
X133500D01*
X135292Y83408D01*
Y85492D01*
G01X136083Y87550D02*
X136042Y87467D01*
X135958D01*
X135917Y87550D01*
X135958Y87633D01*
X136042D01*
X136083Y87550D01*
G01X134958D02*
X134917Y87467D01*
X134833D01*
X134792Y87550D01*
X134833Y87633D01*
X134917D01*
X134958Y87550D01*
G01X136000Y92875D02*
X133500Y94625D01*
G01Y92875D02*
X136000Y94625D01*
G01Y95933D02*
X133500D01*
Y96767D01*
X133625Y97100D01*
X133792Y97350D01*
X134042Y97558D01*
X134333Y97725D01*
X134750Y97767D01*
X135167Y97725D01*
X135458Y97558D01*
X135708Y97350D01*
X135875Y97100D01*
X136000Y96767D01*
Y95933D01*
G01Y99117D02*
X133500D01*
Y100117D01*
X133625Y100450D01*
X133917Y100700D01*
X134250Y100783D01*
X134583Y100700D01*
X134833Y100492D01*
X134958Y100117D01*
Y99117D01*
G01X131000Y84517D02*
X128500D01*
Y85558D01*
X128625Y85892D01*
X128792Y86100D01*
X129125Y86183D01*
X129458Y86100D01*
X129667Y85850D01*
X129792Y85558D01*
Y84517D01*
G01Y85558D02*
X131000Y86183D01*
G01X128917Y87658D02*
X128667Y87908D01*
X128542Y88200D01*
X128500Y88533D01*
X128583Y88950D01*
X128792Y89242D01*
X129042Y89325D01*
X129292Y89283D01*
X129500Y89117D01*
X129917Y88283D01*
X130208Y87908D01*
X130625Y87658D01*
X131000Y87575D01*
Y89325D01*
G01X129958Y90758D02*
X129667Y91050D01*
X129500Y91300D01*
X129417Y91633D01*
X129500Y91925D01*
X129667Y92133D01*
X129917Y92300D01*
X130208Y92342D01*
X130458Y92300D01*
X130708Y92133D01*
X130917Y91883D01*
X131000Y91592D01*
X130917Y91258D01*
X130667Y90967D01*
X130292Y90800D01*
X129875Y90758D01*
X129333Y90842D01*
X129042Y90967D01*
X128750Y91175D01*
X128542Y91467D01*
X128500Y91758D01*
X128583Y92050D01*
X128792Y92258D01*
G01X131000Y95150D02*
X128500D01*
X130292Y93608D01*
Y95692D01*
G01X136000Y123017D02*
X133500D01*
Y124058D01*
X133625Y124392D01*
X133792Y124600D01*
X134125Y124683D01*
X134458Y124600D01*
X134667Y124350D01*
X134792Y124058D01*
Y123017D01*
G01Y124058D02*
X136000Y124683D01*
G01Y127450D02*
X133500D01*
X135292Y125908D01*
Y127992D01*
G01X136000Y129967D02*
X135458Y130050D01*
X135000Y130175D01*
X134583Y130342D01*
X134125Y130550D01*
X133500Y130883D01*
Y129217D01*
G01X133917Y132358D02*
X133667Y132608D01*
X133542Y132900D01*
X133500Y133233D01*
X133583Y133650D01*
X133792Y133942D01*
X134042Y134025D01*
X134292Y133983D01*
X134500Y133817D01*
X134917Y132983D01*
X135208Y132608D01*
X135625Y132358D01*
X136000Y132275D01*
Y134025D01*
G01X152000Y161000D02*
X132000D01*
Y150000D01*
G01X129000Y149000D02*
Y137500D01*
G01X132000Y150500D02*
Y146500D01*
X137500D01*
G01X134708Y139317D02*
X134583Y139067D01*
X134500Y138775D01*
Y138442D01*
X134625Y138067D01*
X134833Y137775D01*
X135083Y137567D01*
X135500Y137400D01*
X135875Y137358D01*
X136250Y137442D01*
X136500Y137567D01*
X136750Y137817D01*
X136917Y138108D01*
X137000Y138400D01*
Y138692D01*
X136917Y138983D01*
X136792Y139233D01*
X136625Y139442D01*
G01X137000Y140542D02*
X134500D01*
X137000Y142458D01*
X134500D01*
G01X137000Y145100D02*
X134500D01*
X136292Y143558D01*
Y145642D01*
G01X136000Y163567D02*
X133500D01*
Y164608D01*
X133625Y164942D01*
X133792Y165150D01*
X134125Y165233D01*
X134458Y165150D01*
X134667Y164900D01*
X134792Y164608D01*
Y163567D01*
G01Y164608D02*
X136000Y165233D01*
G01X134958Y166708D02*
X134667Y167000D01*
X134500Y167250D01*
X134417Y167583D01*
X134500Y167875D01*
X134667Y168083D01*
X134917Y168250D01*
X135208Y168292D01*
X135458Y168250D01*
X135708Y168083D01*
X135917Y167833D01*
X136000Y167542D01*
X135917Y167208D01*
X135667Y166917D01*
X135292Y166750D01*
X134875Y166708D01*
X134333Y166792D01*
X134042Y166917D01*
X133750Y167125D01*
X133542Y167417D01*
X133500Y167708D01*
X133583Y168000D01*
X133792Y168208D01*
G01X135500Y169683D02*
X135792Y169933D01*
X135958Y170267D01*
X136000Y170642D01*
X135958Y170975D01*
X135750Y171308D01*
X135500Y171517D01*
X135250Y171558D01*
X134958Y171475D01*
X134750Y171183D01*
X134667Y170892D01*
Y170517D01*
G01Y170892D02*
X134542Y171142D01*
X134333Y171350D01*
X134083Y171433D01*
X133833Y171350D01*
X133625Y171142D01*
X133500Y170767D01*
X133542Y170392D01*
X133708Y170017D01*
G01X140000Y163567D02*
X137500D01*
Y164608D01*
X137625Y164942D01*
X137792Y165150D01*
X138125Y165233D01*
X138458Y165150D01*
X138667Y164900D01*
X138792Y164608D01*
Y163567D01*
G01Y164608D02*
X140000Y165233D01*
G01X139625Y166583D02*
X139833Y166833D01*
X139958Y167125D01*
X140000Y167500D01*
X139917Y167875D01*
X139750Y168167D01*
X139458Y168375D01*
X139125Y168417D01*
X138792Y168333D01*
X138583Y168125D01*
X138417Y167833D01*
X138375Y167542D01*
X138417Y167250D01*
X138583Y166875D01*
X137500Y167000D01*
Y168125D01*
G01X139708Y169892D02*
X139917Y170183D01*
X140000Y170517D01*
X139917Y170850D01*
X139667Y171142D01*
X139292Y171350D01*
X138917Y171433D01*
X138458D01*
X138083Y171350D01*
X137750Y171142D01*
X137583Y170892D01*
X137500Y170600D01*
X137583Y170267D01*
X137750Y170017D01*
X138000Y169850D01*
X138333Y169767D01*
X138625Y169850D01*
X138917Y170058D01*
X139083Y170308D01*
X139125Y170600D01*
X139042Y170933D01*
X138833Y171183D01*
X138458Y171433D01*
G01X130000Y157017D02*
X127500D01*
Y158058D01*
X127625Y158392D01*
X127792Y158600D01*
X128125Y158683D01*
X128458Y158600D01*
X128667Y158350D01*
X128792Y158058D01*
Y157017D01*
G01Y158058D02*
X130000Y158683D01*
G01Y161450D02*
X127500D01*
X129292Y159908D01*
Y161992D01*
G01X130000Y164050D02*
X129958Y164342D01*
X129833Y164675D01*
X129625Y164883D01*
X129333Y164967D01*
X129042Y164883D01*
X128792Y164633D01*
X128667Y164258D01*
Y163842D01*
X128583Y163592D01*
X128375Y163383D01*
X128083Y163300D01*
X127792Y163425D01*
X127583Y163717D01*
X127500Y164050D01*
X127583Y164383D01*
X127792Y164675D01*
X128083Y164800D01*
X128375Y164717D01*
X128583Y164508D01*
X128667Y164258D01*
Y163842D01*
X128792Y163467D01*
X129042Y163217D01*
X129333Y163133D01*
X129625Y163217D01*
X129833Y163425D01*
X129958Y163758D01*
X130000Y164050D01*
G01Y167150D02*
X129958Y167442D01*
X129833Y167775D01*
X129625Y167983D01*
X129333Y168067D01*
X129042Y167983D01*
X128792Y167733D01*
X128667Y167358D01*
Y166942D01*
X128583Y166692D01*
X128375Y166483D01*
X128083Y166400D01*
X127792Y166525D01*
X127583Y166817D01*
X127500Y167150D01*
X127583Y167483D01*
X127792Y167775D01*
X128083Y167900D01*
X128375Y167817D01*
X128583Y167608D01*
X128667Y167358D01*
Y166942D01*
X128792Y166567D01*
X129042Y166317D01*
X129333Y166233D01*
X129625Y166317D01*
X129833Y166525D01*
X129958Y166858D01*
X130000Y167150D01*
G01X137100Y186317D02*
X134600D01*
Y187358D01*
X134725Y187692D01*
X134892Y187900D01*
X135225Y187983D01*
X135558Y187900D01*
X135767Y187650D01*
X135892Y187358D01*
Y186317D01*
G01Y187358D02*
X137100Y187983D01*
G01Y190250D02*
X134600D01*
X135100Y189750D01*
G01X137100D02*
Y190750D01*
G01X136600Y192433D02*
X136892Y192683D01*
X137058Y193017D01*
X137100Y193392D01*
X137058Y193725D01*
X136850Y194058D01*
X136600Y194267D01*
X136350Y194308D01*
X136058Y194225D01*
X135850Y193933D01*
X135767Y193642D01*
Y193267D01*
G01Y193642D02*
X135642Y193892D01*
X135433Y194100D01*
X135183Y194183D01*
X134933Y194100D01*
X134725Y193892D01*
X134600Y193517D01*
X134642Y193142D01*
X134808Y192767D01*
G01X135017Y195658D02*
X134767Y195908D01*
X134642Y196200D01*
X134600Y196533D01*
X134683Y196950D01*
X134892Y197242D01*
X135142Y197325D01*
X135392Y197283D01*
X135600Y197117D01*
X136017Y196283D01*
X136308Y195908D01*
X136725Y195658D01*
X137100Y195575D01*
Y197325D01*
G01X138708Y187817D02*
X138583Y187567D01*
X138500Y187275D01*
Y186942D01*
X138625Y186567D01*
X138833Y186275D01*
X139083Y186067D01*
X139500Y185900D01*
X139875Y185858D01*
X140250Y185942D01*
X140500Y186067D01*
X140750Y186317D01*
X140917Y186608D01*
X141000Y186900D01*
Y187192D01*
X140917Y187483D01*
X140792Y187733D01*
X140625Y187942D01*
G01X141000Y190000D02*
X138500D01*
X139000Y189500D01*
G01X141000D02*
Y190500D01*
G01Y193600D02*
X138500D01*
X140292Y192058D01*
Y194142D01*
G01X130500Y186117D02*
X133000D01*
Y187783D01*
G01X132500Y189133D02*
X132792Y189383D01*
X132958Y189717D01*
X133000Y190092D01*
X132958Y190425D01*
X132750Y190758D01*
X132500Y190967D01*
X132250Y191008D01*
X131958Y190925D01*
X131750Y190633D01*
X131667Y190342D01*
Y189967D01*
G01Y190342D02*
X131542Y190592D01*
X131333Y190800D01*
X131083Y190883D01*
X130833Y190800D01*
X130625Y190592D01*
X130500Y190217D01*
X130542Y189842D01*
X130708Y189467D01*
G01X131000Y223000D02*
X148000D01*
G01X131517Y230000D02*
Y232500D01*
X132517D01*
X132850Y232375D01*
X133100Y232083D01*
X133183Y231750D01*
X133100Y231417D01*
X132892Y231167D01*
X132517Y231042D01*
X131517D01*
G01X136367Y232292D02*
X136117Y232417D01*
X135825Y232500D01*
X135492D01*
X135117Y232375D01*
X134825Y232167D01*
X134617Y231917D01*
X134450Y231500D01*
X134408Y231125D01*
X134492Y230750D01*
X134617Y230500D01*
X134867Y230250D01*
X135158Y230083D01*
X135450Y230000D01*
X135742D01*
X136033Y230083D01*
X136283Y230208D01*
X136492Y230375D01*
G01X137633Y230500D02*
X137883Y230208D01*
X138217Y230042D01*
X138592Y230000D01*
X138925Y230042D01*
X139258Y230250D01*
X139467Y230500D01*
X139508Y230750D01*
X139425Y231042D01*
X139133Y231250D01*
X138842Y231333D01*
X138467D01*
G01X138842D02*
X139092Y231458D01*
X139300Y231667D01*
X139383Y231917D01*
X139300Y232167D01*
X139092Y232375D01*
X138717Y232500D01*
X138342Y232458D01*
X137967Y232292D01*
G01X140733Y230375D02*
X140983Y230167D01*
X141275Y230042D01*
X141650Y230000D01*
X142025Y230083D01*
X142317Y230250D01*
X142525Y230542D01*
X142567Y230875D01*
X142483Y231208D01*
X142275Y231417D01*
X141983Y231583D01*
X141692Y231625D01*
X141400Y231583D01*
X141025Y231417D01*
X141150Y232500D01*
X142275D01*
G01X131517Y234500D02*
Y237000D01*
X132517D01*
X132850Y236875D01*
X133100Y236583D01*
X133183Y236250D01*
X133100Y235917D01*
X132892Y235667D01*
X132517Y235542D01*
X131517D01*
G01X134617Y234500D02*
Y237000D01*
X135658D01*
X135992Y236875D01*
X136200Y236708D01*
X136283Y236375D01*
X136200Y236042D01*
X135950Y235833D01*
X135658Y235708D01*
X134617D01*
G01X135658D02*
X136283Y234500D01*
G01X137633Y235000D02*
X137883Y234708D01*
X138217Y234542D01*
X138592Y234500D01*
X138925Y234542D01*
X139258Y234750D01*
X139467Y235000D01*
X139508Y235250D01*
X139425Y235542D01*
X139133Y235750D01*
X138842Y235833D01*
X138467D01*
G01X138842D02*
X139092Y235958D01*
X139300Y236167D01*
X139383Y236417D01*
X139300Y236667D01*
X139092Y236875D01*
X138717Y237000D01*
X138342Y236958D01*
X137967Y236792D01*
G01X141650Y234500D02*
X141942Y234542D01*
X142275Y234667D01*
X142483Y234875D01*
X142567Y235167D01*
X142483Y235458D01*
X142233Y235708D01*
X141858Y235833D01*
X141442D01*
X141192Y235917D01*
X140983Y236125D01*
X140900Y236417D01*
X141025Y236708D01*
X141317Y236917D01*
X141650Y237000D01*
X141983Y236917D01*
X142275Y236708D01*
X142400Y236417D01*
X142317Y236125D01*
X142108Y235917D01*
X141858Y235833D01*
X141442D01*
X141067Y235708D01*
X140817Y235458D01*
X140733Y235167D01*
X140817Y234875D01*
X141025Y234667D01*
X141358Y234542D01*
X141650Y234500D01*
G01X133367Y276000D02*
Y278500D01*
X134367D01*
X134700Y278375D01*
X134950Y278083D01*
X135033Y277750D01*
X134950Y277417D01*
X134742Y277167D01*
X134367Y277042D01*
X133367D01*
G01X137300Y276000D02*
X136967Y276042D01*
X136675Y276208D01*
X136425Y276458D01*
X136258Y276750D01*
X136175Y277083D01*
Y277417D01*
X136258Y277750D01*
X136425Y278042D01*
X136675Y278292D01*
X136967Y278458D01*
X137300Y278500D01*
X137633Y278458D01*
X137925Y278292D01*
X138175Y278042D01*
X138342Y277750D01*
X138425Y277417D01*
Y277083D01*
X138342Y276750D01*
X138175Y276458D01*
X137925Y276208D01*
X137633Y276042D01*
X137300Y276000D01*
G01X137633Y276667D02*
X138133Y276000D01*
G01X140400D02*
Y278500D01*
X139900Y278000D01*
G01Y276000D02*
X140900D01*
G01X133417Y280400D02*
Y282900D01*
X134417D01*
X134750Y282775D01*
X135000Y282483D01*
X135083Y282150D01*
X135000Y281817D01*
X134792Y281567D01*
X134417Y281442D01*
X133417D01*
G01X136517Y280400D02*
Y282900D01*
X137558D01*
X137892Y282775D01*
X138100Y282608D01*
X138183Y282275D01*
X138100Y281942D01*
X137850Y281733D01*
X137558Y281608D01*
X136517D01*
G01X137558D02*
X138183Y280400D01*
G01X140450D02*
Y282900D01*
X139950Y282400D01*
G01Y280400D02*
X140950D01*
G01X142842Y280692D02*
X143133Y280483D01*
X143467Y280400D01*
X143800Y280483D01*
X144092Y280733D01*
X144300Y281108D01*
X144383Y281483D01*
Y281942D01*
X144300Y282317D01*
X144092Y282650D01*
X143842Y282817D01*
X143550Y282900D01*
X143217Y282817D01*
X142967Y282650D01*
X142800Y282400D01*
X142717Y282067D01*
X142800Y281775D01*
X143008Y281483D01*
X143258Y281317D01*
X143550Y281275D01*
X143883Y281358D01*
X144133Y281567D01*
X144383Y281942D01*
G01X150500Y40983D02*
X152292D01*
X152667Y41150D01*
X152917Y41483D01*
X153000Y41900D01*
X152917Y42317D01*
X152667Y42650D01*
X152292Y42817D01*
X150500D01*
G01X150917Y44208D02*
X150667Y44458D01*
X150542Y44750D01*
X150500Y45083D01*
X150583Y45500D01*
X150792Y45792D01*
X151042Y45875D01*
X151292Y45833D01*
X151500Y45667D01*
X151917Y44833D01*
X152208Y44458D01*
X152625Y44208D01*
X153000Y44125D01*
Y45875D01*
G01X152708Y47392D02*
X152917Y47683D01*
X153000Y48017D01*
X152917Y48350D01*
X152667Y48642D01*
X152292Y48850D01*
X151917Y48933D01*
X151458D01*
X151083Y48850D01*
X150750Y48642D01*
X150583Y48392D01*
X150500Y48100D01*
X150583Y47767D01*
X150750Y47517D01*
X151000Y47350D01*
X151333Y47267D01*
X151625Y47350D01*
X151917Y47558D01*
X152083Y47808D01*
X152125Y48100D01*
X152042Y48433D01*
X151833Y48683D01*
X151458Y48933D01*
G01X145000Y41017D02*
X142500D01*
Y42058D01*
X142625Y42392D01*
X142792Y42600D01*
X143125Y42683D01*
X143458Y42600D01*
X143667Y42350D01*
X143792Y42058D01*
Y41017D01*
G01Y42058D02*
X145000Y42683D01*
G01Y45450D02*
X142500D01*
X144292Y43908D01*
Y45992D01*
G01X143958Y47258D02*
X143667Y47550D01*
X143500Y47800D01*
X143417Y48133D01*
X143500Y48425D01*
X143667Y48633D01*
X143917Y48800D01*
X144208Y48842D01*
X144458Y48800D01*
X144708Y48633D01*
X144917Y48383D01*
X145000Y48092D01*
X144917Y47758D01*
X144667Y47467D01*
X144292Y47300D01*
X143875Y47258D01*
X143333Y47342D01*
X143042Y47467D01*
X142750Y47675D01*
X142542Y47967D01*
X142500Y48258D01*
X142583Y48550D01*
X142792Y48758D01*
G01X142917Y50358D02*
X142667Y50608D01*
X142542Y50900D01*
X142500Y51233D01*
X142583Y51650D01*
X142792Y51942D01*
X143042Y52025D01*
X143292Y51983D01*
X143500Y51817D01*
X143917Y50983D01*
X144208Y50608D01*
X144625Y50358D01*
X145000Y50275D01*
Y52025D01*
G01X149000Y41017D02*
X146500D01*
Y42058D01*
X146625Y42392D01*
X146792Y42600D01*
X147125Y42683D01*
X147458Y42600D01*
X147667Y42350D01*
X147792Y42058D01*
Y41017D01*
G01Y42058D02*
X149000Y42683D01*
G01Y45450D02*
X146500D01*
X148292Y43908D01*
Y45992D01*
G01X146917Y47258D02*
X146667Y47508D01*
X146542Y47800D01*
X146500Y48133D01*
X146583Y48550D01*
X146792Y48842D01*
X147042Y48925D01*
X147292Y48883D01*
X147500Y48717D01*
X147917Y47883D01*
X148208Y47508D01*
X148625Y47258D01*
X149000Y47175D01*
Y48925D01*
G01Y51150D02*
X146500D01*
X147000Y50650D01*
G01X149000D02*
Y51650D01*
G01X157000Y41017D02*
X154500D01*
Y42058D01*
X154625Y42392D01*
X154792Y42600D01*
X155125Y42683D01*
X155458Y42600D01*
X155667Y42350D01*
X155792Y42058D01*
Y41017D01*
G01Y42058D02*
X157000Y42683D01*
G01Y45450D02*
X154500D01*
X156292Y43908D01*
Y45992D01*
G01X154917Y47258D02*
X154667Y47508D01*
X154542Y47800D01*
X154500Y48133D01*
X154583Y48550D01*
X154792Y48842D01*
X155042Y48925D01*
X155292Y48883D01*
X155500Y48717D01*
X155917Y47883D01*
X156208Y47508D01*
X156625Y47258D01*
X157000Y47175D01*
Y48925D01*
G01X154917Y50358D02*
X154667Y50608D01*
X154542Y50900D01*
X154500Y51233D01*
X154583Y51650D01*
X154792Y51942D01*
X155042Y52025D01*
X155292Y51983D01*
X155500Y51817D01*
X155917Y50983D01*
X156208Y50608D01*
X156625Y50358D01*
X157000Y50275D01*
Y52025D01*
G01X143617Y60992D02*
X143367Y61117D01*
X143075Y61200D01*
X142742D01*
X142367Y61075D01*
X142075Y60867D01*
X141867Y60617D01*
X141700Y60200D01*
X141658Y59825D01*
X141742Y59450D01*
X141867Y59200D01*
X142117Y58950D01*
X142408Y58783D01*
X142700Y58700D01*
X142992D01*
X143283Y58783D01*
X143533Y58908D01*
X143742Y59075D01*
G01X144883Y59200D02*
X145133Y58908D01*
X145467Y58742D01*
X145842Y58700D01*
X146175Y58742D01*
X146508Y58950D01*
X146717Y59200D01*
X146758Y59450D01*
X146675Y59742D01*
X146383Y59950D01*
X146092Y60033D01*
X145717D01*
G01X146092D02*
X146342Y60158D01*
X146550Y60367D01*
X146633Y60617D01*
X146550Y60867D01*
X146342Y61075D01*
X145967Y61200D01*
X145592Y61158D01*
X145217Y60992D01*
G01X148192Y58992D02*
X148483Y58783D01*
X148817Y58700D01*
X149150Y58783D01*
X149442Y59033D01*
X149650Y59408D01*
X149733Y59783D01*
Y60242D01*
X149650Y60617D01*
X149442Y60950D01*
X149192Y61117D01*
X148900Y61200D01*
X148567Y61117D01*
X148317Y60950D01*
X148150Y60700D01*
X148067Y60367D01*
X148150Y60075D01*
X148358Y59783D01*
X148608Y59617D01*
X148900Y59575D01*
X149233Y59658D01*
X149483Y59867D01*
X149733Y60242D01*
G01X147017Y53500D02*
Y56000D01*
X148058D01*
X148392Y55875D01*
X148600Y55708D01*
X148683Y55375D01*
X148600Y55042D01*
X148350Y54833D01*
X148058Y54708D01*
X147017D01*
G01X148058D02*
X148683Y53500D01*
G01X151450D02*
Y56000D01*
X149908Y54208D01*
X151992D01*
G01X154050Y53500D02*
Y56000D01*
X153550Y55500D01*
G01Y53500D02*
X154550D01*
G01X157067D02*
X157150Y54042D01*
X157275Y54500D01*
X157442Y54917D01*
X157650Y55375D01*
X157983Y56000D01*
X156317D01*
G01X141500Y165033D02*
X143292D01*
X143667Y165200D01*
X143917Y165533D01*
X144000Y165950D01*
X143917Y166367D01*
X143667Y166700D01*
X143292Y166867D01*
X141500D01*
G01X142958Y168258D02*
X142667Y168550D01*
X142500Y168800D01*
X142417Y169133D01*
X142500Y169425D01*
X142667Y169633D01*
X142917Y169800D01*
X143208Y169842D01*
X143458Y169800D01*
X143708Y169633D01*
X143917Y169383D01*
X144000Y169092D01*
X143917Y168758D01*
X143667Y168467D01*
X143292Y168300D01*
X142875Y168258D01*
X142333Y168342D01*
X142042Y168467D01*
X141750Y168675D01*
X141542Y168967D01*
X141500Y169258D01*
X141583Y169550D01*
X141792Y169758D01*
G01X147500Y163567D02*
X145000D01*
Y164608D01*
X145125Y164942D01*
X145292Y165150D01*
X145625Y165233D01*
X145958Y165150D01*
X146167Y164900D01*
X146292Y164608D01*
Y163567D01*
G01Y164608D02*
X147500Y165233D01*
G01X146458Y166708D02*
X146167Y167000D01*
X146000Y167250D01*
X145917Y167583D01*
X146000Y167875D01*
X146167Y168083D01*
X146417Y168250D01*
X146708Y168292D01*
X146958Y168250D01*
X147208Y168083D01*
X147417Y167833D01*
X147500Y167542D01*
X147417Y167208D01*
X147167Y166917D01*
X146792Y166750D01*
X146375Y166708D01*
X145833Y166792D01*
X145542Y166917D01*
X145250Y167125D01*
X145042Y167417D01*
X145000Y167708D01*
X145083Y168000D01*
X145292Y168208D01*
G01X147125Y169683D02*
X147333Y169933D01*
X147458Y170225D01*
X147500Y170600D01*
X147417Y170975D01*
X147250Y171267D01*
X146958Y171475D01*
X146625Y171517D01*
X146292Y171433D01*
X146083Y171225D01*
X145917Y170933D01*
X145875Y170642D01*
X145917Y170350D01*
X146083Y169975D01*
X145000Y170100D01*
Y171225D01*
G01X154350Y182400D02*
Y185000D01*
G01X162250Y182400D02*
X154350D01*
G01X152533Y193000D02*
Y191208D01*
X152700Y190833D01*
X153033Y190583D01*
X153450Y190500D01*
X153867Y190583D01*
X154200Y190833D01*
X154367Y191208D01*
Y193000D01*
G01X156467Y190500D02*
X156550Y191042D01*
X156675Y191500D01*
X156842Y191917D01*
X157050Y192375D01*
X157383Y193000D01*
X155717D01*
G01X154350Y185000D02*
X162250D01*
G01X142967Y186100D02*
Y188600D01*
X144008D01*
X144342Y188475D01*
X144550Y188308D01*
X144633Y187975D01*
X144550Y187642D01*
X144300Y187433D01*
X144008Y187308D01*
X142967D01*
G01X144008D02*
X144633Y186100D01*
G01X147400D02*
Y188600D01*
X145858Y186808D01*
X147942D01*
G01X149083Y186600D02*
X149333Y186308D01*
X149667Y186142D01*
X150042Y186100D01*
X150375Y186142D01*
X150708Y186350D01*
X150917Y186600D01*
X150958Y186850D01*
X150875Y187142D01*
X150583Y187350D01*
X150292Y187433D01*
X149917D01*
G01X150292D02*
X150542Y187558D01*
X150750Y187767D01*
X150833Y188017D01*
X150750Y188267D01*
X150542Y188475D01*
X150167Y188600D01*
X149792Y188558D01*
X149417Y188392D01*
G01X142967Y189800D02*
Y192300D01*
X144008D01*
X144342Y192175D01*
X144550Y192008D01*
X144633Y191675D01*
X144550Y191342D01*
X144300Y191133D01*
X144008Y191008D01*
X142967D01*
G01X144008D02*
X144633Y189800D01*
G01X147400D02*
Y192300D01*
X145858Y190508D01*
X147942D01*
G01X149208Y191883D02*
X149458Y192133D01*
X149750Y192258D01*
X150083Y192300D01*
X150500Y192217D01*
X150792Y192008D01*
X150875Y191758D01*
X150833Y191508D01*
X150667Y191300D01*
X149833Y190883D01*
X149458Y190592D01*
X149208Y190175D01*
X149125Y189800D01*
X150875D01*
G01X142417Y207300D02*
Y209800D01*
X143458D01*
X143792Y209675D01*
X144000Y209508D01*
X144083Y209175D01*
X144000Y208842D01*
X143750Y208633D01*
X143458Y208508D01*
X142417D01*
G01X143458D02*
X144083Y207300D01*
G01X146350D02*
Y209800D01*
X145850Y209300D01*
G01Y207300D02*
X146850D01*
G01X148533Y207800D02*
X148783Y207508D01*
X149117Y207342D01*
X149492Y207300D01*
X149825Y207342D01*
X150158Y207550D01*
X150367Y207800D01*
X150408Y208050D01*
X150325Y208342D01*
X150033Y208550D01*
X149742Y208633D01*
X149367D01*
G01X149742D02*
X149992Y208758D01*
X150200Y208967D01*
X150283Y209217D01*
X150200Y209467D01*
X149992Y209675D01*
X149617Y209800D01*
X149242Y209758D01*
X148867Y209592D01*
G01X152550Y207300D02*
X152842Y207342D01*
X153175Y207467D01*
X153383Y207675D01*
X153467Y207967D01*
X153383Y208258D01*
X153133Y208508D01*
X152758Y208633D01*
X152342D01*
X152092Y208717D01*
X151883Y208925D01*
X151800Y209217D01*
X151925Y209508D01*
X152217Y209717D01*
X152550Y209800D01*
X152883Y209717D01*
X153175Y209508D01*
X153300Y209217D01*
X153217Y208925D01*
X153008Y208717D01*
X152758Y208633D01*
X152342D01*
X151967Y208508D01*
X151717Y208258D01*
X151633Y207967D01*
X151717Y207675D01*
X151925Y207467D01*
X152258Y207342D01*
X152550Y207300D01*
G01X155500Y217000D02*
X162000D01*
G01X147000Y228517D02*
X144500D01*
Y229517D01*
X144625Y229850D01*
X144917Y230100D01*
X145250Y230183D01*
X145583Y230100D01*
X145833Y229892D01*
X145958Y229517D01*
Y228517D01*
G01X147000Y231617D02*
X144500D01*
Y232658D01*
X144625Y232992D01*
X144792Y233200D01*
X145125Y233283D01*
X145458Y233200D01*
X145667Y232950D01*
X145792Y232658D01*
Y231617D01*
G01Y232658D02*
X147000Y233283D01*
G01Y235550D02*
X146958Y235842D01*
X146833Y236175D01*
X146625Y236383D01*
X146333Y236467D01*
X146042Y236383D01*
X145792Y236133D01*
X145667Y235758D01*
Y235342D01*
X145583Y235092D01*
X145375Y234883D01*
X145083Y234800D01*
X144792Y234925D01*
X144583Y235217D01*
X144500Y235550D01*
X144583Y235883D01*
X144792Y236175D01*
X145083Y236300D01*
X145375Y236217D01*
X145583Y236008D01*
X145667Y235758D01*
Y235342D01*
X145792Y234967D01*
X146042Y234717D01*
X146333Y234633D01*
X146625Y234717D01*
X146833Y234925D01*
X146958Y235258D01*
X147000Y235550D01*
G01X146625Y237733D02*
X146833Y237983D01*
X146958Y238275D01*
X147000Y238650D01*
X146917Y239025D01*
X146750Y239317D01*
X146458Y239525D01*
X146125Y239567D01*
X145792Y239483D01*
X145583Y239275D01*
X145417Y238983D01*
X145375Y238692D01*
X145417Y238400D01*
X145583Y238025D01*
X144500Y238150D01*
Y239275D01*
G01X161000Y41017D02*
X158500D01*
Y42058D01*
X158625Y42392D01*
X158792Y42600D01*
X159125Y42683D01*
X159458Y42600D01*
X159667Y42350D01*
X159792Y42058D01*
Y41017D01*
G01Y42058D02*
X161000Y42683D01*
G01Y45450D02*
X158500D01*
X160292Y43908D01*
Y45992D01*
G01X159958Y47258D02*
X159667Y47550D01*
X159500Y47800D01*
X159417Y48133D01*
X159500Y48425D01*
X159667Y48633D01*
X159917Y48800D01*
X160208Y48842D01*
X160458Y48800D01*
X160708Y48633D01*
X160917Y48383D01*
X161000Y48092D01*
X160917Y47758D01*
X160667Y47467D01*
X160292Y47300D01*
X159875Y47258D01*
X159333Y47342D01*
X159042Y47467D01*
X158750Y47675D01*
X158542Y47967D01*
X158500Y48258D01*
X158583Y48550D01*
X158792Y48758D01*
G01X160500Y50233D02*
X160792Y50483D01*
X160958Y50817D01*
X161000Y51192D01*
X160958Y51525D01*
X160750Y51858D01*
X160500Y52067D01*
X160250Y52108D01*
X159958Y52025D01*
X159750Y51733D01*
X159667Y51442D01*
Y51067D01*
G01Y51442D02*
X159542Y51692D01*
X159333Y51900D01*
X159083Y51983D01*
X158833Y51900D01*
X158625Y51692D01*
X158500Y51317D01*
X158542Y50942D01*
X158708Y50567D01*
G01X169800Y45267D02*
X167300D01*
Y46308D01*
X167425Y46642D01*
X167592Y46850D01*
X167925Y46933D01*
X168258Y46850D01*
X168467Y46600D01*
X168592Y46308D01*
Y45267D01*
G01Y46308D02*
X169800Y46933D01*
G01X168758Y48408D02*
X168467Y48700D01*
X168300Y48950D01*
X168217Y49283D01*
X168300Y49575D01*
X168467Y49783D01*
X168717Y49950D01*
X169008Y49992D01*
X169258Y49950D01*
X169508Y49783D01*
X169717Y49533D01*
X169800Y49242D01*
X169717Y48908D01*
X169467Y48617D01*
X169092Y48450D01*
X168675Y48408D01*
X168133Y48492D01*
X167842Y48617D01*
X167550Y48825D01*
X167342Y49117D01*
X167300Y49408D01*
X167383Y49700D01*
X167592Y49908D01*
G01X167300Y52300D02*
X167383Y51967D01*
X167592Y51717D01*
X167842Y51550D01*
X168175Y51425D01*
X168550Y51383D01*
X168925Y51425D01*
X169258Y51550D01*
X169508Y51717D01*
X169717Y51967D01*
X169800Y52300D01*
X169717Y52633D01*
X169508Y52883D01*
X169258Y53050D01*
X168925Y53175D01*
X168550Y53217D01*
X168175Y53175D01*
X167842Y53050D01*
X167592Y52883D01*
X167383Y52633D01*
X167300Y52300D01*
G01X174000Y79000D02*
X176000D01*
Y75000D01*
X171000D01*
G01X168500Y165000D02*
X167500D01*
Y161500D01*
X159000D01*
G01X169817Y177292D02*
X169567Y177417D01*
X169275Y177500D01*
X168942D01*
X168567Y177375D01*
X168275Y177167D01*
X168067Y176917D01*
X167900Y176500D01*
X167858Y176125D01*
X167942Y175750D01*
X168067Y175500D01*
X168317Y175250D01*
X168608Y175083D01*
X168900Y175000D01*
X169192D01*
X169483Y175083D01*
X169733Y175208D01*
X169942Y175375D01*
G01X171208Y177083D02*
X171458Y177333D01*
X171750Y177458D01*
X172083Y177500D01*
X172500Y177417D01*
X172792Y177208D01*
X172875Y176958D01*
X172833Y176708D01*
X172667Y176500D01*
X171833Y176083D01*
X171458Y175792D01*
X171208Y175375D01*
X171125Y175000D01*
X172875D01*
G01X174392Y175292D02*
X174683Y175083D01*
X175017Y175000D01*
X175350Y175083D01*
X175642Y175333D01*
X175850Y175708D01*
X175933Y176083D01*
Y176542D01*
X175850Y176917D01*
X175642Y177250D01*
X175392Y177417D01*
X175100Y177500D01*
X174767Y177417D01*
X174517Y177250D01*
X174350Y177000D01*
X174267Y176667D01*
X174350Y176375D01*
X174558Y176083D01*
X174808Y175917D01*
X175100Y175875D01*
X175433Y175958D01*
X175683Y176167D01*
X175933Y176542D01*
G01X156550Y167700D02*
Y170300D01*
G01X164450Y167700D02*
X156550D01*
G01X164450Y170300D02*
Y167700D01*
G01X156550Y170300D02*
X164450D01*
G01X162250Y185000D02*
Y182400D01*
G01X166500Y182950D02*
X166458Y182617D01*
X166292Y182325D01*
X166042Y182075D01*
X165750Y181908D01*
X165417Y181825D01*
X165083D01*
X164750Y181908D01*
X164458Y182075D01*
X164208Y182325D01*
X164042Y182617D01*
X164000Y182950D01*
X164042Y183283D01*
X164208Y183575D01*
X164458Y183825D01*
X164750Y183992D01*
X165083Y184075D01*
X165417D01*
X165750Y183992D01*
X166042Y183825D01*
X166292Y183575D01*
X166458Y183283D01*
X166500Y182950D01*
G01X165833Y183283D02*
X166500Y183783D01*
G01X166000Y185133D02*
X166292Y185383D01*
X166458Y185717D01*
X166500Y186092D01*
X166458Y186425D01*
X166250Y186758D01*
X166000Y186967D01*
X165750Y187008D01*
X165458Y186925D01*
X165250Y186633D01*
X165167Y186342D01*
Y185967D01*
G01Y186342D02*
X165042Y186592D01*
X164833Y186800D01*
X164583Y186883D01*
X164333Y186800D01*
X164125Y186592D01*
X164000Y186217D01*
X164042Y185842D01*
X164208Y185467D01*
G01X181250Y183900D02*
Y186100D01*
X167750D01*
Y183900D01*
X181250D01*
G01X170500Y217000D02*
X180000D01*
Y218500D01*
X201000D01*
Y206500D01*
X206500D01*
G01X160567Y273500D02*
Y276000D01*
X161567D01*
X161900Y275875D01*
X162150Y275583D01*
X162233Y275250D01*
X162150Y274917D01*
X161942Y274667D01*
X161567Y274542D01*
X160567D01*
G01X163583Y276000D02*
Y274208D01*
X163750Y273833D01*
X164083Y273583D01*
X164500Y273500D01*
X164917Y273583D01*
X165250Y273833D01*
X165417Y274208D01*
Y276000D01*
G01X166808Y275583D02*
X167058Y275833D01*
X167350Y275958D01*
X167683Y276000D01*
X168100Y275917D01*
X168392Y275708D01*
X168475Y275458D01*
X168433Y275208D01*
X168267Y275000D01*
X167433Y274583D01*
X167058Y274292D01*
X166808Y273875D01*
X166725Y273500D01*
X168475D01*
G01X160567Y282000D02*
Y284500D01*
X161567D01*
X161900Y284375D01*
X162150Y284083D01*
X162233Y283750D01*
X162150Y283417D01*
X161942Y283167D01*
X161567Y283042D01*
X160567D01*
G01X163667Y284500D02*
Y282000D01*
X165333D01*
G01X167600D02*
Y284500D01*
X167100Y284000D01*
G01Y282000D02*
X168100D01*
G01X160517Y277500D02*
Y280000D01*
X161517D01*
X161850Y279875D01*
X162100Y279583D01*
X162183Y279250D01*
X162100Y278917D01*
X161892Y278667D01*
X161517Y278542D01*
X160517D01*
G01X163617Y277500D02*
Y280000D01*
X164658D01*
X164992Y279875D01*
X165200Y279708D01*
X165283Y279375D01*
X165200Y279042D01*
X164950Y278833D01*
X164658Y278708D01*
X163617D01*
G01X164658D02*
X165283Y277500D01*
G01X166633Y277875D02*
X166883Y277667D01*
X167175Y277542D01*
X167550Y277500D01*
X167925Y277583D01*
X168217Y277750D01*
X168425Y278042D01*
X168467Y278375D01*
X168383Y278708D01*
X168175Y278917D01*
X167883Y279083D01*
X167592Y279125D01*
X167300Y279083D01*
X166925Y278917D01*
X167050Y280000D01*
X168175D01*
G01X170650Y277500D02*
Y280000D01*
X170150Y279500D01*
G01Y277500D02*
X171150D01*
G01X171500Y45367D02*
X174000D01*
Y47033D01*
G01Y49300D02*
X171500D01*
X172000Y48800D01*
G01X174000D02*
Y49800D01*
G01Y52400D02*
X171500D01*
X172000Y51900D01*
G01X174000D02*
Y52900D01*
G01X187000Y44317D02*
X184500D01*
Y45358D01*
X184625Y45692D01*
X184792Y45900D01*
X185125Y45983D01*
X185458Y45900D01*
X185667Y45650D01*
X185792Y45358D01*
Y44317D01*
G01Y45358D02*
X187000Y45983D01*
G01X186500Y47333D02*
X186792Y47583D01*
X186958Y47917D01*
X187000Y48292D01*
X186958Y48625D01*
X186750Y48958D01*
X186500Y49167D01*
X186250Y49208D01*
X185958Y49125D01*
X185750Y48833D01*
X185667Y48542D01*
Y48167D01*
G01Y48542D02*
X185542Y48792D01*
X185333Y49000D01*
X185083Y49083D01*
X184833Y49000D01*
X184625Y48792D01*
X184500Y48417D01*
X184542Y48042D01*
X184708Y47667D01*
G01X187000Y51850D02*
X184500D01*
X186292Y50308D01*
Y52392D01*
G01X187000Y54450D02*
X186958Y54742D01*
X186833Y55075D01*
X186625Y55283D01*
X186333Y55367D01*
X186042Y55283D01*
X185792Y55033D01*
X185667Y54658D01*
Y54242D01*
X185583Y53992D01*
X185375Y53783D01*
X185083Y53700D01*
X184792Y53825D01*
X184583Y54117D01*
X184500Y54450D01*
X184583Y54783D01*
X184792Y55075D01*
X185083Y55200D01*
X185375Y55117D01*
X185583Y54908D01*
X185667Y54658D01*
Y54242D01*
X185792Y53867D01*
X186042Y53617D01*
X186333Y53533D01*
X186625Y53617D01*
X186833Y53825D01*
X186958Y54158D01*
X187000Y54450D01*
G01X179000Y44317D02*
X176500D01*
Y45358D01*
X176625Y45692D01*
X176792Y45900D01*
X177125Y45983D01*
X177458Y45900D01*
X177667Y45650D01*
X177792Y45358D01*
Y44317D01*
G01Y45358D02*
X179000Y45983D01*
G01X178500Y47333D02*
X178792Y47583D01*
X178958Y47917D01*
X179000Y48292D01*
X178958Y48625D01*
X178750Y48958D01*
X178500Y49167D01*
X178250Y49208D01*
X177958Y49125D01*
X177750Y48833D01*
X177667Y48542D01*
Y48167D01*
G01Y48542D02*
X177542Y48792D01*
X177333Y49000D01*
X177083Y49083D01*
X176833Y49000D01*
X176625Y48792D01*
X176500Y48417D01*
X176542Y48042D01*
X176708Y47667D01*
G01X178625Y50433D02*
X178833Y50683D01*
X178958Y50975D01*
X179000Y51350D01*
X178917Y51725D01*
X178750Y52017D01*
X178458Y52225D01*
X178125Y52267D01*
X177792Y52183D01*
X177583Y51975D01*
X177417Y51683D01*
X177375Y51392D01*
X177417Y51100D01*
X177583Y50725D01*
X176500Y50850D01*
Y51975D01*
G01X178708Y53742D02*
X178917Y54033D01*
X179000Y54367D01*
X178917Y54700D01*
X178667Y54992D01*
X178292Y55200D01*
X177917Y55283D01*
X177458D01*
X177083Y55200D01*
X176750Y54992D01*
X176583Y54742D01*
X176500Y54450D01*
X176583Y54117D01*
X176750Y53867D01*
X177000Y53700D01*
X177333Y53617D01*
X177625Y53700D01*
X177917Y53908D01*
X178083Y54158D01*
X178125Y54450D01*
X178042Y54783D01*
X177833Y55033D01*
X177458Y55283D01*
G01X183000Y44317D02*
X180500D01*
Y45358D01*
X180625Y45692D01*
X180792Y45900D01*
X181125Y45983D01*
X181458Y45900D01*
X181667Y45650D01*
X181792Y45358D01*
Y44317D01*
G01Y45358D02*
X183000Y45983D01*
G01X182500Y47333D02*
X182792Y47583D01*
X182958Y47917D01*
X183000Y48292D01*
X182958Y48625D01*
X182750Y48958D01*
X182500Y49167D01*
X182250Y49208D01*
X181958Y49125D01*
X181750Y48833D01*
X181667Y48542D01*
Y48167D01*
G01Y48542D02*
X181542Y48792D01*
X181333Y49000D01*
X181083Y49083D01*
X180833Y49000D01*
X180625Y48792D01*
X180500Y48417D01*
X180542Y48042D01*
X180708Y47667D01*
G01X183000Y51850D02*
X180500D01*
X182292Y50308D01*
Y52392D01*
G01X181958Y53658D02*
X181667Y53950D01*
X181500Y54200D01*
X181417Y54533D01*
X181500Y54825D01*
X181667Y55033D01*
X181917Y55200D01*
X182208Y55242D01*
X182458Y55200D01*
X182708Y55033D01*
X182917Y54783D01*
X183000Y54492D01*
X182917Y54158D01*
X182667Y53867D01*
X182292Y53700D01*
X181875Y53658D01*
X181333Y53742D01*
X181042Y53867D01*
X180750Y54075D01*
X180542Y54367D01*
X180500Y54658D01*
X180583Y54950D01*
X180792Y55158D01*
G01X171500Y70000D02*
Y69000D01*
X183500D01*
G01X171500Y92500D02*
Y81500D01*
G01X183500Y93500D02*
X180500D01*
Y91500D01*
G01X181208Y97267D02*
X181083Y97017D01*
X181000Y96725D01*
Y96392D01*
X181125Y96017D01*
X181333Y95725D01*
X181583Y95517D01*
X182000Y95350D01*
X182375Y95308D01*
X182750Y95392D01*
X183000Y95517D01*
X183250Y95767D01*
X183417Y96058D01*
X183500Y96350D01*
Y96642D01*
X183417Y96933D01*
X183292Y97183D01*
X183125Y97392D01*
G01X181417Y98658D02*
X181167Y98908D01*
X181042Y99200D01*
X181000Y99533D01*
X181083Y99950D01*
X181292Y100242D01*
X181542Y100325D01*
X181792Y100283D01*
X182000Y100117D01*
X182417Y99283D01*
X182708Y98908D01*
X183125Y98658D01*
X183500Y98575D01*
Y100325D01*
G01X181000Y102550D02*
X181083Y102217D01*
X181292Y101967D01*
X181542Y101800D01*
X181875Y101675D01*
X182250Y101633D01*
X182625Y101675D01*
X182958Y101800D01*
X183208Y101967D01*
X183417Y102217D01*
X183500Y102550D01*
X183417Y102883D01*
X183208Y103133D01*
X182958Y103300D01*
X182625Y103425D01*
X182250Y103467D01*
X181875Y103425D01*
X181542Y103300D01*
X181292Y103133D01*
X181083Y102883D01*
X181000Y102550D01*
G01X183500Y105650D02*
X183458Y105942D01*
X183333Y106275D01*
X183125Y106483D01*
X182833Y106567D01*
X182542Y106483D01*
X182292Y106233D01*
X182167Y105858D01*
Y105442D01*
X182083Y105192D01*
X181875Y104983D01*
X181583Y104900D01*
X181292Y105025D01*
X181083Y105317D01*
X181000Y105650D01*
X181083Y105983D01*
X181292Y106275D01*
X181583Y106400D01*
X181875Y106317D01*
X182083Y106108D01*
X182167Y105858D01*
Y105442D01*
X182292Y105067D01*
X182542Y104817D01*
X182833Y104733D01*
X183125Y104817D01*
X183333Y105025D01*
X183458Y105358D01*
X183500Y105650D01*
G01X185698Y134171D02*
X198898D01*
Y148671D01*
X216598D01*
Y134171D01*
X229798D01*
Y94171D01*
X185698D01*
Y134171D01*
G01X184000Y110500D02*
Y108500D01*
G01X171500Y117983D02*
X173292D01*
X173667Y118150D01*
X173917Y118483D01*
X174000Y118900D01*
X173917Y119317D01*
X173667Y119650D01*
X173292Y119817D01*
X171500D01*
G01X174000Y122500D02*
X171500D01*
X173292Y120958D01*
Y123042D01*
G01X173500Y124183D02*
X173792Y124433D01*
X173958Y124767D01*
X174000Y125142D01*
X173958Y125475D01*
X173750Y125808D01*
X173500Y126017D01*
X173250Y126058D01*
X172958Y125975D01*
X172750Y125683D01*
X172667Y125392D01*
Y125017D01*
G01Y125392D02*
X172542Y125642D01*
X172333Y125850D01*
X172083Y125933D01*
X171833Y125850D01*
X171625Y125642D01*
X171500Y125267D01*
X171542Y124892D01*
X171708Y124517D01*
G01X181500Y115950D02*
Y123850D01*
X178700D01*
Y115950D01*
X181500D01*
G01X172017Y112000D02*
Y114500D01*
X173058D01*
X173392Y114375D01*
X173600Y114208D01*
X173683Y113875D01*
X173600Y113542D01*
X173350Y113333D01*
X173058Y113208D01*
X172017D01*
G01X173058D02*
X173683Y112000D01*
G01X175158Y114083D02*
X175408Y114333D01*
X175700Y114458D01*
X176033Y114500D01*
X176450Y114417D01*
X176742Y114208D01*
X176825Y113958D01*
X176783Y113708D01*
X176617Y113500D01*
X175783Y113083D01*
X175408Y112792D01*
X175158Y112375D01*
X175075Y112000D01*
X176825D01*
G01X179550D02*
Y114500D01*
X178008Y112708D01*
X180092D01*
G01X182150Y112000D02*
X182442Y112042D01*
X182775Y112167D01*
X182983Y112375D01*
X183067Y112667D01*
X182983Y112958D01*
X182733Y113208D01*
X182358Y113333D01*
X181942D01*
X181692Y113417D01*
X181483Y113625D01*
X181400Y113917D01*
X181525Y114208D01*
X181817Y114417D01*
X182150Y114500D01*
X182483Y114417D01*
X182775Y114208D01*
X182900Y113917D01*
X182817Y113625D01*
X182608Y113417D01*
X182358Y113333D01*
X181942D01*
X181567Y113208D01*
X181317Y112958D01*
X181233Y112667D01*
X181317Y112375D01*
X181525Y112167D01*
X181858Y112042D01*
X182150Y112000D01*
G01X171500Y136000D02*
X172500D01*
Y131000D01*
X175500D01*
Y128600D01*
G01X178100Y144550D02*
X175500D01*
G01X178100Y152450D02*
Y144550D01*
G01X175500D02*
Y152450D01*
G01X182500Y170500D02*
Y153500D01*
X183500D01*
G01X176300Y154050D02*
X173700D01*
G01X176300Y161950D02*
Y154050D01*
G01X173700Y161950D02*
X176300D01*
G01X173700Y154050D02*
Y161950D01*
G01X176300Y163550D02*
X173700D01*
G01X176300Y171450D02*
Y163550D01*
G01X173700D02*
Y171450D01*
G01X175500Y152450D02*
X178100D01*
G01X185208Y176317D02*
X185083Y176067D01*
X185000Y175775D01*
Y175442D01*
X185125Y175067D01*
X185333Y174775D01*
X185583Y174567D01*
X186000Y174400D01*
X186375Y174358D01*
X186750Y174442D01*
X187000Y174567D01*
X187250Y174817D01*
X187417Y175108D01*
X187500Y175400D01*
Y175692D01*
X187417Y175983D01*
X187292Y176233D01*
X187125Y176442D01*
G01X185417Y177708D02*
X185167Y177958D01*
X185042Y178250D01*
X185000Y178583D01*
X185083Y179000D01*
X185292Y179292D01*
X185542Y179375D01*
X185792Y179333D01*
X186000Y179167D01*
X186417Y178333D01*
X186708Y177958D01*
X187125Y177708D01*
X187500Y177625D01*
Y179375D01*
G01X185000Y181600D02*
X185083Y181267D01*
X185292Y181017D01*
X185542Y180850D01*
X185875Y180725D01*
X186250Y180683D01*
X186625Y180725D01*
X186958Y180850D01*
X187208Y181017D01*
X187417Y181267D01*
X187500Y181600D01*
X187417Y181933D01*
X187208Y182183D01*
X186958Y182350D01*
X186625Y182475D01*
X186250Y182517D01*
X185875Y182475D01*
X185542Y182350D01*
X185292Y182183D01*
X185083Y181933D01*
X185000Y181600D01*
G01X173700Y171450D02*
X176300D01*
G01X176817Y196292D02*
X176567Y196417D01*
X176275Y196500D01*
X175942D01*
X175567Y196375D01*
X175275Y196167D01*
X175067Y195917D01*
X174900Y195500D01*
X174858Y195125D01*
X174942Y194750D01*
X175067Y194500D01*
X175317Y194250D01*
X175608Y194083D01*
X175900Y194000D01*
X176192D01*
X176483Y194083D01*
X176733Y194208D01*
X176942Y194375D01*
G01X179000Y194000D02*
Y196500D01*
X178500Y196000D01*
G01Y194000D02*
X179500D01*
G01X182017D02*
X182100Y194542D01*
X182225Y195000D01*
X182392Y195417D01*
X182600Y195875D01*
X182933Y196500D01*
X181267D01*
G01X184100Y275417D02*
X181600D01*
Y276417D01*
X181725Y276750D01*
X182017Y277000D01*
X182350Y277083D01*
X182683Y277000D01*
X182933Y276792D01*
X183058Y276417D01*
Y275417D01*
G01X181808Y280267D02*
X181683Y280017D01*
X181600Y279725D01*
Y279392D01*
X181725Y279017D01*
X181933Y278725D01*
X182183Y278517D01*
X182600Y278350D01*
X182975Y278308D01*
X183350Y278392D01*
X183600Y278517D01*
X183850Y278767D01*
X184017Y279058D01*
X184100Y279350D01*
Y279642D01*
X184017Y279933D01*
X183892Y280183D01*
X183725Y280392D01*
G01X183600Y281533D02*
X183892Y281783D01*
X184058Y282117D01*
X184100Y282492D01*
X184058Y282825D01*
X183850Y283158D01*
X183600Y283367D01*
X183350Y283408D01*
X183058Y283325D01*
X182850Y283033D01*
X182767Y282742D01*
Y282367D01*
G01Y282742D02*
X182642Y282992D01*
X182433Y283200D01*
X182183Y283283D01*
X181933Y283200D01*
X181725Y282992D01*
X181600Y282617D01*
X181642Y282242D01*
X181808Y281867D01*
G01X181600Y285550D02*
X181683Y285217D01*
X181892Y284967D01*
X182142Y284800D01*
X182475Y284675D01*
X182850Y284633D01*
X183225Y284675D01*
X183558Y284800D01*
X183808Y284967D01*
X184017Y285217D01*
X184100Y285550D01*
X184017Y285883D01*
X183808Y286133D01*
X183558Y286300D01*
X183225Y286425D01*
X182850Y286467D01*
X182475Y286425D01*
X182142Y286300D01*
X181892Y286133D01*
X181683Y285883D01*
X181600Y285550D01*
G01X180100Y275417D02*
X177600D01*
Y276417D01*
X177725Y276750D01*
X178017Y277000D01*
X178350Y277083D01*
X178683Y277000D01*
X178933Y276792D01*
X179058Y276417D01*
Y275417D01*
G01X177808Y280267D02*
X177683Y280017D01*
X177600Y279725D01*
Y279392D01*
X177725Y279017D01*
X177933Y278725D01*
X178183Y278517D01*
X178600Y278350D01*
X178975Y278308D01*
X179350Y278392D01*
X179600Y278517D01*
X179850Y278767D01*
X180017Y279058D01*
X180100Y279350D01*
Y279642D01*
X180017Y279933D01*
X179892Y280183D01*
X179725Y280392D01*
G01X178017Y281658D02*
X177767Y281908D01*
X177642Y282200D01*
X177600Y282533D01*
X177683Y282950D01*
X177892Y283242D01*
X178142Y283325D01*
X178392Y283283D01*
X178600Y283117D01*
X179017Y282283D01*
X179308Y281908D01*
X179725Y281658D01*
X180100Y281575D01*
Y283325D01*
G01X179808Y284842D02*
X180017Y285133D01*
X180100Y285467D01*
X180017Y285800D01*
X179767Y286092D01*
X179392Y286300D01*
X179017Y286383D01*
X178558D01*
X178183Y286300D01*
X177850Y286092D01*
X177683Y285842D01*
X177600Y285550D01*
X177683Y285217D01*
X177850Y284967D01*
X178100Y284800D01*
X178433Y284717D01*
X178725Y284800D01*
X179017Y285008D01*
X179183Y285258D01*
X179225Y285550D01*
X179142Y285883D01*
X178933Y286133D01*
X178558Y286383D01*
G01X203000Y53000D02*
Y46500D01*
X194500D01*
Y41000D01*
X215000D01*
G01X197767Y44792D02*
X197517Y44917D01*
X197225Y45000D01*
X196892D01*
X196517Y44875D01*
X196225Y44667D01*
X196017Y44417D01*
X195850Y44000D01*
X195808Y43625D01*
X195892Y43250D01*
X196017Y43000D01*
X196267Y42750D01*
X196558Y42583D01*
X196850Y42500D01*
X197142D01*
X197433Y42583D01*
X197683Y42708D01*
X197892Y42875D01*
G01X199033Y43000D02*
X199283Y42708D01*
X199617Y42542D01*
X199992Y42500D01*
X200325Y42542D01*
X200658Y42750D01*
X200867Y43000D01*
X200908Y43250D01*
X200825Y43542D01*
X200533Y43750D01*
X200242Y43833D01*
X199867D01*
G01X200242D02*
X200492Y43958D01*
X200700Y44167D01*
X200783Y44417D01*
X200700Y44667D01*
X200492Y44875D01*
X200117Y45000D01*
X199742Y44958D01*
X199367Y44792D01*
G01X203050Y42500D02*
Y45000D01*
X202550Y44500D01*
G01Y42500D02*
X203550D01*
G01X205233Y42875D02*
X205483Y42667D01*
X205775Y42542D01*
X206150Y42500D01*
X206525Y42583D01*
X206817Y42750D01*
X207025Y43042D01*
X207067Y43375D01*
X206983Y43708D01*
X206775Y43917D01*
X206483Y44083D01*
X206192Y44125D01*
X205900Y44083D01*
X205525Y43917D01*
X205650Y45000D01*
X206775D01*
G01X200108Y56667D02*
X199983Y56417D01*
X199900Y56125D01*
Y55792D01*
X200025Y55417D01*
X200233Y55125D01*
X200483Y54917D01*
X200900Y54750D01*
X201275Y54708D01*
X201650Y54792D01*
X201900Y54917D01*
X202150Y55167D01*
X202317Y55458D01*
X202400Y55750D01*
Y56042D01*
X202317Y56333D01*
X202192Y56583D01*
X202025Y56792D01*
G01X201900Y57933D02*
X202192Y58183D01*
X202358Y58517D01*
X202400Y58892D01*
X202358Y59225D01*
X202150Y59558D01*
X201900Y59767D01*
X201650Y59808D01*
X201358Y59725D01*
X201150Y59433D01*
X201067Y59142D01*
Y58767D01*
G01Y59142D02*
X200942Y59392D01*
X200733Y59600D01*
X200483Y59683D01*
X200233Y59600D01*
X200025Y59392D01*
X199900Y59017D01*
X199942Y58642D01*
X200108Y58267D01*
G01X202400Y61950D02*
X199900D01*
X200400Y61450D01*
G01X202400D02*
Y62450D01*
G01X201900Y64133D02*
X202192Y64383D01*
X202358Y64717D01*
X202400Y65092D01*
X202358Y65425D01*
X202150Y65758D01*
X201900Y65967D01*
X201650Y66008D01*
X201358Y65925D01*
X201150Y65633D01*
X201067Y65342D01*
Y64967D01*
G01Y65342D02*
X200942Y65592D01*
X200733Y65800D01*
X200483Y65883D01*
X200233Y65800D01*
X200025Y65592D01*
X199900Y65217D01*
X199942Y64842D01*
X200108Y64467D01*
G01X196108Y56767D02*
X195983Y56517D01*
X195900Y56225D01*
Y55892D01*
X196025Y55517D01*
X196233Y55225D01*
X196483Y55017D01*
X196900Y54850D01*
X197275Y54808D01*
X197650Y54892D01*
X197900Y55017D01*
X198150Y55267D01*
X198317Y55558D01*
X198400Y55850D01*
Y56142D01*
X198317Y56433D01*
X198192Y56683D01*
X198025Y56892D01*
G01X197900Y58033D02*
X198192Y58283D01*
X198358Y58617D01*
X198400Y58992D01*
X198358Y59325D01*
X198150Y59658D01*
X197900Y59867D01*
X197650Y59908D01*
X197358Y59825D01*
X197150Y59533D01*
X197067Y59242D01*
Y58867D01*
G01Y59242D02*
X196942Y59492D01*
X196733Y59700D01*
X196483Y59783D01*
X196233Y59700D01*
X196025Y59492D01*
X195900Y59117D01*
X195942Y58742D01*
X196108Y58367D01*
G01X198400Y62050D02*
X195900D01*
X196400Y61550D01*
G01X198400D02*
Y62550D01*
G01X196317Y64358D02*
X196067Y64608D01*
X195942Y64900D01*
X195900Y65233D01*
X195983Y65650D01*
X196192Y65942D01*
X196442Y66025D01*
X196692Y65983D01*
X196900Y65817D01*
X197317Y64983D01*
X197608Y64608D01*
X198025Y64358D01*
X198400Y64275D01*
Y66025D01*
G01X191000Y44317D02*
X188500D01*
Y45358D01*
X188625Y45692D01*
X188792Y45900D01*
X189125Y45983D01*
X189458Y45900D01*
X189667Y45650D01*
X189792Y45358D01*
Y44317D01*
G01Y45358D02*
X191000Y45983D01*
G01X190500Y47333D02*
X190792Y47583D01*
X190958Y47917D01*
X191000Y48292D01*
X190958Y48625D01*
X190750Y48958D01*
X190500Y49167D01*
X190250Y49208D01*
X189958Y49125D01*
X189750Y48833D01*
X189667Y48542D01*
Y48167D01*
G01Y48542D02*
X189542Y48792D01*
X189333Y49000D01*
X189083Y49083D01*
X188833Y49000D01*
X188625Y48792D01*
X188500Y48417D01*
X188542Y48042D01*
X188708Y47667D01*
G01X188917Y50558D02*
X188667Y50808D01*
X188542Y51100D01*
X188500Y51433D01*
X188583Y51850D01*
X188792Y52142D01*
X189042Y52225D01*
X189292Y52183D01*
X189500Y52017D01*
X189917Y51183D01*
X190208Y50808D01*
X190625Y50558D01*
X191000Y50475D01*
Y52225D01*
G01X190625Y53533D02*
X190833Y53783D01*
X190958Y54075D01*
X191000Y54450D01*
X190917Y54825D01*
X190750Y55117D01*
X190458Y55325D01*
X190125Y55367D01*
X189792Y55283D01*
X189583Y55075D01*
X189417Y54783D01*
X189375Y54492D01*
X189417Y54200D01*
X189583Y53825D01*
X188500Y53950D01*
Y55075D01*
G01X190000Y69500D02*
X197500D01*
Y67500D01*
X199000D01*
G01X198348Y121771D02*
X198298D01*
Y102271D01*
X217198D01*
Y121771D01*
X198298D01*
G01X190667Y142500D02*
X194000Y149500D01*
X197333Y142500D01*
G01X196133Y144950D02*
X191867D01*
G01X195000Y150950D02*
X199000D01*
X197000Y152950D01*
X195000Y150950D01*
G01X191350D02*
X202650D01*
Y169950D01*
X191350D01*
Y150950D01*
G01X197000Y180500D02*
X199000Y178000D01*
Y173000D01*
X200500D01*
G01X203433Y193917D02*
X202633Y194267D01*
X201700Y194500D01*
X200633D01*
X199433Y194150D01*
X198500Y193567D01*
X197833Y192867D01*
X197300Y191700D01*
X197167Y190650D01*
X197433Y189600D01*
X197833Y188900D01*
X198633Y188200D01*
X199567Y187733D01*
X200500Y187500D01*
X201433D01*
X202367Y187733D01*
X203167Y188083D01*
X203833Y188550D01*
G01X195500Y188000D02*
Y187000D01*
X191000D01*
Y188500D01*
G01X203000Y262017D02*
X200500D01*
Y263017D01*
X200625Y263350D01*
X200917Y263600D01*
X201250Y263683D01*
X201583Y263600D01*
X201833Y263392D01*
X201958Y263017D01*
Y262017D01*
G01X200708Y266867D02*
X200583Y266617D01*
X200500Y266325D01*
Y265992D01*
X200625Y265617D01*
X200833Y265325D01*
X201083Y265117D01*
X201500Y264950D01*
X201875Y264908D01*
X202250Y264992D01*
X202500Y265117D01*
X202750Y265367D01*
X202917Y265658D01*
X203000Y265950D01*
Y266242D01*
X202917Y266533D01*
X202792Y266783D01*
X202625Y266992D01*
G01X200917Y268258D02*
X200667Y268508D01*
X200542Y268800D01*
X200500Y269133D01*
X200583Y269550D01*
X200792Y269842D01*
X201042Y269925D01*
X201292Y269883D01*
X201500Y269717D01*
X201917Y268883D01*
X202208Y268508D01*
X202625Y268258D01*
X203000Y268175D01*
Y269925D01*
G01Y272150D02*
X202958Y272442D01*
X202833Y272775D01*
X202625Y272983D01*
X202333Y273067D01*
X202042Y272983D01*
X201792Y272733D01*
X201667Y272358D01*
Y271942D01*
X201583Y271692D01*
X201375Y271483D01*
X201083Y271400D01*
X200792Y271525D01*
X200583Y271817D01*
X200500Y272150D01*
X200583Y272483D01*
X200792Y272775D01*
X201083Y272900D01*
X201375Y272817D01*
X201583Y272608D01*
X201667Y272358D01*
Y271942D01*
X201792Y271567D01*
X202042Y271317D01*
X202333Y271233D01*
X202625Y271317D01*
X202833Y271525D01*
X202958Y271858D01*
X203000Y272150D01*
G01X199000Y262017D02*
X196500D01*
Y263017D01*
X196625Y263350D01*
X196917Y263600D01*
X197250Y263683D01*
X197583Y263600D01*
X197833Y263392D01*
X197958Y263017D01*
Y262017D01*
G01X196708Y266867D02*
X196583Y266617D01*
X196500Y266325D01*
Y265992D01*
X196625Y265617D01*
X196833Y265325D01*
X197083Y265117D01*
X197500Y264950D01*
X197875Y264908D01*
X198250Y264992D01*
X198500Y265117D01*
X198750Y265367D01*
X198917Y265658D01*
X199000Y265950D01*
Y266242D01*
X198917Y266533D01*
X198792Y266783D01*
X198625Y266992D01*
G01X196917Y268258D02*
X196667Y268508D01*
X196542Y268800D01*
X196500Y269133D01*
X196583Y269550D01*
X196792Y269842D01*
X197042Y269925D01*
X197292Y269883D01*
X197500Y269717D01*
X197917Y268883D01*
X198208Y268508D01*
X198625Y268258D01*
X199000Y268175D01*
Y269925D01*
G01Y272067D02*
X198458Y272150D01*
X198000Y272275D01*
X197583Y272442D01*
X197125Y272650D01*
X196500Y272983D01*
Y271317D01*
G01X218267Y44292D02*
X218017Y44417D01*
X217725Y44500D01*
X217392D01*
X217017Y44375D01*
X216725Y44167D01*
X216517Y43917D01*
X216350Y43500D01*
X216308Y43125D01*
X216392Y42750D01*
X216517Y42500D01*
X216767Y42250D01*
X217058Y42083D01*
X217350Y42000D01*
X217642D01*
X217933Y42083D01*
X218183Y42208D01*
X218392Y42375D01*
G01X219533Y42500D02*
X219783Y42208D01*
X220117Y42042D01*
X220492Y42000D01*
X220825Y42042D01*
X221158Y42250D01*
X221367Y42500D01*
X221408Y42750D01*
X221325Y43042D01*
X221033Y43250D01*
X220742Y43333D01*
X220367D01*
G01X220742D02*
X220992Y43458D01*
X221200Y43667D01*
X221283Y43917D01*
X221200Y44167D01*
X220992Y44375D01*
X220617Y44500D01*
X220242Y44458D01*
X219867Y44292D01*
G01X223550Y42000D02*
Y44500D01*
X223050Y44000D01*
G01Y42000D02*
X224050D01*
G01X225858Y43042D02*
X226150Y43333D01*
X226400Y43500D01*
X226733Y43583D01*
X227025Y43500D01*
X227233Y43333D01*
X227400Y43083D01*
X227442Y42792D01*
X227400Y42542D01*
X227233Y42292D01*
X226983Y42083D01*
X226692Y42000D01*
X226358Y42083D01*
X226067Y42333D01*
X225900Y42708D01*
X225858Y43125D01*
X225942Y43667D01*
X226067Y43958D01*
X226275Y44250D01*
X226567Y44458D01*
X226858Y44500D01*
X227150Y44417D01*
X227358Y44208D01*
G01X217000Y54500D02*
X222500D01*
Y61000D01*
X233500D01*
Y59000D01*
G01X209000Y54500D02*
X204000D01*
G01X221050Y58650D02*
Y62150D01*
X207550D01*
Y58650D01*
X221050D01*
G01X219250Y87950D02*
X207950D01*
Y68950D01*
X219250D01*
Y87950D01*
G01X215600D02*
X211600D01*
X213600Y85950D01*
X215600Y87950D01*
G01X209748Y102271D02*
X207748Y104271D01*
X205748Y102271D01*
X217198D01*
G01X215567Y150500D02*
Y153000D01*
X216608D01*
X216942Y152875D01*
X217150Y152708D01*
X217233Y152375D01*
X217150Y152042D01*
X216900Y151833D01*
X216608Y151708D01*
X215567D01*
G01X216608D02*
X217233Y150500D01*
G01X218792Y150792D02*
X219083Y150583D01*
X219417Y150500D01*
X219750Y150583D01*
X220042Y150833D01*
X220250Y151208D01*
X220333Y151583D01*
Y152042D01*
X220250Y152417D01*
X220042Y152750D01*
X219792Y152917D01*
X219500Y153000D01*
X219167Y152917D01*
X218917Y152750D01*
X218750Y152500D01*
X218667Y152167D01*
X218750Y151875D01*
X218958Y151583D01*
X219208Y151417D01*
X219500Y151375D01*
X219833Y151458D01*
X220083Y151667D01*
X220333Y152042D01*
G01X222600Y150500D02*
X222892Y150542D01*
X223225Y150667D01*
X223433Y150875D01*
X223517Y151167D01*
X223433Y151458D01*
X223183Y151708D01*
X222808Y151833D01*
X222392D01*
X222142Y151917D01*
X221933Y152125D01*
X221850Y152417D01*
X221975Y152708D01*
X222267Y152917D01*
X222600Y153000D01*
X222933Y152917D01*
X223225Y152708D01*
X223350Y152417D01*
X223267Y152125D01*
X223058Y151917D01*
X222808Y151833D01*
X222392D01*
X222017Y151708D01*
X221767Y151458D01*
X221683Y151167D01*
X221767Y150875D01*
X221975Y150667D01*
X222308Y150542D01*
X222600Y150500D01*
G01X213500Y153567D02*
X211000D01*
Y154608D01*
X211125Y154942D01*
X211292Y155150D01*
X211625Y155233D01*
X211958Y155150D01*
X212167Y154900D01*
X212292Y154608D01*
Y153567D01*
G01Y154608D02*
X213500Y155233D01*
G01Y157500D02*
X213458Y157792D01*
X213333Y158125D01*
X213125Y158333D01*
X212833Y158417D01*
X212542Y158333D01*
X212292Y158083D01*
X212167Y157708D01*
Y157292D01*
X212083Y157042D01*
X211875Y156833D01*
X211583Y156750D01*
X211292Y156875D01*
X211083Y157167D01*
X211000Y157500D01*
X211083Y157833D01*
X211292Y158125D01*
X211583Y158250D01*
X211875Y158167D01*
X212083Y157958D01*
X212167Y157708D01*
Y157292D01*
X212292Y156917D01*
X212542Y156667D01*
X212833Y156583D01*
X213125Y156667D01*
X213333Y156875D01*
X213458Y157208D01*
X213500Y157500D01*
G01Y160600D02*
X213458Y160892D01*
X213333Y161225D01*
X213125Y161433D01*
X212833Y161517D01*
X212542Y161433D01*
X212292Y161183D01*
X212167Y160808D01*
Y160392D01*
X212083Y160142D01*
X211875Y159933D01*
X211583Y159850D01*
X211292Y159975D01*
X211083Y160267D01*
X211000Y160600D01*
X211083Y160933D01*
X211292Y161225D01*
X211583Y161350D01*
X211875Y161267D01*
X212083Y161058D01*
X212167Y160808D01*
Y160392D01*
X212292Y160017D01*
X212542Y159767D01*
X212833Y159683D01*
X213125Y159767D01*
X213333Y159975D01*
X213458Y160308D01*
X213500Y160600D01*
G01X217000Y169500D02*
Y171500D01*
X223500D01*
G01X205500Y173000D02*
X211000D01*
Y168500D01*
G01X213000Y206500D02*
X213500D01*
Y197500D01*
X212500D01*
G01X207000Y195000D02*
Y197000D01*
X208500D01*
G01Y194400D02*
X208600D01*
Y186000D01*
X203000D01*
G01X221500Y218000D02*
X205000D01*
Y206500D01*
G01X207000Y258017D02*
X204500D01*
Y259017D01*
X204625Y259350D01*
X204917Y259600D01*
X205250Y259683D01*
X205583Y259600D01*
X205833Y259392D01*
X205958Y259017D01*
Y258017D01*
G01X207000Y261117D02*
X204500D01*
Y262158D01*
X204625Y262492D01*
X204792Y262700D01*
X205125Y262783D01*
X205458Y262700D01*
X205667Y262450D01*
X205792Y262158D01*
Y261117D01*
G01Y262158D02*
X207000Y262783D01*
G01X206500Y264133D02*
X206792Y264383D01*
X206958Y264717D01*
X207000Y265092D01*
X206958Y265425D01*
X206750Y265758D01*
X206500Y265967D01*
X206250Y266008D01*
X205958Y265925D01*
X205750Y265633D01*
X205667Y265342D01*
Y264967D01*
G01Y265342D02*
X205542Y265592D01*
X205333Y265800D01*
X205083Y265883D01*
X204833Y265800D01*
X204625Y265592D01*
X204500Y265217D01*
X204542Y264842D01*
X204708Y264467D01*
G01X206500Y267233D02*
X206792Y267483D01*
X206958Y267817D01*
X207000Y268192D01*
X206958Y268525D01*
X206750Y268858D01*
X206500Y269067D01*
X206250Y269108D01*
X205958Y269025D01*
X205750Y268733D01*
X205667Y268442D01*
Y268067D01*
G01Y268442D02*
X205542Y268692D01*
X205333Y268900D01*
X205083Y268983D01*
X204833Y268900D01*
X204625Y268692D01*
X204500Y268317D01*
X204542Y267942D01*
X204708Y267567D01*
G01X209017Y258000D02*
Y260500D01*
X210017D01*
X210350Y260375D01*
X210600Y260083D01*
X210683Y259750D01*
X210600Y259417D01*
X210392Y259167D01*
X210017Y259042D01*
X209017D01*
G01X213867Y260292D02*
X213617Y260417D01*
X213325Y260500D01*
X212992D01*
X212617Y260375D01*
X212325Y260167D01*
X212117Y259917D01*
X211950Y259500D01*
X211908Y259125D01*
X211992Y258750D01*
X212117Y258500D01*
X212367Y258250D01*
X212658Y258083D01*
X212950Y258000D01*
X213242D01*
X213533Y258083D01*
X213783Y258208D01*
X213992Y258375D01*
G01X215133Y258500D02*
X215383Y258208D01*
X215717Y258042D01*
X216092Y258000D01*
X216425Y258042D01*
X216758Y258250D01*
X216967Y258500D01*
X217008Y258750D01*
X216925Y259042D01*
X216633Y259250D01*
X216342Y259333D01*
X215967D01*
G01X216342D02*
X216592Y259458D01*
X216800Y259667D01*
X216883Y259917D01*
X216800Y260167D01*
X216592Y260375D01*
X216217Y260500D01*
X215842Y260458D01*
X215467Y260292D01*
G01X219150Y258000D02*
Y260500D01*
X218650Y260000D01*
G01Y258000D02*
X219650D01*
G01X203067Y251000D02*
Y253500D01*
X204067D01*
X204400Y253375D01*
X204650Y253083D01*
X204733Y252750D01*
X204650Y252417D01*
X204442Y252167D01*
X204067Y252042D01*
X203067D01*
G01X206167Y253500D02*
Y251000D01*
X207833D01*
G01X210600D02*
Y253500D01*
X209058Y251708D01*
X211142D01*
G01X228000Y67000D02*
Y92000D01*
X230500D01*
Y93000D01*
G01X230900Y62000D02*
X230567Y62042D01*
X230275Y62208D01*
X230025Y62458D01*
X229858Y62750D01*
X229775Y63083D01*
Y63417D01*
X229858Y63750D01*
X230025Y64042D01*
X230275Y64292D01*
X230567Y64458D01*
X230900Y64500D01*
X231233Y64458D01*
X231525Y64292D01*
X231775Y64042D01*
X231942Y63750D01*
X232025Y63417D01*
Y63083D01*
X231942Y62750D01*
X231775Y62458D01*
X231525Y62208D01*
X231233Y62042D01*
X230900Y62000D01*
G01X231233Y62667D02*
X231733Y62000D01*
G01X234000D02*
Y64500D01*
X233500Y64000D01*
G01Y62000D02*
X234500D01*
G01X237100D02*
X237392Y62042D01*
X237725Y62167D01*
X237933Y62375D01*
X238017Y62667D01*
X237933Y62958D01*
X237683Y63208D01*
X237308Y63333D01*
X236892D01*
X236642Y63417D01*
X236433Y63625D01*
X236350Y63917D01*
X236475Y64208D01*
X236767Y64417D01*
X237100Y64500D01*
X237433Y64417D01*
X237725Y64208D01*
X237850Y63917D01*
X237767Y63625D01*
X237558Y63417D01*
X237308Y63333D01*
X236892D01*
X236517Y63208D01*
X236267Y62958D01*
X236183Y62667D01*
X236267Y62375D01*
X236475Y62167D01*
X236808Y62042D01*
X237100Y62000D01*
G01X231900Y94000D02*
X231567Y94042D01*
X231275Y94208D01*
X231025Y94458D01*
X230858Y94750D01*
X230775Y95083D01*
Y95417D01*
X230858Y95750D01*
X231025Y96042D01*
X231275Y96292D01*
X231567Y96458D01*
X231900Y96500D01*
X232233Y96458D01*
X232525Y96292D01*
X232775Y96042D01*
X232942Y95750D01*
X233025Y95417D01*
Y95083D01*
X232942Y94750D01*
X232775Y94458D01*
X232525Y94208D01*
X232233Y94042D01*
X231900Y94000D01*
G01X232233Y94667D02*
X232733Y94000D01*
G01X235000D02*
Y96500D01*
X234500Y96000D01*
G01Y94000D02*
X235500D01*
G01X238100Y96500D02*
X237767Y96417D01*
X237517Y96208D01*
X237350Y95958D01*
X237225Y95625D01*
X237183Y95250D01*
X237225Y94875D01*
X237350Y94542D01*
X237517Y94292D01*
X237767Y94083D01*
X238100Y94000D01*
X238433Y94083D01*
X238683Y94292D01*
X238850Y94542D01*
X238975Y94875D01*
X239017Y95250D01*
X238975Y95625D01*
X238850Y95958D01*
X238683Y96208D01*
X238433Y96417D01*
X238100Y96500D01*
G01X231000Y110000D02*
Y133500D01*
G01X225017Y135500D02*
Y138000D01*
X226058D01*
X226392Y137875D01*
X226600Y137708D01*
X226683Y137375D01*
X226600Y137042D01*
X226350Y136833D01*
X226058Y136708D01*
X225017D01*
G01X226058D02*
X226683Y135500D01*
G01X228950D02*
Y138000D01*
X228450Y137500D01*
G01Y135500D02*
X229450D01*
G01X232050D02*
Y138000D01*
X231550Y137500D01*
G01Y135500D02*
X232550D01*
G01X234358Y136542D02*
X234650Y136833D01*
X234900Y137000D01*
X235233Y137083D01*
X235525Y137000D01*
X235733Y136833D01*
X235900Y136583D01*
X235942Y136292D01*
X235900Y136042D01*
X235733Y135792D01*
X235483Y135583D01*
X235192Y135500D01*
X234858Y135583D01*
X234567Y135833D01*
X234400Y136208D01*
X234358Y136625D01*
X234442Y137167D01*
X234567Y137458D01*
X234775Y137750D01*
X235067Y137958D01*
X235358Y138000D01*
X235650Y137917D01*
X235858Y137708D01*
G01X232708Y153817D02*
X232583Y153567D01*
X232500Y153275D01*
Y152942D01*
X232625Y152567D01*
X232833Y152275D01*
X233083Y152067D01*
X233500Y151900D01*
X233875Y151858D01*
X234250Y151942D01*
X234500Y152067D01*
X234750Y152317D01*
X234917Y152608D01*
X235000Y152900D01*
Y153192D01*
X234917Y153483D01*
X234792Y153733D01*
X234625Y153942D01*
G01X235000Y156000D02*
X232500D01*
X233000Y155500D01*
G01X235000D02*
Y156500D01*
G01X234708Y158392D02*
X234917Y158683D01*
X235000Y159017D01*
X234917Y159350D01*
X234667Y159642D01*
X234292Y159850D01*
X233917Y159933D01*
X233458D01*
X233083Y159850D01*
X232750Y159642D01*
X232583Y159392D01*
X232500Y159100D01*
X232583Y158767D01*
X232750Y158517D01*
X233000Y158350D01*
X233333Y158267D01*
X233625Y158350D01*
X233917Y158558D01*
X234083Y158808D01*
X234125Y159100D01*
X234042Y159433D01*
X233833Y159683D01*
X233458Y159933D01*
G01X225017Y143500D02*
Y146000D01*
X226058D01*
X226392Y145875D01*
X226600Y145708D01*
X226683Y145375D01*
X226600Y145042D01*
X226350Y144833D01*
X226058Y144708D01*
X225017D01*
G01X226058D02*
X226683Y143500D01*
G01X228950D02*
Y146000D01*
X228450Y145500D01*
G01Y143500D02*
X229450D01*
G01X232050Y146000D02*
X231717Y145917D01*
X231467Y145708D01*
X231300Y145458D01*
X231175Y145125D01*
X231133Y144750D01*
X231175Y144375D01*
X231300Y144042D01*
X231467Y143792D01*
X231717Y143583D01*
X232050Y143500D01*
X232383Y143583D01*
X232633Y143792D01*
X232800Y144042D01*
X232925Y144375D01*
X232967Y144750D01*
X232925Y145125D01*
X232800Y145458D01*
X232633Y145708D01*
X232383Y145917D01*
X232050Y146000D01*
G01X234358Y144542D02*
X234650Y144833D01*
X234900Y145000D01*
X235233Y145083D01*
X235525Y145000D01*
X235733Y144833D01*
X235900Y144583D01*
X235942Y144292D01*
X235900Y144042D01*
X235733Y143792D01*
X235483Y143583D01*
X235192Y143500D01*
X234858Y143583D01*
X234567Y143833D01*
X234400Y144208D01*
X234358Y144625D01*
X234442Y145167D01*
X234567Y145458D01*
X234775Y145750D01*
X235067Y145958D01*
X235358Y146000D01*
X235650Y145917D01*
X235858Y145708D01*
G01X225017Y147500D02*
Y150000D01*
X226058D01*
X226392Y149875D01*
X226600Y149708D01*
X226683Y149375D01*
X226600Y149042D01*
X226350Y148833D01*
X226058Y148708D01*
X225017D01*
G01X226058D02*
X226683Y147500D01*
G01X228950D02*
Y150000D01*
X228450Y149500D01*
G01Y147500D02*
X229450D01*
G01X232050Y150000D02*
X231717Y149917D01*
X231467Y149708D01*
X231300Y149458D01*
X231175Y149125D01*
X231133Y148750D01*
X231175Y148375D01*
X231300Y148042D01*
X231467Y147792D01*
X231717Y147583D01*
X232050Y147500D01*
X232383Y147583D01*
X232633Y147792D01*
X232800Y148042D01*
X232925Y148375D01*
X232967Y148750D01*
X232925Y149125D01*
X232800Y149458D01*
X232633Y149708D01*
X232383Y149917D01*
X232050Y150000D01*
G01X235150Y147500D02*
Y150000D01*
X234650Y149500D01*
G01Y147500D02*
X235650D01*
G01X225017Y139500D02*
Y142000D01*
X226058D01*
X226392Y141875D01*
X226600Y141708D01*
X226683Y141375D01*
X226600Y141042D01*
X226350Y140833D01*
X226058Y140708D01*
X225017D01*
G01X226058D02*
X226683Y139500D01*
G01X228950D02*
Y142000D01*
X228450Y141500D01*
G01Y139500D02*
X229450D01*
G01X232050D02*
Y142000D01*
X231550Y141500D01*
G01Y139500D02*
X232550D01*
G01X235150Y142000D02*
X234817Y141917D01*
X234567Y141708D01*
X234400Y141458D01*
X234275Y141125D01*
X234233Y140750D01*
X234275Y140375D01*
X234400Y140042D01*
X234567Y139792D01*
X234817Y139583D01*
X235150Y139500D01*
X235483Y139583D01*
X235733Y139792D01*
X235900Y140042D01*
X236025Y140375D01*
X236067Y140750D01*
X236025Y141125D01*
X235900Y141458D01*
X235733Y141708D01*
X235483Y141917D01*
X235150Y142000D01*
G01X224500Y175000D02*
Y180500D01*
X238000D01*
Y198000D01*
X263500D01*
G01X278500Y222000D02*
X265500D01*
Y211500D01*
X233500D01*
Y213500D01*
X230000D01*
Y217500D01*
X228500D01*
G01X234000Y230517D02*
X231500D01*
Y231517D01*
X231625Y231850D01*
X231917Y232100D01*
X232250Y232183D01*
X232583Y232100D01*
X232833Y231892D01*
X232958Y231517D01*
Y230517D01*
G01X231708Y235367D02*
X231583Y235117D01*
X231500Y234825D01*
Y234492D01*
X231625Y234117D01*
X231833Y233825D01*
X232083Y233617D01*
X232500Y233450D01*
X232875Y233408D01*
X233250Y233492D01*
X233500Y233617D01*
X233750Y233867D01*
X233917Y234158D01*
X234000Y234450D01*
Y234742D01*
X233917Y235033D01*
X233792Y235283D01*
X233625Y235492D01*
G01Y236633D02*
X233833Y236883D01*
X233958Y237175D01*
X234000Y237550D01*
X233917Y237925D01*
X233750Y238217D01*
X233458Y238425D01*
X233125Y238467D01*
X232792Y238383D01*
X232583Y238175D01*
X232417Y237883D01*
X232375Y237592D01*
X232417Y237300D01*
X232583Y236925D01*
X231500Y237050D01*
Y238175D01*
G01X233708Y239942D02*
X233917Y240233D01*
X234000Y240567D01*
X233917Y240900D01*
X233667Y241192D01*
X233292Y241400D01*
X232917Y241483D01*
X232458D01*
X232083Y241400D01*
X231750Y241192D01*
X231583Y240942D01*
X231500Y240650D01*
X231583Y240317D01*
X231750Y240067D01*
X232000Y239900D01*
X232333Y239817D01*
X232625Y239900D01*
X232917Y240108D01*
X233083Y240358D01*
X233125Y240650D01*
X233042Y240983D01*
X232833Y241233D01*
X232458Y241483D01*
G01X227500Y230467D02*
X225000D01*
Y231467D01*
X225125Y231800D01*
X225417Y232050D01*
X225750Y232133D01*
X226083Y232050D01*
X226333Y231842D01*
X226458Y231467D01*
Y230467D01*
G01X225208Y235317D02*
X225083Y235067D01*
X225000Y234775D01*
Y234442D01*
X225125Y234067D01*
X225333Y233775D01*
X225583Y233567D01*
X226000Y233400D01*
X226375Y233358D01*
X226750Y233442D01*
X227000Y233567D01*
X227250Y233817D01*
X227417Y234108D01*
X227500Y234400D01*
Y234692D01*
X227417Y234983D01*
X227292Y235233D01*
X227125Y235442D01*
G01X227500Y237500D02*
X225000D01*
X225500Y237000D01*
G01X227500D02*
Y238000D01*
G01Y241100D02*
X225000D01*
X226792Y239558D01*
Y241642D01*
G01X227125Y242783D02*
X227333Y243033D01*
X227458Y243325D01*
X227500Y243700D01*
X227417Y244075D01*
X227250Y244367D01*
X226958Y244575D01*
X226625Y244617D01*
X226292Y244533D01*
X226083Y244325D01*
X225917Y244033D01*
X225875Y243742D01*
X225917Y243450D01*
X226083Y243075D01*
X225000Y243200D01*
Y244325D01*
G01X229500Y258517D02*
X227000D01*
Y259517D01*
X227125Y259850D01*
X227417Y260100D01*
X227750Y260183D01*
X228083Y260100D01*
X228333Y259892D01*
X228458Y259517D01*
Y258517D01*
G01X227208Y263367D02*
X227083Y263117D01*
X227000Y262825D01*
Y262492D01*
X227125Y262117D01*
X227333Y261825D01*
X227583Y261617D01*
X228000Y261450D01*
X228375Y261408D01*
X228750Y261492D01*
X229000Y261617D01*
X229250Y261867D01*
X229417Y262158D01*
X229500Y262450D01*
Y262742D01*
X229417Y263033D01*
X229292Y263283D01*
X229125Y263492D01*
G01X229000Y264633D02*
X229292Y264883D01*
X229458Y265217D01*
X229500Y265592D01*
X229458Y265925D01*
X229250Y266258D01*
X229000Y266467D01*
X228750Y266508D01*
X228458Y266425D01*
X228250Y266133D01*
X228167Y265842D01*
Y265467D01*
G01Y265842D02*
X228042Y266092D01*
X227833Y266300D01*
X227583Y266383D01*
X227333Y266300D01*
X227125Y266092D01*
X227000Y265717D01*
X227042Y265342D01*
X227208Y264967D01*
G01X229500Y268567D02*
X228958Y268650D01*
X228500Y268775D01*
X228083Y268942D01*
X227625Y269150D01*
X227000Y269483D01*
Y267817D01*
G01X221708Y257867D02*
X221583Y257617D01*
X221500Y257325D01*
Y256992D01*
X221625Y256617D01*
X221833Y256325D01*
X222083Y256117D01*
X222500Y255950D01*
X222875Y255908D01*
X223250Y255992D01*
X223500Y256117D01*
X223750Y256367D01*
X223917Y256658D01*
X224000Y256950D01*
Y257242D01*
X223917Y257533D01*
X223792Y257783D01*
X223625Y257992D01*
G01X223708Y259342D02*
X223917Y259633D01*
X224000Y259967D01*
X223917Y260300D01*
X223667Y260592D01*
X223292Y260800D01*
X222917Y260883D01*
X222458D01*
X222083Y260800D01*
X221750Y260592D01*
X221583Y260342D01*
X221500Y260050D01*
X221583Y259717D01*
X221750Y259467D01*
X222000Y259300D01*
X222333Y259217D01*
X222625Y259300D01*
X222917Y259508D01*
X223083Y259758D01*
X223125Y260050D01*
X223042Y260383D01*
X222833Y260633D01*
X222458Y260883D01*
G01X242000Y41983D02*
X243792D01*
X244167Y42150D01*
X244417Y42483D01*
X244500Y42900D01*
X244417Y43317D01*
X244167Y43650D01*
X243792Y43817D01*
X242000D01*
G01X244000Y45083D02*
X244292Y45333D01*
X244458Y45667D01*
X244500Y46042D01*
X244458Y46375D01*
X244250Y46708D01*
X244000Y46917D01*
X243750Y46958D01*
X243458Y46875D01*
X243250Y46583D01*
X243167Y46292D01*
Y45917D01*
G01Y46292D02*
X243042Y46542D01*
X242833Y46750D01*
X242583Y46833D01*
X242333Y46750D01*
X242125Y46542D01*
X242000Y46167D01*
X242042Y45792D01*
X242208Y45417D01*
G01X244500Y49600D02*
X242000D01*
X243792Y48058D01*
Y50142D01*
G01X238500Y41850D02*
X241000D01*
G01X238500Y40892D02*
Y42808D01*
G01X241000Y44117D02*
X238500D01*
Y45117D01*
X238625Y45450D01*
X238917Y45700D01*
X239250Y45783D01*
X239583Y45700D01*
X239833Y45492D01*
X239958Y45117D01*
Y44117D01*
G01X240625Y47133D02*
X240833Y47383D01*
X240958Y47675D01*
X241000Y48050D01*
X240917Y48425D01*
X240750Y48717D01*
X240458Y48925D01*
X240125Y48967D01*
X239792Y48883D01*
X239583Y48675D01*
X239417Y48383D01*
X239375Y48092D01*
X239417Y47800D01*
X239583Y47425D01*
X238500Y47550D01*
Y48675D01*
G01X241000Y51150D02*
X240958Y51442D01*
X240833Y51775D01*
X240625Y51983D01*
X240333Y52067D01*
X240042Y51983D01*
X239792Y51733D01*
X239667Y51358D01*
Y50942D01*
X239583Y50692D01*
X239375Y50483D01*
X239083Y50400D01*
X238792Y50525D01*
X238583Y50817D01*
X238500Y51150D01*
X238583Y51483D01*
X238792Y51775D01*
X239083Y51900D01*
X239375Y51817D01*
X239583Y51608D01*
X239667Y51358D01*
Y50942D01*
X239792Y50567D01*
X240042Y50317D01*
X240333Y50233D01*
X240625Y50317D01*
X240833Y50525D01*
X240958Y50858D01*
X241000Y51150D01*
G01X248000Y41517D02*
X245500D01*
Y42558D01*
X245625Y42892D01*
X245792Y43100D01*
X246125Y43183D01*
X246458Y43100D01*
X246667Y42850D01*
X246792Y42558D01*
Y41517D01*
G01Y42558D02*
X248000Y43183D01*
G01Y45950D02*
X245500D01*
X247292Y44408D01*
Y46492D01*
G01X248000Y48550D02*
X247958Y48842D01*
X247833Y49175D01*
X247625Y49383D01*
X247333Y49467D01*
X247042Y49383D01*
X246792Y49133D01*
X246667Y48758D01*
Y48342D01*
X246583Y48092D01*
X246375Y47883D01*
X246083Y47800D01*
X245792Y47925D01*
X245583Y48217D01*
X245500Y48550D01*
X245583Y48883D01*
X245792Y49175D01*
X246083Y49300D01*
X246375Y49217D01*
X246583Y49008D01*
X246667Y48758D01*
Y48342D01*
X246792Y47967D01*
X247042Y47717D01*
X247333Y47633D01*
X247625Y47717D01*
X247833Y47925D01*
X247958Y48258D01*
X248000Y48550D01*
G01Y51650D02*
X245500D01*
X246000Y51150D01*
G01X248000D02*
Y52150D01*
G01X237000Y41517D02*
X234500D01*
Y42558D01*
X234625Y42892D01*
X234792Y43100D01*
X235125Y43183D01*
X235458Y43100D01*
X235667Y42850D01*
X235792Y42558D01*
Y41517D01*
G01Y42558D02*
X237000Y43183D01*
G01Y45950D02*
X234500D01*
X236292Y44408D01*
Y46492D01*
G01X237000Y48550D02*
X234500D01*
X235000Y48050D01*
G01X237000D02*
Y49050D01*
G01X234917Y50858D02*
X234667Y51108D01*
X234542Y51400D01*
X234500Y51733D01*
X234583Y52150D01*
X234792Y52442D01*
X235042Y52525D01*
X235292Y52483D01*
X235500Y52317D01*
X235917Y51483D01*
X236208Y51108D01*
X236625Y50858D01*
X237000Y50775D01*
Y52525D01*
G01X242000Y55500D02*
X242500D01*
Y53500D01*
X248000D01*
G01X247708Y59767D02*
X247583Y59517D01*
X247500Y59225D01*
Y58892D01*
X247625Y58517D01*
X247833Y58225D01*
X248083Y58017D01*
X248500Y57850D01*
X248875Y57808D01*
X249250Y57892D01*
X249500Y58017D01*
X249750Y58267D01*
X249917Y58558D01*
X250000Y58850D01*
Y59142D01*
X249917Y59433D01*
X249792Y59683D01*
X249625Y59892D01*
G01X249500Y61033D02*
X249792Y61283D01*
X249958Y61617D01*
X250000Y61992D01*
X249958Y62325D01*
X249750Y62658D01*
X249500Y62867D01*
X249250Y62908D01*
X248958Y62825D01*
X248750Y62533D01*
X248667Y62242D01*
Y61867D01*
G01Y62242D02*
X248542Y62492D01*
X248333Y62700D01*
X248083Y62783D01*
X247833Y62700D01*
X247625Y62492D01*
X247500Y62117D01*
X247542Y61742D01*
X247708Y61367D01*
G01X247500Y65050D02*
X247583Y64717D01*
X247792Y64467D01*
X248042Y64300D01*
X248375Y64175D01*
X248750Y64133D01*
X249125Y64175D01*
X249458Y64300D01*
X249708Y64467D01*
X249917Y64717D01*
X250000Y65050D01*
X249917Y65383D01*
X249708Y65633D01*
X249458Y65800D01*
X249125Y65925D01*
X248750Y65967D01*
X248375Y65925D01*
X248042Y65800D01*
X247792Y65633D01*
X247583Y65383D01*
X247500Y65050D01*
G01X250000Y68150D02*
X249958Y68442D01*
X249833Y68775D01*
X249625Y68983D01*
X249333Y69067D01*
X249042Y68983D01*
X248792Y68733D01*
X248667Y68358D01*
Y67942D01*
X248583Y67692D01*
X248375Y67483D01*
X248083Y67400D01*
X247792Y67525D01*
X247583Y67817D01*
X247500Y68150D01*
X247583Y68483D01*
X247792Y68775D01*
X248083Y68900D01*
X248375Y68817D01*
X248583Y68608D01*
X248667Y68358D01*
Y67942D01*
X248792Y67567D01*
X249042Y67317D01*
X249333Y67233D01*
X249625Y67317D01*
X249833Y67525D01*
X249958Y67858D01*
X250000Y68150D01*
G01X246017Y74500D02*
Y77000D01*
X247058D01*
X247392Y76875D01*
X247600Y76708D01*
X247683Y76375D01*
X247600Y76042D01*
X247350Y75833D01*
X247058Y75708D01*
X246017D01*
G01X247058D02*
X247683Y74500D01*
G01X249950D02*
Y77000D01*
X249450Y76500D01*
G01Y74500D02*
X250450D01*
G01X252967D02*
X253050Y75042D01*
X253175Y75500D01*
X253342Y75917D01*
X253550Y76375D01*
X253883Y77000D01*
X252217D01*
G01X256650Y74500D02*
Y77000D01*
X255108Y75208D01*
X257192D01*
G01X246017Y70500D02*
Y73000D01*
X247058D01*
X247392Y72875D01*
X247600Y72708D01*
X247683Y72375D01*
X247600Y72042D01*
X247350Y71833D01*
X247058Y71708D01*
X246017D01*
G01X247058D02*
X247683Y70500D01*
G01X249950D02*
Y73000D01*
X249450Y72500D01*
G01Y70500D02*
X250450D01*
G01X253050D02*
X253342Y70542D01*
X253675Y70667D01*
X253883Y70875D01*
X253967Y71167D01*
X253883Y71458D01*
X253633Y71708D01*
X253258Y71833D01*
X252842D01*
X252592Y71917D01*
X252383Y72125D01*
X252300Y72417D01*
X252425Y72708D01*
X252717Y72917D01*
X253050Y73000D01*
X253383Y72917D01*
X253675Y72708D01*
X253800Y72417D01*
X253717Y72125D01*
X253508Y71917D01*
X253258Y71833D01*
X252842D01*
X252467Y71708D01*
X252217Y71458D01*
X252133Y71167D01*
X252217Y70875D01*
X252425Y70667D01*
X252758Y70542D01*
X253050Y70500D01*
G01X256150Y73000D02*
X255817Y72917D01*
X255567Y72708D01*
X255400Y72458D01*
X255275Y72125D01*
X255233Y71750D01*
X255275Y71375D01*
X255400Y71042D01*
X255567Y70792D01*
X255817Y70583D01*
X256150Y70500D01*
X256483Y70583D01*
X256733Y70792D01*
X256900Y71042D01*
X257025Y71375D01*
X257067Y71750D01*
X257025Y72125D01*
X256900Y72458D01*
X256733Y72708D01*
X256483Y72917D01*
X256150Y73000D01*
G01X238750Y92750D02*
X235250D01*
Y79250D01*
X238750D01*
Y92750D01*
G01X241517Y79000D02*
Y81500D01*
X242558D01*
X242892Y81375D01*
X243100Y81208D01*
X243183Y80875D01*
X243100Y80542D01*
X242850Y80333D01*
X242558Y80208D01*
X241517D01*
G01X242558D02*
X243183Y79000D01*
G01X244658Y81083D02*
X244908Y81333D01*
X245200Y81458D01*
X245533Y81500D01*
X245950Y81417D01*
X246242Y81208D01*
X246325Y80958D01*
X246283Y80708D01*
X246117Y80500D01*
X245283Y80083D01*
X244908Y79792D01*
X244658Y79375D01*
X244575Y79000D01*
X246325D01*
G01X247633Y79375D02*
X247883Y79167D01*
X248175Y79042D01*
X248550Y79000D01*
X248925Y79083D01*
X249217Y79250D01*
X249425Y79542D01*
X249467Y79875D01*
X249383Y80208D01*
X249175Y80417D01*
X248883Y80583D01*
X248592Y80625D01*
X248300Y80583D01*
X247925Y80417D01*
X248050Y81500D01*
X249175D01*
G01X251567Y79000D02*
X251650Y79542D01*
X251775Y80000D01*
X251942Y80417D01*
X252150Y80875D01*
X252483Y81500D01*
X250817D01*
G01X244517Y83000D02*
Y85500D01*
X245558D01*
X245892Y85375D01*
X246100Y85208D01*
X246183Y84875D01*
X246100Y84542D01*
X245850Y84333D01*
X245558Y84208D01*
X244517D01*
G01X245558D02*
X246183Y83000D01*
G01X247658Y85083D02*
X247908Y85333D01*
X248200Y85458D01*
X248533Y85500D01*
X248950Y85417D01*
X249242Y85208D01*
X249325Y84958D01*
X249283Y84708D01*
X249117Y84500D01*
X248283Y84083D01*
X247908Y83792D01*
X247658Y83375D01*
X247575Y83000D01*
X249325D01*
G01X250633Y83375D02*
X250883Y83167D01*
X251175Y83042D01*
X251550Y83000D01*
X251925Y83083D01*
X252217Y83250D01*
X252425Y83542D01*
X252467Y83875D01*
X252383Y84208D01*
X252175Y84417D01*
X251883Y84583D01*
X251592Y84625D01*
X251300Y84583D01*
X250925Y84417D01*
X251050Y85500D01*
X252175D01*
G01X253858Y84042D02*
X254150Y84333D01*
X254400Y84500D01*
X254733Y84583D01*
X255025Y84500D01*
X255233Y84333D01*
X255400Y84083D01*
X255442Y83792D01*
X255400Y83542D01*
X255233Y83292D01*
X254983Y83083D01*
X254692Y83000D01*
X254358Y83083D01*
X254067Y83333D01*
X253900Y83708D01*
X253858Y84125D01*
X253942Y84667D01*
X254067Y84958D01*
X254275Y85250D01*
X254567Y85458D01*
X254858Y85500D01*
X255150Y85417D01*
X255358Y85208D01*
G01X239000Y107550D02*
X241200D01*
Y121050D01*
X239000D01*
Y107550D01*
G01X239950Y132000D02*
X239617Y132042D01*
X239325Y132208D01*
X239075Y132458D01*
X238908Y132750D01*
X238825Y133083D01*
Y133417D01*
X238908Y133750D01*
X239075Y134042D01*
X239325Y134292D01*
X239617Y134458D01*
X239950Y134500D01*
X240283Y134458D01*
X240575Y134292D01*
X240825Y134042D01*
X240992Y133750D01*
X241075Y133417D01*
Y133083D01*
X240992Y132750D01*
X240825Y132458D01*
X240575Y132208D01*
X240283Y132042D01*
X239950Y132000D01*
G01X240283Y132667D02*
X240783Y132000D01*
G01X242967D02*
X243050Y132542D01*
X243175Y133000D01*
X243342Y133417D01*
X243550Y133875D01*
X243883Y134500D01*
X242217D01*
G01X239375Y139833D02*
X239708Y139625D01*
X240083Y139500D01*
X240417D01*
X240750Y139625D01*
X241000Y139833D01*
X241125Y140125D01*
X241042Y140417D01*
X240833Y140667D01*
X240458Y140833D01*
X239958Y140917D01*
X239667Y141083D01*
X239542Y141375D01*
X239625Y141667D01*
X239833Y141875D01*
X240125Y142000D01*
X240417D01*
X240708Y141917D01*
X240958Y141708D01*
G01X242433Y139500D02*
Y142000D01*
G01X244017D02*
X242433Y140458D01*
G01X244267Y139500D02*
X243142Y141167D01*
G01X246450Y142000D02*
Y139500D01*
G01X245492Y142000D02*
X247408D01*
G01X249550Y139500D02*
Y142000D01*
X249050Y141500D01*
G01Y139500D02*
X250050D01*
G01X252650Y139417D02*
X252567Y139458D01*
Y139542D01*
X252650Y139583D01*
X252733Y139542D01*
Y139458D01*
X252650Y139417D01*
G01Y140542D02*
X252567Y140583D01*
Y140667D01*
X252650Y140708D01*
X252733Y140667D01*
Y140583D01*
X252650Y140542D01*
G01X256083Y140833D02*
X256250Y140958D01*
X256375Y141167D01*
X256458Y141458D01*
X256375Y141708D01*
X256208Y141875D01*
X255917Y142000D01*
X254792D01*
Y139500D01*
X256167D01*
X256458Y139667D01*
X256625Y139917D01*
X256708Y140208D01*
X256625Y140500D01*
X256375Y140750D01*
X256083Y140833D01*
X254792D01*
G01X258350Y142000D02*
X259350D01*
G01X258850D02*
Y139500D01*
G01X258350D02*
X259350D01*
G01X261950D02*
X261617Y139542D01*
X261325Y139708D01*
X261075Y139958D01*
X260908Y140250D01*
X260825Y140583D01*
Y140917D01*
X260908Y141250D01*
X261075Y141542D01*
X261325Y141792D01*
X261617Y141958D01*
X261950Y142000D01*
X262283Y141958D01*
X262575Y141792D01*
X262825Y141542D01*
X262992Y141250D01*
X263075Y140917D01*
Y140583D01*
X262992Y140250D01*
X262825Y139958D01*
X262575Y139708D01*
X262283Y139542D01*
X261950Y139500D01*
G01X264175Y139833D02*
X264508Y139625D01*
X264883Y139500D01*
X265217D01*
X265550Y139625D01*
X265800Y139833D01*
X265925Y140125D01*
X265842Y140417D01*
X265633Y140667D01*
X265258Y140833D01*
X264758Y140917D01*
X264467Y141083D01*
X264342Y141375D01*
X264425Y141667D01*
X264633Y141875D01*
X264925Y142000D01*
X265217D01*
X265508Y141917D01*
X265758Y141708D01*
G01X236500Y151983D02*
X238292D01*
X238667Y152150D01*
X238917Y152483D01*
X239000Y152900D01*
X238917Y153317D01*
X238667Y153650D01*
X238292Y153817D01*
X236500D01*
G01X239000Y156000D02*
X236500D01*
X237000Y155500D01*
G01X239000D02*
Y156500D01*
G01Y159100D02*
X236500D01*
X237000Y158600D01*
G01X239000D02*
Y159600D01*
G01X247000Y152067D02*
X244500D01*
Y153108D01*
X244625Y153442D01*
X244792Y153650D01*
X245125Y153733D01*
X245458Y153650D01*
X245667Y153400D01*
X245792Y153108D01*
Y152067D01*
G01Y153108D02*
X247000Y153733D01*
G01X246500Y155083D02*
X246792Y155333D01*
X246958Y155667D01*
X247000Y156042D01*
X246958Y156375D01*
X246750Y156708D01*
X246500Y156917D01*
X246250Y156958D01*
X245958Y156875D01*
X245750Y156583D01*
X245667Y156292D01*
Y155917D01*
G01Y156292D02*
X245542Y156542D01*
X245333Y156750D01*
X245083Y156833D01*
X244833Y156750D01*
X244625Y156542D01*
X244500Y156167D01*
X244542Y155792D01*
X244708Y155417D01*
G01X245958Y158308D02*
X245667Y158600D01*
X245500Y158850D01*
X245417Y159183D01*
X245500Y159475D01*
X245667Y159683D01*
X245917Y159850D01*
X246208Y159892D01*
X246458Y159850D01*
X246708Y159683D01*
X246917Y159433D01*
X247000Y159142D01*
X246917Y158808D01*
X246667Y158517D01*
X246292Y158350D01*
X245875Y158308D01*
X245333Y158392D01*
X245042Y158517D01*
X244750Y158725D01*
X244542Y159017D01*
X244500Y159308D01*
X244583Y159600D01*
X244792Y159808D01*
G01X243000Y152067D02*
X240500D01*
Y153108D01*
X240625Y153442D01*
X240792Y153650D01*
X241125Y153733D01*
X241458Y153650D01*
X241667Y153400D01*
X241792Y153108D01*
Y152067D01*
G01Y153108D02*
X243000Y153733D01*
G01X241958Y155208D02*
X241667Y155500D01*
X241500Y155750D01*
X241417Y156083D01*
X241500Y156375D01*
X241667Y156583D01*
X241917Y156750D01*
X242208Y156792D01*
X242458Y156750D01*
X242708Y156583D01*
X242917Y156333D01*
X243000Y156042D01*
X242917Y155708D01*
X242667Y155417D01*
X242292Y155250D01*
X241875Y155208D01*
X241333Y155292D01*
X241042Y155417D01*
X240750Y155625D01*
X240542Y155917D01*
X240500Y156208D01*
X240583Y156500D01*
X240792Y156708D01*
G01X243000Y159600D02*
X240500D01*
X242292Y158058D01*
Y160142D01*
G01X240708Y182817D02*
X240583Y182567D01*
X240500Y182275D01*
Y181942D01*
X240625Y181567D01*
X240833Y181275D01*
X241083Y181067D01*
X241500Y180900D01*
X241875Y180858D01*
X242250Y180942D01*
X242500Y181067D01*
X242750Y181317D01*
X242917Y181608D01*
X243000Y181900D01*
Y182192D01*
X242917Y182483D01*
X242792Y182733D01*
X242625Y182942D01*
G01X243000Y184917D02*
X242458Y185000D01*
X242000Y185125D01*
X241583Y185292D01*
X241125Y185500D01*
X240500Y185833D01*
Y184167D01*
G01X240917Y187308D02*
X240667Y187558D01*
X240542Y187850D01*
X240500Y188183D01*
X240583Y188600D01*
X240792Y188892D01*
X241042Y188975D01*
X241292Y188933D01*
X241500Y188767D01*
X241917Y187933D01*
X242208Y187558D01*
X242625Y187308D01*
X243000Y187225D01*
Y188975D01*
G01X254650Y176650D02*
X243800D01*
Y168350D01*
X254650D01*
Y176650D01*
G01X243800Y176500D02*
Y168500D01*
G01X244900Y172500D02*
X243800Y173600D01*
G01X244900Y172500D02*
X243800Y171400D01*
G01X251000Y188567D02*
X248500D01*
Y189608D01*
X248625Y189942D01*
X248792Y190150D01*
X249125Y190233D01*
X249458Y190150D01*
X249667Y189900D01*
X249792Y189608D01*
Y188567D01*
G01Y189608D02*
X251000Y190233D01*
G01X250500Y191583D02*
X250792Y191833D01*
X250958Y192167D01*
X251000Y192542D01*
X250958Y192875D01*
X250750Y193208D01*
X250500Y193417D01*
X250250Y193458D01*
X249958Y193375D01*
X249750Y193083D01*
X249667Y192792D01*
Y192417D01*
G01Y192792D02*
X249542Y193042D01*
X249333Y193250D01*
X249083Y193333D01*
X248833Y193250D01*
X248625Y193042D01*
X248500Y192667D01*
X248542Y192292D01*
X248708Y191917D01*
G01X250625Y194683D02*
X250833Y194933D01*
X250958Y195225D01*
X251000Y195600D01*
X250917Y195975D01*
X250750Y196267D01*
X250458Y196475D01*
X250125Y196517D01*
X249792Y196433D01*
X249583Y196225D01*
X249417Y195933D01*
X249375Y195642D01*
X249417Y195350D01*
X249583Y194975D01*
X248500Y195100D01*
Y196225D01*
G01X250500Y230517D02*
X248000D01*
Y231517D01*
X248125Y231850D01*
X248417Y232100D01*
X248750Y232183D01*
X249083Y232100D01*
X249333Y231892D01*
X249458Y231517D01*
Y230517D01*
G01X250500Y233617D02*
X248000D01*
Y234658D01*
X248125Y234992D01*
X248292Y235200D01*
X248625Y235283D01*
X248958Y235200D01*
X249167Y234950D01*
X249292Y234658D01*
Y233617D01*
G01Y234658D02*
X250500Y235283D01*
G01Y237467D02*
X249958Y237550D01*
X249500Y237675D01*
X249083Y237842D01*
X248625Y238050D01*
X248000Y238383D01*
Y236717D01*
G01X250500Y240650D02*
X250458Y240942D01*
X250333Y241275D01*
X250125Y241483D01*
X249833Y241567D01*
X249542Y241483D01*
X249292Y241233D01*
X249167Y240858D01*
Y240442D01*
X249083Y240192D01*
X248875Y239983D01*
X248583Y239900D01*
X248292Y240025D01*
X248083Y240317D01*
X248000Y240650D01*
X248083Y240983D01*
X248292Y241275D01*
X248583Y241400D01*
X248875Y241317D01*
X249083Y241108D01*
X249167Y240858D01*
Y240442D01*
X249292Y240067D01*
X249542Y239817D01*
X249833Y239733D01*
X250125Y239817D01*
X250333Y240025D01*
X250458Y240358D01*
X250500Y240650D01*
G01X242500Y230517D02*
X240000D01*
Y231517D01*
X240125Y231850D01*
X240417Y232100D01*
X240750Y232183D01*
X241083Y232100D01*
X241333Y231892D01*
X241458Y231517D01*
Y230517D01*
G01X240208Y235367D02*
X240083Y235117D01*
X240000Y234825D01*
Y234492D01*
X240125Y234117D01*
X240333Y233825D01*
X240583Y233617D01*
X241000Y233450D01*
X241375Y233408D01*
X241750Y233492D01*
X242000Y233617D01*
X242250Y233867D01*
X242417Y234158D01*
X242500Y234450D01*
Y234742D01*
X242417Y235033D01*
X242292Y235283D01*
X242125Y235492D01*
G01X241458Y236758D02*
X241167Y237050D01*
X241000Y237300D01*
X240917Y237633D01*
X241000Y237925D01*
X241167Y238133D01*
X241417Y238300D01*
X241708Y238342D01*
X241958Y238300D01*
X242208Y238133D01*
X242417Y237883D01*
X242500Y237592D01*
X242417Y237258D01*
X242167Y236967D01*
X241792Y236800D01*
X241375Y236758D01*
X240833Y236842D01*
X240542Y236967D01*
X240250Y237175D01*
X240042Y237467D01*
X240000Y237758D01*
X240083Y238050D01*
X240292Y238258D01*
G01X240000Y240650D02*
X240083Y240317D01*
X240292Y240067D01*
X240542Y239900D01*
X240875Y239775D01*
X241250Y239733D01*
X241625Y239775D01*
X241958Y239900D01*
X242208Y240067D01*
X242417Y240317D01*
X242500Y240650D01*
X242417Y240983D01*
X242208Y241233D01*
X241958Y241400D01*
X241625Y241525D01*
X241250Y241567D01*
X240875Y241525D01*
X240542Y241400D01*
X240292Y241233D01*
X240083Y240983D01*
X240000Y240650D01*
G01X246500Y230467D02*
X244000D01*
Y231467D01*
X244125Y231800D01*
X244417Y232050D01*
X244750Y232133D01*
X245083Y232050D01*
X245333Y231842D01*
X245458Y231467D01*
Y230467D01*
G01X244208Y235317D02*
X244083Y235067D01*
X244000Y234775D01*
Y234442D01*
X244125Y234067D01*
X244333Y233775D01*
X244583Y233567D01*
X245000Y233400D01*
X245375Y233358D01*
X245750Y233442D01*
X246000Y233567D01*
X246250Y233817D01*
X246417Y234108D01*
X246500Y234400D01*
Y234692D01*
X246417Y234983D01*
X246292Y235233D01*
X246125Y235442D01*
G01X246500Y237500D02*
X244000D01*
X244500Y237000D01*
G01X246500D02*
Y238000D01*
G01Y241100D02*
X244000D01*
X245792Y239558D01*
Y241642D01*
G01X246500Y244200D02*
X244000D01*
X245792Y242658D01*
Y244742D01*
G01X245000Y258017D02*
X242500D01*
Y259017D01*
X242625Y259350D01*
X242917Y259600D01*
X243250Y259683D01*
X243583Y259600D01*
X243833Y259392D01*
X243958Y259017D01*
Y258017D01*
G01X242708Y262867D02*
X242583Y262617D01*
X242500Y262325D01*
Y261992D01*
X242625Y261617D01*
X242833Y261325D01*
X243083Y261117D01*
X243500Y260950D01*
X243875Y260908D01*
X244250Y260992D01*
X244500Y261117D01*
X244750Y261367D01*
X244917Y261658D01*
X245000Y261950D01*
Y262242D01*
X244917Y262533D01*
X244792Y262783D01*
X244625Y262992D01*
G01X244500Y264133D02*
X244792Y264383D01*
X244958Y264717D01*
X245000Y265092D01*
X244958Y265425D01*
X244750Y265758D01*
X244500Y265967D01*
X244250Y266008D01*
X243958Y265925D01*
X243750Y265633D01*
X243667Y265342D01*
Y264967D01*
G01Y265342D02*
X243542Y265592D01*
X243333Y265800D01*
X243083Y265883D01*
X242833Y265800D01*
X242625Y265592D01*
X242500Y265217D01*
X242542Y264842D01*
X242708Y264467D01*
G01X245000Y268150D02*
X244958Y268442D01*
X244833Y268775D01*
X244625Y268983D01*
X244333Y269067D01*
X244042Y268983D01*
X243792Y268733D01*
X243667Y268358D01*
Y267942D01*
X243583Y267692D01*
X243375Y267483D01*
X243083Y267400D01*
X242792Y267525D01*
X242583Y267817D01*
X242500Y268150D01*
X242583Y268483D01*
X242792Y268775D01*
X243083Y268900D01*
X243375Y268817D01*
X243583Y268608D01*
X243667Y268358D01*
Y267942D01*
X243792Y267567D01*
X244042Y267317D01*
X244333Y267233D01*
X244625Y267317D01*
X244833Y267525D01*
X244958Y267858D01*
X245000Y268150D01*
G01X237500Y258517D02*
X235000D01*
Y259517D01*
X235125Y259850D01*
X235417Y260100D01*
X235750Y260183D01*
X236083Y260100D01*
X236333Y259892D01*
X236458Y259517D01*
Y258517D01*
G01X235208Y263367D02*
X235083Y263117D01*
X235000Y262825D01*
Y262492D01*
X235125Y262117D01*
X235333Y261825D01*
X235583Y261617D01*
X236000Y261450D01*
X236375Y261408D01*
X236750Y261492D01*
X237000Y261617D01*
X237250Y261867D01*
X237417Y262158D01*
X237500Y262450D01*
Y262742D01*
X237417Y263033D01*
X237292Y263283D01*
X237125Y263492D01*
G01X237000Y264633D02*
X237292Y264883D01*
X237458Y265217D01*
X237500Y265592D01*
X237458Y265925D01*
X237250Y266258D01*
X237000Y266467D01*
X236750Y266508D01*
X236458Y266425D01*
X236250Y266133D01*
X236167Y265842D01*
Y265467D01*
G01Y265842D02*
X236042Y266092D01*
X235833Y266300D01*
X235583Y266383D01*
X235333Y266300D01*
X235125Y266092D01*
X235000Y265717D01*
X235042Y265342D01*
X235208Y264967D01*
G01X237208Y267942D02*
X237417Y268233D01*
X237500Y268567D01*
X237417Y268900D01*
X237167Y269192D01*
X236792Y269400D01*
X236417Y269483D01*
X235958D01*
X235583Y269400D01*
X235250Y269192D01*
X235083Y268942D01*
X235000Y268650D01*
X235083Y268317D01*
X235250Y268067D01*
X235500Y267900D01*
X235833Y267817D01*
X236125Y267900D01*
X236417Y268108D01*
X236583Y268358D01*
X236625Y268650D01*
X236542Y268983D01*
X236333Y269233D01*
X235958Y269483D01*
G01X252000Y49500D02*
Y41500D01*
X250500D01*
G01X258767Y43292D02*
X258517Y43417D01*
X258225Y43500D01*
X257892D01*
X257517Y43375D01*
X257225Y43167D01*
X257017Y42917D01*
X256850Y42500D01*
X256808Y42125D01*
X256892Y41750D01*
X257017Y41500D01*
X257267Y41250D01*
X257558Y41083D01*
X257850Y41000D01*
X258142D01*
X258433Y41083D01*
X258683Y41208D01*
X258892Y41375D01*
G01X260033Y41500D02*
X260283Y41208D01*
X260617Y41042D01*
X260992Y41000D01*
X261325Y41042D01*
X261658Y41250D01*
X261867Y41500D01*
X261908Y41750D01*
X261825Y42042D01*
X261533Y42250D01*
X261242Y42333D01*
X260867D01*
G01X261242D02*
X261492Y42458D01*
X261700Y42667D01*
X261783Y42917D01*
X261700Y43167D01*
X261492Y43375D01*
X261117Y43500D01*
X260742Y43458D01*
X260367Y43292D01*
G01X263133Y41500D02*
X263383Y41208D01*
X263717Y41042D01*
X264092Y41000D01*
X264425Y41042D01*
X264758Y41250D01*
X264967Y41500D01*
X265008Y41750D01*
X264925Y42042D01*
X264633Y42250D01*
X264342Y42333D01*
X263967D01*
G01X264342D02*
X264592Y42458D01*
X264800Y42667D01*
X264883Y42917D01*
X264800Y43167D01*
X264592Y43375D01*
X264217Y43500D01*
X263842Y43458D01*
X263467Y43292D01*
G01X267150Y41000D02*
X267442Y41042D01*
X267775Y41167D01*
X267983Y41375D01*
X268067Y41667D01*
X267983Y41958D01*
X267733Y42208D01*
X267358Y42333D01*
X266942D01*
X266692Y42417D01*
X266483Y42625D01*
X266400Y42917D01*
X266525Y43208D01*
X266817Y43417D01*
X267150Y43500D01*
X267483Y43417D01*
X267775Y43208D01*
X267900Y42917D01*
X267817Y42625D01*
X267608Y42417D01*
X267358Y42333D01*
X266942D01*
X266567Y42208D01*
X266317Y41958D01*
X266233Y41667D01*
X266317Y41375D01*
X266525Y41167D01*
X266858Y41042D01*
X267150Y41000D01*
G01X254517Y44500D02*
Y47000D01*
X255558D01*
X255892Y46875D01*
X256100Y46708D01*
X256183Y46375D01*
X256100Y46042D01*
X255850Y45833D01*
X255558Y45708D01*
X254517D01*
G01X255558D02*
X256183Y44500D01*
G01X258950D02*
Y47000D01*
X257408Y45208D01*
X259492D01*
G01X261467Y44500D02*
X261550Y45042D01*
X261675Y45500D01*
X261842Y45917D01*
X262050Y46375D01*
X262383Y47000D01*
X260717D01*
G01X265150Y44500D02*
Y47000D01*
X263608Y45208D01*
X265692D01*
G01X251708Y59767D02*
X251583Y59517D01*
X251500Y59225D01*
Y58892D01*
X251625Y58517D01*
X251833Y58225D01*
X252083Y58017D01*
X252500Y57850D01*
X252875Y57808D01*
X253250Y57892D01*
X253500Y58017D01*
X253750Y58267D01*
X253917Y58558D01*
X254000Y58850D01*
Y59142D01*
X253917Y59433D01*
X253792Y59683D01*
X253625Y59892D01*
G01X253500Y61033D02*
X253792Y61283D01*
X253958Y61617D01*
X254000Y61992D01*
X253958Y62325D01*
X253750Y62658D01*
X253500Y62867D01*
X253250Y62908D01*
X252958Y62825D01*
X252750Y62533D01*
X252667Y62242D01*
Y61867D01*
G01Y62242D02*
X252542Y62492D01*
X252333Y62700D01*
X252083Y62783D01*
X251833Y62700D01*
X251625Y62492D01*
X251500Y62117D01*
X251542Y61742D01*
X251708Y61367D01*
G01X251500Y65050D02*
X251583Y64717D01*
X251792Y64467D01*
X252042Y64300D01*
X252375Y64175D01*
X252750Y64133D01*
X253125Y64175D01*
X253458Y64300D01*
X253708Y64467D01*
X253917Y64717D01*
X254000Y65050D01*
X253917Y65383D01*
X253708Y65633D01*
X253458Y65800D01*
X253125Y65925D01*
X252750Y65967D01*
X252375Y65925D01*
X252042Y65800D01*
X251792Y65633D01*
X251583Y65383D01*
X251500Y65050D01*
G01X254000Y68067D02*
X253458Y68150D01*
X253000Y68275D01*
X252583Y68442D01*
X252125Y68650D01*
X251500Y68983D01*
Y67317D01*
G01X260500Y55517D02*
X258000D01*
Y56558D01*
X258125Y56892D01*
X258292Y57100D01*
X258625Y57183D01*
X258958Y57100D01*
X259167Y56850D01*
X259292Y56558D01*
Y55517D01*
G01Y56558D02*
X260500Y57183D01*
G01Y59950D02*
X258000D01*
X259792Y58408D01*
Y60492D01*
G01X260500Y62467D02*
X259958Y62550D01*
X259500Y62675D01*
X259083Y62842D01*
X258625Y63050D01*
X258000Y63383D01*
Y61717D01*
G01X260125Y64733D02*
X260333Y64983D01*
X260458Y65275D01*
X260500Y65650D01*
X260417Y66025D01*
X260250Y66317D01*
X259958Y66525D01*
X259625Y66567D01*
X259292Y66483D01*
X259083Y66275D01*
X258917Y65983D01*
X258875Y65692D01*
X258917Y65400D01*
X259083Y65025D01*
X258000Y65150D01*
Y66275D01*
G01X264200Y77517D02*
X261700D01*
Y78558D01*
X261825Y78892D01*
X261992Y79100D01*
X262325Y79183D01*
X262658Y79100D01*
X262867Y78850D01*
X262992Y78558D01*
Y77517D01*
G01Y78558D02*
X264200Y79183D01*
G01Y81450D02*
X261700D01*
X262200Y80950D01*
G01X264200D02*
Y81950D01*
G01X263825Y83633D02*
X264033Y83883D01*
X264158Y84175D01*
X264200Y84550D01*
X264117Y84925D01*
X263950Y85217D01*
X263658Y85425D01*
X263325Y85467D01*
X262992Y85383D01*
X262783Y85175D01*
X262617Y84883D01*
X262575Y84592D01*
X262617Y84300D01*
X262783Y83925D01*
X261700Y84050D01*
Y85175D01*
G01X264200Y87567D02*
X263658Y87650D01*
X263200Y87775D01*
X262783Y87942D01*
X262325Y88150D01*
X261700Y88483D01*
Y86817D01*
G01X254550Y112550D02*
X251050D01*
Y99050D01*
X254550D01*
Y112550D01*
G01X258017Y100500D02*
Y103000D01*
X259058D01*
X259392Y102875D01*
X259600Y102708D01*
X259683Y102375D01*
X259600Y102042D01*
X259350Y101833D01*
X259058Y101708D01*
X258017D01*
G01X259058D02*
X259683Y100500D01*
G01X261158Y102583D02*
X261408Y102833D01*
X261700Y102958D01*
X262033Y103000D01*
X262450Y102917D01*
X262742Y102708D01*
X262825Y102458D01*
X262783Y102208D01*
X262617Y102000D01*
X261783Y101583D01*
X261408Y101292D01*
X261158Y100875D01*
X261075Y100500D01*
X262825D01*
G01X264133Y100875D02*
X264383Y100667D01*
X264675Y100542D01*
X265050Y100500D01*
X265425Y100583D01*
X265717Y100750D01*
X265925Y101042D01*
X265967Y101375D01*
X265883Y101708D01*
X265675Y101917D01*
X265383Y102083D01*
X265092Y102125D01*
X264800Y102083D01*
X264425Y101917D01*
X264550Y103000D01*
X265675D01*
G01X267233Y100875D02*
X267483Y100667D01*
X267775Y100542D01*
X268150Y100500D01*
X268525Y100583D01*
X268817Y100750D01*
X269025Y101042D01*
X269067Y101375D01*
X268983Y101708D01*
X268775Y101917D01*
X268483Y102083D01*
X268192Y102125D01*
X267900Y102083D01*
X267525Y101917D01*
X267650Y103000D01*
X268775D01*
G01X258017Y96000D02*
Y98500D01*
X259058D01*
X259392Y98375D01*
X259600Y98208D01*
X259683Y97875D01*
X259600Y97542D01*
X259350Y97333D01*
X259058Y97208D01*
X258017D01*
G01X259058D02*
X259683Y96000D01*
G01X261158Y98083D02*
X261408Y98333D01*
X261700Y98458D01*
X262033Y98500D01*
X262450Y98417D01*
X262742Y98208D01*
X262825Y97958D01*
X262783Y97708D01*
X262617Y97500D01*
X261783Y97083D01*
X261408Y96792D01*
X261158Y96375D01*
X261075Y96000D01*
X262825D01*
G01X264133Y96375D02*
X264383Y96167D01*
X264675Y96042D01*
X265050Y96000D01*
X265425Y96083D01*
X265717Y96250D01*
X265925Y96542D01*
X265967Y96875D01*
X265883Y97208D01*
X265675Y97417D01*
X265383Y97583D01*
X265092Y97625D01*
X264800Y97583D01*
X264425Y97417D01*
X264550Y98500D01*
X265675D01*
G01X267233Y96500D02*
X267483Y96208D01*
X267817Y96042D01*
X268192Y96000D01*
X268525Y96042D01*
X268858Y96250D01*
X269067Y96500D01*
X269108Y96750D01*
X269025Y97042D01*
X268733Y97250D01*
X268442Y97333D01*
X268067D01*
G01X268442D02*
X268692Y97458D01*
X268900Y97667D01*
X268983Y97917D01*
X268900Y98167D01*
X268692Y98375D01*
X268317Y98500D01*
X267942Y98458D01*
X267567Y98292D01*
G01X258500Y115450D02*
X258458Y115117D01*
X258292Y114825D01*
X258042Y114575D01*
X257750Y114408D01*
X257417Y114325D01*
X257083D01*
X256750Y114408D01*
X256458Y114575D01*
X256208Y114825D01*
X256042Y115117D01*
X256000Y115450D01*
X256042Y115783D01*
X256208Y116075D01*
X256458Y116325D01*
X256750Y116492D01*
X257083Y116575D01*
X257417D01*
X257750Y116492D01*
X258042Y116325D01*
X258292Y116075D01*
X258458Y115783D01*
X258500Y115450D01*
G01X257833Y115783D02*
X258500Y116283D01*
G01Y118550D02*
X258458Y118842D01*
X258333Y119175D01*
X258125Y119383D01*
X257833Y119467D01*
X257542Y119383D01*
X257292Y119133D01*
X257167Y118758D01*
Y118342D01*
X257083Y118092D01*
X256875Y117883D01*
X256583Y117800D01*
X256292Y117925D01*
X256083Y118217D01*
X256000Y118550D01*
X256083Y118883D01*
X256292Y119175D01*
X256583Y119300D01*
X256875Y119217D01*
X257083Y119008D01*
X257167Y118758D01*
Y118342D01*
X257292Y117967D01*
X257542Y117717D01*
X257833Y117633D01*
X258125Y117717D01*
X258333Y117925D01*
X258458Y118258D01*
X258500Y118550D01*
G01X260708Y114767D02*
X260583Y114517D01*
X260500Y114225D01*
Y113892D01*
X260625Y113517D01*
X260833Y113225D01*
X261083Y113017D01*
X261500Y112850D01*
X261875Y112808D01*
X262250Y112892D01*
X262500Y113017D01*
X262750Y113267D01*
X262917Y113558D01*
X263000Y113850D01*
Y114142D01*
X262917Y114433D01*
X262792Y114683D01*
X262625Y114892D01*
G01X263000Y116950D02*
X260500D01*
X261000Y116450D01*
G01X263000D02*
Y117450D01*
G01Y120050D02*
X260500D01*
X261000Y119550D01*
G01X263000D02*
Y120550D01*
G01X262500Y122233D02*
X262792Y122483D01*
X262958Y122817D01*
X263000Y123192D01*
X262958Y123525D01*
X262750Y123858D01*
X262500Y124067D01*
X262250Y124108D01*
X261958Y124025D01*
X261750Y123733D01*
X261667Y123442D01*
Y123067D01*
G01Y123442D02*
X261542Y123692D01*
X261333Y123900D01*
X261083Y123983D01*
X260833Y123900D01*
X260625Y123692D01*
X260500Y123317D01*
X260542Y122942D01*
X260708Y122567D01*
G01X261517Y126500D02*
Y129000D01*
X262558D01*
X262892Y128875D01*
X263100Y128708D01*
X263183Y128375D01*
X263100Y128042D01*
X262850Y127833D01*
X262558Y127708D01*
X261517D01*
G01X262558D02*
X263183Y126500D01*
G01X264658Y128583D02*
X264908Y128833D01*
X265200Y128958D01*
X265533Y129000D01*
X265950Y128917D01*
X266242Y128708D01*
X266325Y128458D01*
X266283Y128208D01*
X266117Y128000D01*
X265283Y127583D01*
X264908Y127292D01*
X264658Y126875D01*
X264575Y126500D01*
X266325D01*
G01X269050D02*
Y129000D01*
X267508Y127208D01*
X269592D01*
G01X271650Y129000D02*
X271317Y128917D01*
X271067Y128708D01*
X270900Y128458D01*
X270775Y128125D01*
X270733Y127750D01*
X270775Y127375D01*
X270900Y127042D01*
X271067Y126792D01*
X271317Y126583D01*
X271650Y126500D01*
X271983Y126583D01*
X272233Y126792D01*
X272400Y127042D01*
X272525Y127375D01*
X272567Y127750D01*
X272525Y128125D01*
X272400Y128458D01*
X272233Y128708D01*
X271983Y128917D01*
X271650Y129000D01*
G01X261517Y130500D02*
Y133000D01*
X262558D01*
X262892Y132875D01*
X263100Y132708D01*
X263183Y132375D01*
X263100Y132042D01*
X262850Y131833D01*
X262558Y131708D01*
X261517D01*
G01X262558D02*
X263183Y130500D01*
G01X264658Y132583D02*
X264908Y132833D01*
X265200Y132958D01*
X265533Y133000D01*
X265950Y132917D01*
X266242Y132708D01*
X266325Y132458D01*
X266283Y132208D01*
X266117Y132000D01*
X265283Y131583D01*
X264908Y131292D01*
X264658Y130875D01*
X264575Y130500D01*
X266325D01*
G01X267633Y131000D02*
X267883Y130708D01*
X268217Y130542D01*
X268592Y130500D01*
X268925Y130542D01*
X269258Y130750D01*
X269467Y131000D01*
X269508Y131250D01*
X269425Y131542D01*
X269133Y131750D01*
X268842Y131833D01*
X268467D01*
G01X268842D02*
X269092Y131958D01*
X269300Y132167D01*
X269383Y132417D01*
X269300Y132667D01*
X269092Y132875D01*
X268717Y133000D01*
X268342Y132958D01*
X267967Y132792D01*
G01X270942Y130792D02*
X271233Y130583D01*
X271567Y130500D01*
X271900Y130583D01*
X272192Y130833D01*
X272400Y131208D01*
X272483Y131583D01*
Y132042D01*
X272400Y132417D01*
X272192Y132750D01*
X271942Y132917D01*
X271650Y133000D01*
X271317Y132917D01*
X271067Y132750D01*
X270900Y132500D01*
X270817Y132167D01*
X270900Y131875D01*
X271108Y131583D01*
X271358Y131417D01*
X271650Y131375D01*
X271983Y131458D01*
X272233Y131667D01*
X272483Y132042D01*
G01X252000Y151983D02*
X253792D01*
X254167Y152150D01*
X254417Y152483D01*
X254500Y152900D01*
X254417Y153317D01*
X254167Y153650D01*
X253792Y153817D01*
X252000D01*
G01X254000Y155083D02*
X254292Y155333D01*
X254458Y155667D01*
X254500Y156042D01*
X254458Y156375D01*
X254250Y156708D01*
X254000Y156917D01*
X253750Y156958D01*
X253458Y156875D01*
X253250Y156583D01*
X253167Y156292D01*
Y155917D01*
G01Y156292D02*
X253042Y156542D01*
X252833Y156750D01*
X252583Y156833D01*
X252333Y156750D01*
X252125Y156542D01*
X252000Y156167D01*
X252042Y155792D01*
X252208Y155417D01*
G01X254000Y158183D02*
X254292Y158433D01*
X254458Y158767D01*
X254500Y159142D01*
X254458Y159475D01*
X254250Y159808D01*
X254000Y160017D01*
X253750Y160058D01*
X253458Y159975D01*
X253250Y159683D01*
X253167Y159392D01*
Y159017D01*
G01Y159392D02*
X253042Y159642D01*
X252833Y159850D01*
X252583Y159933D01*
X252333Y159850D01*
X252125Y159642D01*
X252000Y159267D01*
X252042Y158892D01*
X252208Y158517D01*
G01X256167Y151800D02*
Y154300D01*
X257208D01*
X257542Y154175D01*
X257750Y154008D01*
X257833Y153675D01*
X257750Y153342D01*
X257500Y153133D01*
X257208Y153008D01*
X256167D01*
G01X257208D02*
X257833Y151800D01*
G01X260600D02*
Y154300D01*
X259058Y152508D01*
X261142D01*
G01X262492Y152092D02*
X262783Y151883D01*
X263117Y151800D01*
X263450Y151883D01*
X263742Y152133D01*
X263950Y152508D01*
X264033Y152883D01*
Y153342D01*
X263950Y153717D01*
X263742Y154050D01*
X263492Y154217D01*
X263200Y154300D01*
X262867Y154217D01*
X262617Y154050D01*
X262450Y153800D01*
X262367Y153467D01*
X262450Y153175D01*
X262658Y152883D01*
X262908Y152717D01*
X263200Y152675D01*
X263533Y152758D01*
X263783Y152967D01*
X264033Y153342D01*
G01X264067Y144500D02*
Y147000D01*
X265108D01*
X265442Y146875D01*
X265650Y146708D01*
X265733Y146375D01*
X265650Y146042D01*
X265400Y145833D01*
X265108Y145708D01*
X264067D01*
G01X265108D02*
X265733Y144500D01*
G01X267292Y144792D02*
X267583Y144583D01*
X267917Y144500D01*
X268250Y144583D01*
X268542Y144833D01*
X268750Y145208D01*
X268833Y145583D01*
Y146042D01*
X268750Y146417D01*
X268542Y146750D01*
X268292Y146917D01*
X268000Y147000D01*
X267667Y146917D01*
X267417Y146750D01*
X267250Y146500D01*
X267167Y146167D01*
X267250Y145875D01*
X267458Y145583D01*
X267708Y145417D01*
X268000Y145375D01*
X268333Y145458D01*
X268583Y145667D01*
X268833Y146042D01*
G01X270392Y144792D02*
X270683Y144583D01*
X271017Y144500D01*
X271350Y144583D01*
X271642Y144833D01*
X271850Y145208D01*
X271933Y145583D01*
Y146042D01*
X271850Y146417D01*
X271642Y146750D01*
X271392Y146917D01*
X271100Y147000D01*
X270767Y146917D01*
X270517Y146750D01*
X270350Y146500D01*
X270267Y146167D01*
X270350Y145875D01*
X270558Y145583D01*
X270808Y145417D01*
X271100Y145375D01*
X271433Y145458D01*
X271683Y145667D01*
X271933Y146042D01*
G01X264067Y161300D02*
Y163800D01*
X265108D01*
X265442Y163675D01*
X265650Y163508D01*
X265733Y163175D01*
X265650Y162842D01*
X265400Y162633D01*
X265108Y162508D01*
X264067D01*
G01X265108D02*
X265733Y161300D01*
G01X267083Y161675D02*
X267333Y161467D01*
X267625Y161342D01*
X268000Y161300D01*
X268375Y161383D01*
X268667Y161550D01*
X268875Y161842D01*
X268917Y162175D01*
X268833Y162508D01*
X268625Y162717D01*
X268333Y162883D01*
X268042Y162925D01*
X267750Y162883D01*
X267375Y162717D01*
X267500Y163800D01*
X268625D01*
G01X271100D02*
X270767Y163717D01*
X270517Y163508D01*
X270350Y163258D01*
X270225Y162925D01*
X270183Y162550D01*
X270225Y162175D01*
X270350Y161842D01*
X270517Y161592D01*
X270767Y161383D01*
X271100Y161300D01*
X271433Y161383D01*
X271683Y161592D01*
X271850Y161842D01*
X271975Y162175D01*
X272017Y162550D01*
X271975Y162925D01*
X271850Y163258D01*
X271683Y163508D01*
X271433Y163717D01*
X271100Y163800D01*
G01X269000Y183000D02*
Y189500D01*
X267500D01*
Y193500D01*
X263500D01*
Y198000D01*
G01X260000Y187033D02*
X261792D01*
X262167Y187200D01*
X262417Y187533D01*
X262500Y187950D01*
X262417Y188367D01*
X262167Y188700D01*
X261792Y188867D01*
X260000D01*
G01X262208Y190342D02*
X262417Y190633D01*
X262500Y190967D01*
X262417Y191300D01*
X262167Y191592D01*
X261792Y191800D01*
X261417Y191883D01*
X260958D01*
X260583Y191800D01*
X260250Y191592D01*
X260083Y191342D01*
X260000Y191050D01*
X260083Y190717D01*
X260250Y190467D01*
X260500Y190300D01*
X260833Y190217D01*
X261125Y190300D01*
X261417Y190508D01*
X261583Y190758D01*
X261625Y191050D01*
X261542Y191383D01*
X261333Y191633D01*
X260958Y191883D01*
G01X255000Y189067D02*
X252500D01*
Y190108D01*
X252625Y190442D01*
X252792Y190650D01*
X253125Y190733D01*
X253458Y190650D01*
X253667Y190400D01*
X253792Y190108D01*
Y189067D01*
G01Y190108D02*
X255000Y190733D01*
G01Y193500D02*
X252500D01*
X254292Y191958D01*
Y194042D01*
G01X252500Y196100D02*
X252583Y195767D01*
X252792Y195517D01*
X253042Y195350D01*
X253375Y195225D01*
X253750Y195183D01*
X254125Y195225D01*
X254458Y195350D01*
X254708Y195517D01*
X254917Y195767D01*
X255000Y196100D01*
X254917Y196433D01*
X254708Y196683D01*
X254458Y196850D01*
X254125Y196975D01*
X253750Y197017D01*
X253375Y196975D01*
X253042Y196850D01*
X252792Y196683D01*
X252583Y196433D01*
X252500Y196100D01*
G01X265067Y203400D02*
X259733D01*
Y210400D01*
X265067D01*
G01X262933Y207017D02*
X259733D01*
G01X262500Y232017D02*
X260000D01*
Y233058D01*
X260125Y233392D01*
X260292Y233600D01*
X260625Y233683D01*
X260958Y233600D01*
X261167Y233350D01*
X261292Y233058D01*
Y232017D01*
G01Y233058D02*
X262500Y233683D01*
G01Y236450D02*
X260000D01*
X261792Y234908D01*
Y236992D01*
G01X262500Y238967D02*
X261958Y239050D01*
X261500Y239175D01*
X261083Y239342D01*
X260625Y239550D01*
X260000Y239883D01*
Y238217D01*
G01X262000Y241233D02*
X262292Y241483D01*
X262458Y241817D01*
X262500Y242192D01*
X262458Y242525D01*
X262250Y242858D01*
X262000Y243067D01*
X261750Y243108D01*
X261458Y243025D01*
X261250Y242733D01*
X261167Y242442D01*
Y242067D01*
G01Y242442D02*
X261042Y242692D01*
X260833Y242900D01*
X260583Y242983D01*
X260333Y242900D01*
X260125Y242692D01*
X260000Y242317D01*
X260042Y241942D01*
X260208Y241567D01*
G01X259200Y257967D02*
X256700D01*
Y258967D01*
X256825Y259300D01*
X257117Y259550D01*
X257450Y259633D01*
X257783Y259550D01*
X258033Y259342D01*
X258158Y258967D01*
Y257967D01*
G01X256908Y262817D02*
X256783Y262567D01*
X256700Y262275D01*
Y261942D01*
X256825Y261567D01*
X257033Y261275D01*
X257283Y261067D01*
X257700Y260900D01*
X258075Y260858D01*
X258450Y260942D01*
X258700Y261067D01*
X258950Y261317D01*
X259117Y261608D01*
X259200Y261900D01*
Y262192D01*
X259117Y262483D01*
X258992Y262733D01*
X258825Y262942D01*
G01X259200Y265000D02*
X256700D01*
X257200Y264500D01*
G01X259200D02*
Y265500D01*
G01X258700Y267183D02*
X258992Y267433D01*
X259158Y267767D01*
X259200Y268142D01*
X259158Y268475D01*
X258950Y268808D01*
X258700Y269017D01*
X258450Y269058D01*
X258158Y268975D01*
X257950Y268683D01*
X257867Y268392D01*
Y268017D01*
G01Y268392D02*
X257742Y268642D01*
X257533Y268850D01*
X257283Y268933D01*
X257033Y268850D01*
X256825Y268642D01*
X256700Y268267D01*
X256742Y267892D01*
X256908Y267517D01*
G01X258158Y270408D02*
X257867Y270700D01*
X257700Y270950D01*
X257617Y271283D01*
X257700Y271575D01*
X257867Y271783D01*
X258117Y271950D01*
X258408Y271992D01*
X258658Y271950D01*
X258908Y271783D01*
X259117Y271533D01*
X259200Y271242D01*
X259117Y270908D01*
X258867Y270617D01*
X258492Y270450D01*
X258075Y270408D01*
X257533Y270492D01*
X257242Y270617D01*
X256950Y270825D01*
X256742Y271117D01*
X256700Y271408D01*
X256783Y271700D01*
X256992Y271908D01*
G01X252100Y258017D02*
X249600D01*
Y259017D01*
X249725Y259350D01*
X250017Y259600D01*
X250350Y259683D01*
X250683Y259600D01*
X250933Y259392D01*
X251058Y259017D01*
Y258017D01*
G01X249808Y262867D02*
X249683Y262617D01*
X249600Y262325D01*
Y261992D01*
X249725Y261617D01*
X249933Y261325D01*
X250183Y261117D01*
X250600Y260950D01*
X250975Y260908D01*
X251350Y260992D01*
X251600Y261117D01*
X251850Y261367D01*
X252017Y261658D01*
X252100Y261950D01*
Y262242D01*
X252017Y262533D01*
X251892Y262783D01*
X251725Y262992D01*
G01X252100Y265050D02*
X249600D01*
X250100Y264550D01*
G01X252100D02*
Y265550D01*
G01X251600Y267233D02*
X251892Y267483D01*
X252058Y267817D01*
X252100Y268192D01*
X252058Y268525D01*
X251850Y268858D01*
X251600Y269067D01*
X251350Y269108D01*
X251058Y269025D01*
X250850Y268733D01*
X250767Y268442D01*
Y268067D01*
G01Y268442D02*
X250642Y268692D01*
X250433Y268900D01*
X250183Y268983D01*
X249933Y268900D01*
X249725Y268692D01*
X249600Y268317D01*
X249642Y267942D01*
X249808Y267567D01*
G01X251725Y270333D02*
X251933Y270583D01*
X252058Y270875D01*
X252100Y271250D01*
X252017Y271625D01*
X251850Y271917D01*
X251558Y272125D01*
X251225Y272167D01*
X250892Y272083D01*
X250683Y271875D01*
X250517Y271583D01*
X250475Y271292D01*
X250517Y271000D01*
X250683Y270625D01*
X249600Y270750D01*
Y271875D01*
G01X264017Y252500D02*
Y255000D01*
X265058D01*
X265392Y254875D01*
X265600Y254708D01*
X265683Y254375D01*
X265600Y254042D01*
X265350Y253833D01*
X265058Y253708D01*
X264017D01*
G01X265058D02*
X265683Y252500D01*
G01X267950D02*
Y255000D01*
X267450Y254500D01*
G01Y252500D02*
X268450D01*
G01X271550D02*
Y255000D01*
X270008Y253208D01*
X272092D01*
G01X273358Y253542D02*
X273650Y253833D01*
X273900Y254000D01*
X274233Y254083D01*
X274525Y254000D01*
X274733Y253833D01*
X274900Y253583D01*
X274942Y253292D01*
X274900Y253042D01*
X274733Y252792D01*
X274483Y252583D01*
X274192Y252500D01*
X273858Y252583D01*
X273567Y252833D01*
X273400Y253208D01*
X273358Y253625D01*
X273442Y254167D01*
X273567Y254458D01*
X273775Y254750D01*
X274067Y254958D01*
X274358Y255000D01*
X274650Y254917D01*
X274858Y254708D01*
G01X264017Y248500D02*
Y251000D01*
X265058D01*
X265392Y250875D01*
X265600Y250708D01*
X265683Y250375D01*
X265600Y250042D01*
X265350Y249833D01*
X265058Y249708D01*
X264017D01*
G01X265058D02*
X265683Y248500D01*
G01X267033Y248875D02*
X267283Y248667D01*
X267575Y248542D01*
X267950Y248500D01*
X268325Y248583D01*
X268617Y248750D01*
X268825Y249042D01*
X268867Y249375D01*
X268783Y249708D01*
X268575Y249917D01*
X268283Y250083D01*
X267992Y250125D01*
X267700Y250083D01*
X267325Y249917D01*
X267450Y251000D01*
X268575D01*
G01X271050D02*
X270717Y250917D01*
X270467Y250708D01*
X270300Y250458D01*
X270175Y250125D01*
X270133Y249750D01*
X270175Y249375D01*
X270300Y249042D01*
X270467Y248792D01*
X270717Y248583D01*
X271050Y248500D01*
X271383Y248583D01*
X271633Y248792D01*
X271800Y249042D01*
X271925Y249375D01*
X271967Y249750D01*
X271925Y250125D01*
X271800Y250458D01*
X271633Y250708D01*
X271383Y250917D01*
X271050Y251000D01*
G01X273233Y249000D02*
X273483Y248708D01*
X273817Y248542D01*
X274192Y248500D01*
X274525Y248542D01*
X274858Y248750D01*
X275067Y249000D01*
X275108Y249250D01*
X275025Y249542D01*
X274733Y249750D01*
X274442Y249833D01*
X274067D01*
G01X274442D02*
X274692Y249958D01*
X274900Y250167D01*
X274983Y250417D01*
X274900Y250667D01*
X274692Y250875D01*
X274317Y251000D01*
X273942Y250958D01*
X273567Y250792D01*
G01X263317Y267792D02*
X263067Y267917D01*
X262775Y268000D01*
X262442D01*
X262067Y267875D01*
X261775Y267667D01*
X261567Y267417D01*
X261400Y267000D01*
X261358Y266625D01*
X261442Y266250D01*
X261567Y266000D01*
X261817Y265750D01*
X262108Y265583D01*
X262400Y265500D01*
X262692D01*
X262983Y265583D01*
X263233Y265708D01*
X263442Y265875D01*
G01X264542Y265500D02*
Y268000D01*
X266458Y265500D01*
Y268000D01*
G01X268600Y265500D02*
Y268000D01*
X268100Y267500D01*
G01Y265500D02*
X269100D01*
G01X261483Y263500D02*
Y261708D01*
X261650Y261333D01*
X261983Y261083D01*
X262400Y261000D01*
X262817Y261083D01*
X263150Y261333D01*
X263317Y261708D01*
Y263500D01*
G01X265500Y261000D02*
Y263500D01*
X265000Y263000D01*
G01Y261000D02*
X266000D01*
G01X267892Y261292D02*
X268183Y261083D01*
X268517Y261000D01*
X268850Y261083D01*
X269142Y261333D01*
X269350Y261708D01*
X269433Y262083D01*
Y262542D01*
X269350Y262917D01*
X269142Y263250D01*
X268892Y263417D01*
X268600Y263500D01*
X268267Y263417D01*
X268017Y263250D01*
X267850Y263000D01*
X267767Y262667D01*
X267850Y262375D01*
X268058Y262083D01*
X268308Y261917D01*
X268600Y261875D01*
X268933Y261958D01*
X269183Y262167D01*
X269433Y262542D01*
G01X271600Y54450D02*
Y46550D01*
X274400D01*
Y54450D01*
X271600D01*
G01X265017Y58000D02*
Y60500D01*
X266058D01*
X266392Y60375D01*
X266600Y60208D01*
X266683Y59875D01*
X266600Y59542D01*
X266350Y59333D01*
X266058Y59208D01*
X265017D01*
G01X266058D02*
X266683Y58000D01*
G01X269450D02*
Y60500D01*
X267908Y58708D01*
X269992D01*
G01X271258Y59042D02*
X271550Y59333D01*
X271800Y59500D01*
X272133Y59583D01*
X272425Y59500D01*
X272633Y59333D01*
X272800Y59083D01*
X272842Y58792D01*
X272800Y58542D01*
X272633Y58292D01*
X272383Y58083D01*
X272092Y58000D01*
X271758Y58083D01*
X271467Y58333D01*
X271300Y58708D01*
X271258Y59125D01*
X271342Y59667D01*
X271467Y59958D01*
X271675Y60250D01*
X271967Y60458D01*
X272258Y60500D01*
X272550Y60417D01*
X272758Y60208D01*
G01X275650Y58000D02*
Y60500D01*
X274108Y58708D01*
X276192D01*
G01X265017Y62000D02*
Y64500D01*
X266058D01*
X266392Y64375D01*
X266600Y64208D01*
X266683Y63875D01*
X266600Y63542D01*
X266350Y63333D01*
X266058Y63208D01*
X265017D01*
G01X266058D02*
X266683Y62000D01*
G01X269450D02*
Y64500D01*
X267908Y62708D01*
X269992D01*
G01X271258Y63042D02*
X271550Y63333D01*
X271800Y63500D01*
X272133Y63583D01*
X272425Y63500D01*
X272633Y63333D01*
X272800Y63083D01*
X272842Y62792D01*
X272800Y62542D01*
X272633Y62292D01*
X272383Y62083D01*
X272092Y62000D01*
X271758Y62083D01*
X271467Y62333D01*
X271300Y62708D01*
X271258Y63125D01*
X271342Y63667D01*
X271467Y63958D01*
X271675Y64250D01*
X271967Y64458D01*
X272258Y64500D01*
X272550Y64417D01*
X272758Y64208D01*
G01X275150Y62000D02*
Y64500D01*
X274650Y64000D01*
G01Y62000D02*
X275650D01*
G01X274717Y67100D02*
Y69600D01*
X275758D01*
X276092Y69475D01*
X276300Y69308D01*
X276383Y68975D01*
X276300Y68642D01*
X276050Y68433D01*
X275758Y68308D01*
X274717D01*
G01X275758D02*
X276383Y67100D01*
G01X279150D02*
Y69600D01*
X277608Y67808D01*
X279692D01*
G01X282250Y67100D02*
Y69600D01*
X280708Y67808D01*
X282792D01*
G01X284058Y69183D02*
X284308Y69433D01*
X284600Y69558D01*
X284933Y69600D01*
X285350Y69517D01*
X285642Y69308D01*
X285725Y69058D01*
X285683Y68808D01*
X285517Y68600D01*
X284683Y68183D01*
X284308Y67892D01*
X284058Y67475D01*
X283975Y67100D01*
X285725D01*
G01X278783Y87100D02*
Y85308D01*
X278950Y84933D01*
X279283Y84683D01*
X279700Y84600D01*
X280117Y84683D01*
X280450Y84933D01*
X280617Y85308D01*
Y87100D01*
G01X281883Y85100D02*
X282133Y84808D01*
X282467Y84642D01*
X282842Y84600D01*
X283175Y84642D01*
X283508Y84850D01*
X283717Y85100D01*
X283758Y85350D01*
X283675Y85642D01*
X283383Y85850D01*
X283092Y85933D01*
X282717D01*
G01X283092D02*
X283342Y86058D01*
X283550Y86267D01*
X283633Y86517D01*
X283550Y86767D01*
X283342Y86975D01*
X282967Y87100D01*
X282592Y87058D01*
X282217Y86892D01*
G01X285108Y86683D02*
X285358Y86933D01*
X285650Y87058D01*
X285983Y87100D01*
X286400Y87017D01*
X286692Y86808D01*
X286775Y86558D01*
X286733Y86308D01*
X286567Y86100D01*
X285733Y85683D01*
X285358Y85392D01*
X285108Y84975D01*
X285025Y84600D01*
X286775D01*
G01X275500Y77517D02*
X273000D01*
Y78558D01*
X273125Y78892D01*
X273292Y79100D01*
X273625Y79183D01*
X273958Y79100D01*
X274167Y78850D01*
X274292Y78558D01*
Y77517D01*
G01Y78558D02*
X275500Y79183D01*
G01Y81950D02*
X273000D01*
X274792Y80408D01*
Y82492D01*
G01X275500Y84550D02*
X273000D01*
X273500Y84050D01*
G01X275500D02*
Y85050D01*
G01Y87650D02*
X273000D01*
X273500Y87150D01*
G01X275500D02*
Y88150D01*
G01X278000Y103950D02*
X277958Y103617D01*
X277792Y103325D01*
X277542Y103075D01*
X277250Y102908D01*
X276917Y102825D01*
X276583D01*
X276250Y102908D01*
X275958Y103075D01*
X275708Y103325D01*
X275542Y103617D01*
X275500Y103950D01*
X275542Y104283D01*
X275708Y104575D01*
X275958Y104825D01*
X276250Y104992D01*
X276583Y105075D01*
X276917D01*
X277250Y104992D01*
X277542Y104825D01*
X277792Y104575D01*
X277958Y104283D01*
X278000Y103950D01*
G01X277333Y104283D02*
X278000Y104783D01*
G01X277708Y106342D02*
X277917Y106633D01*
X278000Y106967D01*
X277917Y107300D01*
X277667Y107592D01*
X277292Y107800D01*
X276917Y107883D01*
X276458D01*
X276083Y107800D01*
X275750Y107592D01*
X275583Y107342D01*
X275500Y107050D01*
X275583Y106717D01*
X275750Y106467D01*
X276000Y106300D01*
X276333Y106217D01*
X276625Y106300D01*
X276917Y106508D01*
X277083Y106758D01*
X277125Y107050D01*
X277042Y107383D01*
X276833Y107633D01*
X276458Y107883D01*
G01X275017Y93000D02*
Y95500D01*
X276058D01*
X276392Y95375D01*
X276600Y95208D01*
X276683Y94875D01*
X276600Y94542D01*
X276350Y94333D01*
X276058Y94208D01*
X275017D01*
G01X276058D02*
X276683Y93000D01*
G01X278158Y95083D02*
X278408Y95333D01*
X278700Y95458D01*
X279033Y95500D01*
X279450Y95417D01*
X279742Y95208D01*
X279825Y94958D01*
X279783Y94708D01*
X279617Y94500D01*
X278783Y94083D01*
X278408Y93792D01*
X278158Y93375D01*
X278075Y93000D01*
X279825D01*
G01X281133Y93375D02*
X281383Y93167D01*
X281675Y93042D01*
X282050Y93000D01*
X282425Y93083D01*
X282717Y93250D01*
X282925Y93542D01*
X282967Y93875D01*
X282883Y94208D01*
X282675Y94417D01*
X282383Y94583D01*
X282092Y94625D01*
X281800Y94583D01*
X281425Y94417D01*
X281550Y95500D01*
X282675D01*
G01X285150D02*
X284817Y95417D01*
X284567Y95208D01*
X284400Y94958D01*
X284275Y94625D01*
X284233Y94250D01*
X284275Y93875D01*
X284400Y93542D01*
X284567Y93292D01*
X284817Y93083D01*
X285150Y93000D01*
X285483Y93083D01*
X285733Y93292D01*
X285900Y93542D01*
X286025Y93875D01*
X286067Y94250D01*
X286025Y94625D01*
X285900Y94958D01*
X285733Y95208D01*
X285483Y95417D01*
X285150Y95500D01*
G01X273000Y95017D02*
X270500D01*
Y96058D01*
X270625Y96392D01*
X270792Y96600D01*
X271125Y96683D01*
X271458Y96600D01*
X271667Y96350D01*
X271792Y96058D01*
Y95017D01*
G01Y96058D02*
X273000Y96683D01*
G01X270917Y98158D02*
X270667Y98408D01*
X270542Y98700D01*
X270500Y99033D01*
X270583Y99450D01*
X270792Y99742D01*
X271042Y99825D01*
X271292Y99783D01*
X271500Y99617D01*
X271917Y98783D01*
X272208Y98408D01*
X272625Y98158D01*
X273000Y98075D01*
Y99825D01*
G01X272625Y101133D02*
X272833Y101383D01*
X272958Y101675D01*
X273000Y102050D01*
X272917Y102425D01*
X272750Y102717D01*
X272458Y102925D01*
X272125Y102967D01*
X271792Y102883D01*
X271583Y102675D01*
X271417Y102383D01*
X271375Y102092D01*
X271417Y101800D01*
X271583Y101425D01*
X270500Y101550D01*
Y102675D01*
G01X273000Y105650D02*
X270500D01*
X272292Y104108D01*
Y106192D01*
G01X268017Y115500D02*
Y118000D01*
X269058D01*
X269392Y117875D01*
X269600Y117708D01*
X269683Y117375D01*
X269600Y117042D01*
X269350Y116833D01*
X269058Y116708D01*
X268017D01*
G01X269058D02*
X269683Y115500D01*
G01X271950D02*
Y118000D01*
X271450Y117500D01*
G01Y115500D02*
X272450D01*
G01X274258Y117583D02*
X274508Y117833D01*
X274800Y117958D01*
X275133Y118000D01*
X275550Y117917D01*
X275842Y117708D01*
X275925Y117458D01*
X275883Y117208D01*
X275717Y117000D01*
X274883Y116583D01*
X274508Y116292D01*
X274258Y115875D01*
X274175Y115500D01*
X275925D01*
G01X278650D02*
Y118000D01*
X277108Y116208D01*
X279192D01*
G01X268017Y111000D02*
Y113500D01*
X269058D01*
X269392Y113375D01*
X269600Y113208D01*
X269683Y112875D01*
X269600Y112542D01*
X269350Y112333D01*
X269058Y112208D01*
X268017D01*
G01X269058D02*
X269683Y111000D01*
G01X272450D02*
Y113500D01*
X270908Y111708D01*
X272992D01*
G01X275050Y113500D02*
X274717Y113417D01*
X274467Y113208D01*
X274300Y112958D01*
X274175Y112625D01*
X274133Y112250D01*
X274175Y111875D01*
X274300Y111542D01*
X274467Y111292D01*
X274717Y111083D01*
X275050Y111000D01*
X275383Y111083D01*
X275633Y111292D01*
X275800Y111542D01*
X275925Y111875D01*
X275967Y112250D01*
X275925Y112625D01*
X275800Y112958D01*
X275633Y113208D01*
X275383Y113417D01*
X275050Y113500D01*
G01X277233Y111500D02*
X277483Y111208D01*
X277817Y111042D01*
X278192Y111000D01*
X278525Y111042D01*
X278858Y111250D01*
X279067Y111500D01*
X279108Y111750D01*
X279025Y112042D01*
X278733Y112250D01*
X278442Y112333D01*
X278067D01*
G01X278442D02*
X278692Y112458D01*
X278900Y112667D01*
X278983Y112917D01*
X278900Y113167D01*
X278692Y113375D01*
X278317Y113500D01*
X277942Y113458D01*
X277567Y113292D01*
G01X275017Y134000D02*
Y136500D01*
X276058D01*
X276392Y136375D01*
X276600Y136208D01*
X276683Y135875D01*
X276600Y135542D01*
X276350Y135333D01*
X276058Y135208D01*
X275017D01*
G01X276058D02*
X276683Y134000D01*
G01X278950D02*
Y136500D01*
X278450Y136000D01*
G01Y134000D02*
X279450D01*
G01X282050D02*
Y136500D01*
X281550Y136000D01*
G01Y134000D02*
X282550D01*
G01X284358Y136083D02*
X284608Y136333D01*
X284900Y136458D01*
X285233Y136500D01*
X285650Y136417D01*
X285942Y136208D01*
X286025Y135958D01*
X285983Y135708D01*
X285817Y135500D01*
X284983Y135083D01*
X284608Y134792D01*
X284358Y134375D01*
X284275Y134000D01*
X286025D01*
G01X275017Y126500D02*
Y129000D01*
X276058D01*
X276392Y128875D01*
X276600Y128708D01*
X276683Y128375D01*
X276600Y128042D01*
X276350Y127833D01*
X276058Y127708D01*
X275017D01*
G01X276058D02*
X276683Y126500D01*
G01X278950D02*
Y129000D01*
X278450Y128500D01*
G01Y126500D02*
X279450D01*
G01X282050Y129000D02*
X281717Y128917D01*
X281467Y128708D01*
X281300Y128458D01*
X281175Y128125D01*
X281133Y127750D01*
X281175Y127375D01*
X281300Y127042D01*
X281467Y126792D01*
X281717Y126583D01*
X282050Y126500D01*
X282383Y126583D01*
X282633Y126792D01*
X282800Y127042D01*
X282925Y127375D01*
X282967Y127750D01*
X282925Y128125D01*
X282800Y128458D01*
X282633Y128708D01*
X282383Y128917D01*
X282050Y129000D01*
G01X285067Y126500D02*
X285150Y127042D01*
X285275Y127500D01*
X285442Y127917D01*
X285650Y128375D01*
X285983Y129000D01*
X284317D01*
G01X276000Y148575D02*
X273500Y150325D01*
G01Y148575D02*
X276000Y150325D01*
G01Y152550D02*
X273500D01*
X274000Y152050D01*
G01X276000D02*
Y153050D01*
G01X268100Y148667D02*
X265600D01*
Y149708D01*
X265725Y150042D01*
X265892Y150250D01*
X266225Y150333D01*
X266558Y150250D01*
X266767Y150000D01*
X266892Y149708D01*
Y148667D01*
G01Y149708D02*
X268100Y150333D01*
G01X267600Y151683D02*
X267892Y151933D01*
X268058Y152267D01*
X268100Y152642D01*
X268058Y152975D01*
X267850Y153308D01*
X267600Y153517D01*
X267350Y153558D01*
X267058Y153475D01*
X266850Y153183D01*
X266767Y152892D01*
Y152517D01*
G01Y152892D02*
X266642Y153142D01*
X266433Y153350D01*
X266183Y153433D01*
X265933Y153350D01*
X265725Y153142D01*
X265600Y152767D01*
X265642Y152392D01*
X265808Y152017D01*
G01X267808Y154992D02*
X268017Y155283D01*
X268100Y155617D01*
X268017Y155950D01*
X267767Y156242D01*
X267392Y156450D01*
X267017Y156533D01*
X266558D01*
X266183Y156450D01*
X265850Y156242D01*
X265683Y155992D01*
X265600Y155700D01*
X265683Y155367D01*
X265850Y155117D01*
X266100Y154950D01*
X266433Y154867D01*
X266725Y154950D01*
X267017Y155158D01*
X267183Y155408D01*
X267225Y155700D01*
X267142Y156033D01*
X266933Y156283D01*
X266558Y156533D01*
G01X272100Y148917D02*
X269600D01*
Y149958D01*
X269725Y150292D01*
X269892Y150500D01*
X270225Y150583D01*
X270558Y150500D01*
X270767Y150250D01*
X270892Y149958D01*
Y148917D01*
G01Y149958D02*
X272100Y150583D01*
G01X271600Y151933D02*
X271892Y152183D01*
X272058Y152517D01*
X272100Y152892D01*
X272058Y153225D01*
X271850Y153558D01*
X271600Y153767D01*
X271350Y153808D01*
X271058Y153725D01*
X270850Y153433D01*
X270767Y153142D01*
Y152767D01*
G01Y153142D02*
X270642Y153392D01*
X270433Y153600D01*
X270183Y153683D01*
X269933Y153600D01*
X269725Y153392D01*
X269600Y153017D01*
X269642Y152642D01*
X269808Y152267D01*
G01X272100Y155950D02*
X269600D01*
X270100Y155450D01*
G01X272100D02*
Y156450D01*
G01X271058Y158258D02*
X270767Y158550D01*
X270600Y158800D01*
X270517Y159133D01*
X270600Y159425D01*
X270767Y159633D01*
X271017Y159800D01*
X271308Y159842D01*
X271558Y159800D01*
X271808Y159633D01*
X272017Y159383D01*
X272100Y159092D01*
X272017Y158758D01*
X271767Y158467D01*
X271392Y158300D01*
X270975Y158258D01*
X270433Y158342D01*
X270142Y158467D01*
X269850Y158675D01*
X269642Y158967D01*
X269600Y159258D01*
X269683Y159550D01*
X269892Y159758D01*
G01X276100Y156467D02*
X273600D01*
Y157508D01*
X273725Y157842D01*
X273892Y158050D01*
X274225Y158133D01*
X274558Y158050D01*
X274767Y157800D01*
X274892Y157508D01*
Y156467D01*
G01Y157508D02*
X276100Y158133D01*
G01Y160317D02*
X275558Y160400D01*
X275100Y160525D01*
X274683Y160692D01*
X274225Y160900D01*
X273600Y161233D01*
Y159567D01*
G01X276100Y163500D02*
X273600D01*
X274100Y163000D01*
G01X276100D02*
Y164000D01*
G01X281000Y176000D02*
X274000D01*
G01X270000Y176500D02*
X269000D01*
G01X279750Y203750D02*
X276250D01*
Y190250D01*
X279750D01*
Y203750D01*
G01X276250D02*
X279750D01*
Y217250D01*
X276250D01*
Y203750D01*
G01X266500Y235517D02*
X264000D01*
Y236558D01*
X264125Y236892D01*
X264292Y237100D01*
X264625Y237183D01*
X264958Y237100D01*
X265167Y236850D01*
X265292Y236558D01*
Y235517D01*
G01Y236558D02*
X266500Y237183D01*
G01Y239950D02*
X264000D01*
X265792Y238408D01*
Y240492D01*
G01X266500Y242467D02*
X265958Y242550D01*
X265500Y242675D01*
X265083Y242842D01*
X264625Y243050D01*
X264000Y243383D01*
Y241717D01*
G01X265458Y244858D02*
X265167Y245150D01*
X265000Y245400D01*
X264917Y245733D01*
X265000Y246025D01*
X265167Y246233D01*
X265417Y246400D01*
X265708Y246442D01*
X265958Y246400D01*
X266208Y246233D01*
X266417Y245983D01*
X266500Y245692D01*
X266417Y245358D01*
X266167Y245067D01*
X265792Y244900D01*
X265375Y244858D01*
X264833Y244942D01*
X264542Y245067D01*
X264250Y245275D01*
X264042Y245567D01*
X264000Y245858D01*
X264083Y246150D01*
X264292Y246358D01*
G01X302311Y269286D02*
Y257486D01*
X271311D01*
Y269286D01*
X302311D01*
G01X290400Y42000D02*
X290067Y42042D01*
X289775Y42208D01*
X289525Y42458D01*
X289358Y42750D01*
X289275Y43083D01*
Y43417D01*
X289358Y43750D01*
X289525Y44042D01*
X289775Y44292D01*
X290067Y44458D01*
X290400Y44500D01*
X290733Y44458D01*
X291025Y44292D01*
X291275Y44042D01*
X291442Y43750D01*
X291525Y43417D01*
Y43083D01*
X291442Y42750D01*
X291275Y42458D01*
X291025Y42208D01*
X290733Y42042D01*
X290400Y42000D01*
G01X290733Y42667D02*
X291233Y42000D01*
G01X293500D02*
Y44500D01*
X293000Y44000D01*
G01Y42000D02*
X294000D01*
G01X295683Y42375D02*
X295933Y42167D01*
X296225Y42042D01*
X296600Y42000D01*
X296975Y42083D01*
X297267Y42250D01*
X297475Y42542D01*
X297517Y42875D01*
X297433Y43208D01*
X297225Y43417D01*
X296933Y43583D01*
X296642Y43625D01*
X296350Y43583D01*
X295975Y43417D01*
X296100Y44500D01*
X297225D01*
G01X279500Y45983D02*
X281292D01*
X281667Y46150D01*
X281917Y46483D01*
X282000Y46900D01*
X281917Y47317D01*
X281667Y47650D01*
X281292Y47817D01*
X279500D01*
G01X282000Y50500D02*
X279500D01*
X281292Y48958D01*
Y51042D01*
G01X279917Y52308D02*
X279667Y52558D01*
X279542Y52850D01*
X279500Y53183D01*
X279583Y53600D01*
X279792Y53892D01*
X280042Y53975D01*
X280292Y53933D01*
X280500Y53767D01*
X280917Y52933D01*
X281208Y52558D01*
X281625Y52308D01*
X282000Y52225D01*
Y53975D01*
G01X290750Y46250D02*
X294250D01*
Y59750D01*
X290750D01*
Y46250D01*
G01X292100Y62517D02*
X289600D01*
Y63558D01*
X289725Y63892D01*
X289892Y64100D01*
X290225Y64183D01*
X290558Y64100D01*
X290767Y63850D01*
X290892Y63558D01*
Y62517D01*
G01Y63558D02*
X292100Y64183D01*
G01Y66950D02*
X289600D01*
X291392Y65408D01*
Y67492D01*
G01X292100Y70050D02*
X289600D01*
X291392Y68508D01*
Y70592D01*
G01X291600Y71733D02*
X291892Y71983D01*
X292058Y72317D01*
X292100Y72692D01*
X292058Y73025D01*
X291850Y73358D01*
X291600Y73567D01*
X291350Y73608D01*
X291058Y73525D01*
X290850Y73233D01*
X290767Y72942D01*
Y72567D01*
G01Y72942D02*
X290642Y73192D01*
X290433Y73400D01*
X290183Y73483D01*
X289933Y73400D01*
X289725Y73192D01*
X289600Y72817D01*
X289642Y72442D01*
X289808Y72067D01*
G01X288517Y89500D02*
Y92000D01*
X289558D01*
X289892Y91875D01*
X290100Y91708D01*
X290183Y91375D01*
X290100Y91042D01*
X289850Y90833D01*
X289558Y90708D01*
X288517D01*
G01X289558D02*
X290183Y89500D01*
G01X292450D02*
Y92000D01*
X291950Y91500D01*
G01Y89500D02*
X292950D01*
G01X294633Y90000D02*
X294883Y89708D01*
X295217Y89542D01*
X295592Y89500D01*
X295925Y89542D01*
X296258Y89750D01*
X296467Y90000D01*
X296508Y90250D01*
X296425Y90542D01*
X296133Y90750D01*
X295842Y90833D01*
X295467D01*
G01X295842D02*
X296092Y90958D01*
X296300Y91167D01*
X296383Y91417D01*
X296300Y91667D01*
X296092Y91875D01*
X295717Y92000D01*
X295342Y91958D01*
X294967Y91792D01*
G01X297942Y89792D02*
X298233Y89583D01*
X298567Y89500D01*
X298900Y89583D01*
X299192Y89833D01*
X299400Y90208D01*
X299483Y90583D01*
Y91042D01*
X299400Y91417D01*
X299192Y91750D01*
X298942Y91917D01*
X298650Y92000D01*
X298317Y91917D01*
X298067Y91750D01*
X297900Y91500D01*
X297817Y91167D01*
X297900Y90875D01*
X298108Y90583D01*
X298358Y90417D01*
X298650Y90375D01*
X298983Y90458D01*
X299233Y90667D01*
X299483Y91042D01*
G01X285517Y109000D02*
Y111500D01*
X286558D01*
X286892Y111375D01*
X287100Y111208D01*
X287183Y110875D01*
X287100Y110542D01*
X286850Y110333D01*
X286558Y110208D01*
X285517D01*
G01X286558D02*
X287183Y109000D01*
G01X289450D02*
Y111500D01*
X288950Y111000D01*
G01Y109000D02*
X289950D01*
G01X292550D02*
Y111500D01*
X292050Y111000D01*
G01Y109000D02*
X293050D01*
G01X295567D02*
X295650Y109542D01*
X295775Y110000D01*
X295942Y110417D01*
X296150Y110875D01*
X296483Y111500D01*
X294817D01*
G01X283500Y106517D02*
X281000D01*
Y107558D01*
X281125Y107892D01*
X281292Y108100D01*
X281625Y108183D01*
X281958Y108100D01*
X282167Y107850D01*
X282292Y107558D01*
Y106517D01*
G01Y107558D02*
X283500Y108183D01*
G01X283000Y109533D02*
X283292Y109783D01*
X283458Y110117D01*
X283500Y110492D01*
X283458Y110825D01*
X283250Y111158D01*
X283000Y111367D01*
X282750Y111408D01*
X282458Y111325D01*
X282250Y111033D01*
X282167Y110742D01*
Y110367D01*
G01Y110742D02*
X282042Y110992D01*
X281833Y111200D01*
X281583Y111283D01*
X281333Y111200D01*
X281125Y110992D01*
X281000Y110617D01*
X281042Y110242D01*
X281208Y109867D01*
G01X283500Y114050D02*
X281000D01*
X282792Y112508D01*
Y114592D01*
G01X281417Y115858D02*
X281167Y116108D01*
X281042Y116400D01*
X281000Y116733D01*
X281083Y117150D01*
X281292Y117442D01*
X281542Y117525D01*
X281792Y117483D01*
X282000Y117317D01*
X282417Y116483D01*
X282708Y116108D01*
X283125Y115858D01*
X283500Y115775D01*
Y117525D01*
G01X285517Y113000D02*
Y115500D01*
X286558D01*
X286892Y115375D01*
X287100Y115208D01*
X287183Y114875D01*
X287100Y114542D01*
X286850Y114333D01*
X286558Y114208D01*
X285517D01*
G01X286558D02*
X287183Y113000D01*
G01X288533Y113500D02*
X288783Y113208D01*
X289117Y113042D01*
X289492Y113000D01*
X289825Y113042D01*
X290158Y113250D01*
X290367Y113500D01*
X290408Y113750D01*
X290325Y114042D01*
X290033Y114250D01*
X289742Y114333D01*
X289367D01*
G01X289742D02*
X289992Y114458D01*
X290200Y114667D01*
X290283Y114917D01*
X290200Y115167D01*
X289992Y115375D01*
X289617Y115500D01*
X289242Y115458D01*
X288867Y115292D01*
G01X293050Y113000D02*
Y115500D01*
X291508Y113708D01*
X293592D01*
G01X295567Y113000D02*
X295650Y113542D01*
X295775Y114000D01*
X295942Y114417D01*
X296150Y114875D01*
X296483Y115500D01*
X294817D01*
G01X285500Y152000D02*
Y142000D01*
X294000D01*
Y149000D01*
X301500D01*
Y153000D01*
G01X284850Y140500D02*
Y138000D01*
G01X283892Y140500D02*
X285808D01*
G01X287117Y138000D02*
Y140500D01*
X288117D01*
X288450Y140375D01*
X288700Y140083D01*
X288783Y139750D01*
X288700Y139417D01*
X288492Y139167D01*
X288117Y139042D01*
X287117D01*
G01X290133Y138500D02*
X290383Y138208D01*
X290717Y138042D01*
X291092Y138000D01*
X291425Y138042D01*
X291758Y138250D01*
X291967Y138500D01*
X292008Y138750D01*
X291925Y139042D01*
X291633Y139250D01*
X291342Y139333D01*
X290967D01*
G01X291342D02*
X291592Y139458D01*
X291800Y139667D01*
X291883Y139917D01*
X291800Y140167D01*
X291592Y140375D01*
X291217Y140500D01*
X290842Y140458D01*
X290467Y140292D01*
G01X293233Y138500D02*
X293483Y138208D01*
X293817Y138042D01*
X294192Y138000D01*
X294525Y138042D01*
X294858Y138250D01*
X295067Y138500D01*
X295108Y138750D01*
X295025Y139042D01*
X294733Y139250D01*
X294442Y139333D01*
X294067D01*
G01X294442D02*
X294692Y139458D01*
X294900Y139667D01*
X294983Y139917D01*
X294900Y140167D01*
X294692Y140375D01*
X294317Y140500D01*
X293942Y140458D01*
X293567Y140292D01*
G01X292000Y177000D02*
X282500D01*
Y167000D01*
G01X285000Y199500D02*
Y179000D01*
X283000D01*
G01X293250Y213000D02*
X296750Y218000D01*
G01X293250D02*
X296750Y213000D01*
G01X300600D02*
Y218000D01*
X299600Y217000D01*
G01Y213000D02*
X301600D01*
G01X306200Y212833D02*
X306033Y212917D01*
Y213083D01*
X306200Y213167D01*
X306367Y213083D01*
Y212917D01*
X306200Y212833D01*
G01Y215083D02*
X306033Y215167D01*
Y215333D01*
X306200Y215417D01*
X306367Y215333D01*
Y215167D01*
X306200Y215083D01*
G01X309967Y214000D02*
X310467Y213417D01*
X311133Y213083D01*
X311883Y213000D01*
X312550Y213083D01*
X313217Y213500D01*
X313633Y214000D01*
X313717Y214500D01*
X313550Y215083D01*
X312967Y215500D01*
X312383Y215667D01*
X311633D01*
G01X312383D02*
X312883Y215917D01*
X313300Y216333D01*
X313467Y216833D01*
X313300Y217333D01*
X312883Y217750D01*
X312133Y218000D01*
X311383Y217917D01*
X310633Y217583D01*
G01X315817Y217167D02*
X316317Y217667D01*
X316900Y217917D01*
X317567Y218000D01*
X318400Y217833D01*
X318983Y217417D01*
X319150Y216917D01*
X319067Y216417D01*
X318733Y216000D01*
X317067Y215167D01*
X316317Y214583D01*
X315817Y213750D01*
X315650Y213000D01*
X319150D01*
G01X323000Y212833D02*
X322833Y212917D01*
Y213083D01*
X323000Y213167D01*
X323167Y213083D01*
Y212917D01*
X323000Y212833D01*
G01X328433Y213000D02*
X328600Y214083D01*
X328850Y215000D01*
X329183Y215833D01*
X329600Y216750D01*
X330267Y218000D01*
X326933D01*
G01X332617Y215083D02*
X333200Y215667D01*
X333700Y216000D01*
X334367Y216167D01*
X334950Y216000D01*
X335367Y215667D01*
X335700Y215167D01*
X335783Y214583D01*
X335700Y214083D01*
X335367Y213583D01*
X334867Y213167D01*
X334283Y213000D01*
X333617Y213167D01*
X333033Y213667D01*
X332700Y214417D01*
X332617Y215250D01*
X332783Y216333D01*
X333033Y216917D01*
X333450Y217500D01*
X334033Y217917D01*
X334617Y218000D01*
X335200Y217833D01*
X335617Y217417D01*
G01X339800Y213000D02*
X340383Y213083D01*
X341050Y213333D01*
X341467Y213750D01*
X341633Y214333D01*
X341467Y214917D01*
X340967Y215417D01*
X340217Y215667D01*
X339383D01*
X338883Y215833D01*
X338467Y216250D01*
X338300Y216833D01*
X338550Y217417D01*
X339133Y217833D01*
X339800Y218000D01*
X340467Y217833D01*
X341050Y217417D01*
X341300Y216833D01*
X341133Y216250D01*
X340717Y215833D01*
X340217Y215667D01*
X339383D01*
X338633Y215417D01*
X338133Y214917D01*
X337967Y214333D01*
X338133Y213750D01*
X338550Y213333D01*
X339217Y213083D01*
X339800Y213000D01*
G01X343567D02*
Y218000D01*
G01X346733D02*
X343567Y214917D01*
G01X347233Y213000D02*
X344983Y216333D01*
G01X349250Y213000D02*
Y218000D01*
G01X352750D02*
Y213000D01*
G01Y215500D02*
X349250D01*
G01X355017Y218000D02*
X358183D01*
X355017Y213000D01*
X358183D01*
G01X285000Y204000D02*
Y216500D01*
G01X292000Y199067D02*
X289500D01*
Y200108D01*
X289625Y200442D01*
X289792Y200650D01*
X290125Y200733D01*
X290458Y200650D01*
X290667Y200400D01*
X290792Y200108D01*
Y199067D01*
G01Y200108D02*
X292000Y200733D01*
G01Y203500D02*
X289500D01*
X291292Y201958D01*
Y204042D01*
G01X292000Y206600D02*
X289500D01*
X291292Y205058D01*
Y207142D01*
G01X296000Y199067D02*
X293500D01*
Y200108D01*
X293625Y200442D01*
X293792Y200650D01*
X294125Y200733D01*
X294458Y200650D01*
X294667Y200400D01*
X294792Y200108D01*
Y199067D01*
G01Y200108D02*
X296000Y200733D01*
G01Y203500D02*
X293500D01*
X295292Y201958D01*
Y204042D01*
G01X295625Y205183D02*
X295833Y205433D01*
X295958Y205725D01*
X296000Y206100D01*
X295917Y206475D01*
X295750Y206767D01*
X295458Y206975D01*
X295125Y207017D01*
X294792Y206933D01*
X294583Y206725D01*
X294417Y206433D01*
X294375Y206142D01*
X294417Y205850D01*
X294583Y205475D01*
X293500Y205600D01*
Y206725D01*
G01X284800Y232545D02*
Y252450D01*
G01X298800Y232545D02*
X284800D01*
G01X291700Y250950D02*
X290200Y252450D01*
G01X293200D02*
X291700Y250950D01*
G01X284800Y252450D02*
X298800D01*
G01X300517Y58000D02*
Y60500D01*
X301558D01*
X301892Y60375D01*
X302100Y60208D01*
X302183Y59875D01*
X302100Y59542D01*
X301850Y59333D01*
X301558Y59208D01*
X300517D01*
G01X301558D02*
X302183Y58000D01*
G01X303533Y58500D02*
X303783Y58208D01*
X304117Y58042D01*
X304492Y58000D01*
X304825Y58042D01*
X305158Y58250D01*
X305367Y58500D01*
X305408Y58750D01*
X305325Y59042D01*
X305033Y59250D01*
X304742Y59333D01*
X304367D01*
G01X304742D02*
X304992Y59458D01*
X305200Y59667D01*
X305283Y59917D01*
X305200Y60167D01*
X304992Y60375D01*
X304617Y60500D01*
X304242Y60458D01*
X303867Y60292D01*
G01X306842Y58292D02*
X307133Y58083D01*
X307467Y58000D01*
X307800Y58083D01*
X308092Y58333D01*
X308300Y58708D01*
X308383Y59083D01*
Y59542D01*
X308300Y59917D01*
X308092Y60250D01*
X307842Y60417D01*
X307550Y60500D01*
X307217Y60417D01*
X306967Y60250D01*
X306800Y60000D01*
X306717Y59667D01*
X306800Y59375D01*
X307008Y59083D01*
X307258Y58917D01*
X307550Y58875D01*
X307883Y58958D01*
X308133Y59167D01*
X308383Y59542D01*
G01X310650Y58000D02*
X310942Y58042D01*
X311275Y58167D01*
X311483Y58375D01*
X311567Y58667D01*
X311483Y58958D01*
X311233Y59208D01*
X310858Y59333D01*
X310442D01*
X310192Y59417D01*
X309983Y59625D01*
X309900Y59917D01*
X310025Y60208D01*
X310317Y60417D01*
X310650Y60500D01*
X310983Y60417D01*
X311275Y60208D01*
X311400Y59917D01*
X311317Y59625D01*
X311108Y59417D01*
X310858Y59333D01*
X310442D01*
X310067Y59208D01*
X309817Y58958D01*
X309733Y58667D01*
X309817Y58375D01*
X310025Y58167D01*
X310358Y58042D01*
X310650Y58000D01*
G01X304000Y78500D02*
Y77000D01*
X305500D01*
Y74000D01*
X348500D01*
Y66000D01*
X361500D01*
Y62500D01*
X379000D01*
Y64000D01*
G01X306801Y75040D02*
Y77540D01*
X307801D01*
X308134Y77415D01*
X308384Y77123D01*
X308467Y76790D01*
X308384Y76457D01*
X308176Y76207D01*
X307801Y76082D01*
X306801D01*
G01X311651Y77332D02*
X311401Y77457D01*
X311109Y77540D01*
X310776D01*
X310401Y77415D01*
X310109Y77207D01*
X309901Y76957D01*
X309734Y76540D01*
X309692Y76165D01*
X309776Y75790D01*
X309901Y75540D01*
X310151Y75290D01*
X310442Y75123D01*
X310734Y75040D01*
X311026D01*
X311317Y75123D01*
X311567Y75248D01*
X311776Y75415D01*
G01X314334Y75040D02*
Y77540D01*
X312792Y75748D01*
X314876D01*
G01X316142Y76082D02*
X316434Y76373D01*
X316684Y76540D01*
X317017Y76623D01*
X317309Y76540D01*
X317517Y76373D01*
X317684Y76123D01*
X317726Y75832D01*
X317684Y75582D01*
X317517Y75332D01*
X317267Y75123D01*
X316976Y75040D01*
X316642Y75123D01*
X316351Y75373D01*
X316184Y75748D01*
X316142Y76165D01*
X316226Y76707D01*
X316351Y76998D01*
X316559Y77290D01*
X316851Y77498D01*
X317142Y77540D01*
X317434Y77457D01*
X317642Y77248D01*
G01X300517Y62000D02*
Y64500D01*
X301558D01*
X301892Y64375D01*
X302100Y64208D01*
X302183Y63875D01*
X302100Y63542D01*
X301850Y63333D01*
X301558Y63208D01*
X300517D01*
G01X301558D02*
X302183Y62000D01*
G01X304950D02*
Y64500D01*
X303408Y62708D01*
X305492D01*
G01X306758Y64083D02*
X307008Y64333D01*
X307300Y64458D01*
X307633Y64500D01*
X308050Y64417D01*
X308342Y64208D01*
X308425Y63958D01*
X308383Y63708D01*
X308217Y63500D01*
X307383Y63083D01*
X307008Y62792D01*
X306758Y62375D01*
X306675Y62000D01*
X308425D01*
G01X309733Y62500D02*
X309983Y62208D01*
X310317Y62042D01*
X310692Y62000D01*
X311025Y62042D01*
X311358Y62250D01*
X311567Y62500D01*
X311608Y62750D01*
X311525Y63042D01*
X311233Y63250D01*
X310942Y63333D01*
X310567D01*
G01X310942D02*
X311192Y63458D01*
X311400Y63667D01*
X311483Y63917D01*
X311400Y64167D01*
X311192Y64375D01*
X310817Y64500D01*
X310442Y64458D01*
X310067Y64292D01*
G01X300517Y66000D02*
Y68500D01*
X301558D01*
X301892Y68375D01*
X302100Y68208D01*
X302183Y67875D01*
X302100Y67542D01*
X301850Y67333D01*
X301558Y67208D01*
X300517D01*
G01X301558D02*
X302183Y66000D01*
G01X304450D02*
Y68500D01*
X303950Y68000D01*
G01Y66000D02*
X304950D01*
G01X306842Y66292D02*
X307133Y66083D01*
X307467Y66000D01*
X307800Y66083D01*
X308092Y66333D01*
X308300Y66708D01*
X308383Y67083D01*
Y67542D01*
X308300Y67917D01*
X308092Y68250D01*
X307842Y68417D01*
X307550Y68500D01*
X307217Y68417D01*
X306967Y68250D01*
X306800Y68000D01*
X306717Y67667D01*
X306800Y67375D01*
X307008Y67083D01*
X307258Y66917D01*
X307550Y66875D01*
X307883Y66958D01*
X308133Y67167D01*
X308383Y67542D01*
G01X309733Y66500D02*
X309983Y66208D01*
X310317Y66042D01*
X310692Y66000D01*
X311025Y66042D01*
X311358Y66250D01*
X311567Y66500D01*
X311608Y66750D01*
X311525Y67042D01*
X311233Y67250D01*
X310942Y67333D01*
X310567D01*
G01X310942D02*
X311192Y67458D01*
X311400Y67667D01*
X311483Y67917D01*
X311400Y68167D01*
X311192Y68375D01*
X310817Y68500D01*
X310442Y68458D01*
X310067Y68292D01*
G01X304000Y83000D02*
Y94500D01*
X375000D01*
Y98000D01*
X396000D01*
Y78500D01*
X388000D01*
Y64000D01*
X379000D01*
G01X307017Y82500D02*
Y85000D01*
X308017D01*
X308350Y84875D01*
X308600Y84583D01*
X308683Y84250D01*
X308600Y83917D01*
X308392Y83667D01*
X308017Y83542D01*
X307017D01*
G01X310117Y82500D02*
Y85000D01*
X311158D01*
X311492Y84875D01*
X311700Y84708D01*
X311783Y84375D01*
X311700Y84042D01*
X311450Y83833D01*
X311158Y83708D01*
X310117D01*
G01X311158D02*
X311783Y82500D01*
G01X313133Y82875D02*
X313383Y82667D01*
X313675Y82542D01*
X314050Y82500D01*
X314425Y82583D01*
X314717Y82750D01*
X314925Y83042D01*
X314967Y83375D01*
X314883Y83708D01*
X314675Y83917D01*
X314383Y84083D01*
X314092Y84125D01*
X313800Y84083D01*
X313425Y83917D01*
X313550Y85000D01*
X314675D01*
G01X317650Y82500D02*
Y85000D01*
X316108Y83208D01*
X318192D01*
G01X306817Y78700D02*
Y81200D01*
X307817D01*
X308150Y81075D01*
X308400Y80783D01*
X308483Y80450D01*
X308400Y80117D01*
X308192Y79867D01*
X307817Y79742D01*
X306817D01*
G01X309917Y78700D02*
Y81200D01*
X310958D01*
X311292Y81075D01*
X311500Y80908D01*
X311583Y80575D01*
X311500Y80242D01*
X311250Y80033D01*
X310958Y79908D01*
X309917D01*
G01X310958D02*
X311583Y78700D01*
G01X312933Y79075D02*
X313183Y78867D01*
X313475Y78742D01*
X313850Y78700D01*
X314225Y78783D01*
X314517Y78950D01*
X314725Y79242D01*
X314767Y79575D01*
X314683Y79908D01*
X314475Y80117D01*
X314183Y80283D01*
X313892Y80325D01*
X313600Y80283D01*
X313225Y80117D01*
X313350Y81200D01*
X314475D01*
G01X316950Y78700D02*
X317242Y78742D01*
X317575Y78867D01*
X317783Y79075D01*
X317867Y79367D01*
X317783Y79658D01*
X317533Y79908D01*
X317158Y80033D01*
X316742D01*
X316492Y80117D01*
X316283Y80325D01*
X316200Y80617D01*
X316325Y80908D01*
X316617Y81117D01*
X316950Y81200D01*
X317283Y81117D01*
X317575Y80908D01*
X317700Y80617D01*
X317617Y80325D01*
X317408Y80117D01*
X317158Y80033D01*
X316742D01*
X316367Y79908D01*
X316117Y79658D01*
X316033Y79367D01*
X316117Y79075D01*
X316325Y78867D01*
X316658Y78742D01*
X316950Y78700D01*
G01X312162Y99131D02*
G03I-1850J0D01*
G01X306017Y91000D02*
Y93500D01*
X307017D01*
X307350Y93375D01*
X307600Y93083D01*
X307683Y92750D01*
X307600Y92417D01*
X307392Y92167D01*
X307017Y92042D01*
X306017D01*
G01X309117Y91000D02*
Y93500D01*
X310158D01*
X310492Y93375D01*
X310700Y93208D01*
X310783Y92875D01*
X310700Y92542D01*
X310450Y92333D01*
X310158Y92208D01*
X309117D01*
G01X310158D02*
X310783Y91000D01*
G01X313550D02*
Y93500D01*
X312008Y91708D01*
X314092D01*
G01X316650Y91000D02*
Y93500D01*
X315108Y91708D01*
X317192D01*
G01X296017Y105500D02*
Y108000D01*
X297058D01*
X297392Y107875D01*
X297600Y107708D01*
X297683Y107375D01*
X297600Y107042D01*
X297350Y106833D01*
X297058Y106708D01*
X296017D01*
G01X297058D02*
X297683Y105500D01*
G01X299033Y106000D02*
X299283Y105708D01*
X299617Y105542D01*
X299992Y105500D01*
X300325Y105542D01*
X300658Y105750D01*
X300867Y106000D01*
X300908Y106250D01*
X300825Y106542D01*
X300533Y106750D01*
X300242Y106833D01*
X299867D01*
G01X300242D02*
X300492Y106958D01*
X300700Y107167D01*
X300783Y107417D01*
X300700Y107667D01*
X300492Y107875D01*
X300117Y108000D01*
X299742Y107958D01*
X299367Y107792D01*
G01X302133Y105875D02*
X302383Y105667D01*
X302675Y105542D01*
X303050Y105500D01*
X303425Y105583D01*
X303717Y105750D01*
X303925Y106042D01*
X303967Y106375D01*
X303883Y106708D01*
X303675Y106917D01*
X303383Y107083D01*
X303092Y107125D01*
X302800Y107083D01*
X302425Y106917D01*
X302550Y108000D01*
X303675D01*
G01X305358Y107583D02*
X305608Y107833D01*
X305900Y107958D01*
X306233Y108000D01*
X306650Y107917D01*
X306942Y107708D01*
X307025Y107458D01*
X306983Y107208D01*
X306817Y107000D01*
X305983Y106583D01*
X305608Y106292D01*
X305358Y105875D01*
X305275Y105500D01*
X307025D01*
G01X296017Y101500D02*
Y104000D01*
X297058D01*
X297392Y103875D01*
X297600Y103708D01*
X297683Y103375D01*
X297600Y103042D01*
X297350Y102833D01*
X297058Y102708D01*
X296017D01*
G01X297058D02*
X297683Y101500D01*
G01X299033Y102000D02*
X299283Y101708D01*
X299617Y101542D01*
X299992Y101500D01*
X300325Y101542D01*
X300658Y101750D01*
X300867Y102000D01*
X300908Y102250D01*
X300825Y102542D01*
X300533Y102750D01*
X300242Y102833D01*
X299867D01*
G01X300242D02*
X300492Y102958D01*
X300700Y103167D01*
X300783Y103417D01*
X300700Y103667D01*
X300492Y103875D01*
X300117Y104000D01*
X299742Y103958D01*
X299367Y103792D01*
G01X302133Y101875D02*
X302383Y101667D01*
X302675Y101542D01*
X303050Y101500D01*
X303425Y101583D01*
X303717Y101750D01*
X303925Y102042D01*
X303967Y102375D01*
X303883Y102708D01*
X303675Y102917D01*
X303383Y103083D01*
X303092Y103125D01*
X302800Y103083D01*
X302425Y102917D01*
X302550Y104000D01*
X303675D01*
G01X306150Y101500D02*
X306442Y101542D01*
X306775Y101667D01*
X306983Y101875D01*
X307067Y102167D01*
X306983Y102458D01*
X306733Y102708D01*
X306358Y102833D01*
X305942D01*
X305692Y102917D01*
X305483Y103125D01*
X305400Y103417D01*
X305525Y103708D01*
X305817Y103917D01*
X306150Y104000D01*
X306483Y103917D01*
X306775Y103708D01*
X306900Y103417D01*
X306817Y103125D01*
X306608Y102917D01*
X306358Y102833D01*
X305942D01*
X305567Y102708D01*
X305317Y102458D01*
X305233Y102167D01*
X305317Y101875D01*
X305525Y101667D01*
X305858Y101542D01*
X306150Y101500D01*
G01X312162Y107511D02*
G03I-1850J0D01*
G01X297017Y120500D02*
Y123000D01*
X298058D01*
X298392Y122875D01*
X298600Y122708D01*
X298683Y122375D01*
X298600Y122042D01*
X298350Y121833D01*
X298058Y121708D01*
X297017D01*
G01X298058D02*
X298683Y120500D01*
G01X300033Y121000D02*
X300283Y120708D01*
X300617Y120542D01*
X300992Y120500D01*
X301325Y120542D01*
X301658Y120750D01*
X301867Y121000D01*
X301908Y121250D01*
X301825Y121542D01*
X301533Y121750D01*
X301242Y121833D01*
X300867D01*
G01X301242D02*
X301492Y121958D01*
X301700Y122167D01*
X301783Y122417D01*
X301700Y122667D01*
X301492Y122875D01*
X301117Y123000D01*
X300742Y122958D01*
X300367Y122792D01*
G01X303967Y120500D02*
X304050Y121042D01*
X304175Y121500D01*
X304342Y121917D01*
X304550Y122375D01*
X304883Y123000D01*
X303217D01*
G01X307150Y120500D02*
Y123000D01*
X306650Y122500D01*
G01Y120500D02*
X307650D01*
G01X304100Y131200D02*
X306600D01*
G01X304100Y130242D02*
Y132158D01*
G01X306600Y133467D02*
X304100D01*
Y134467D01*
X304225Y134800D01*
X304517Y135050D01*
X304850Y135133D01*
X305183Y135050D01*
X305433Y134842D01*
X305558Y134467D01*
Y133467D01*
G01X306600Y137317D02*
X306058Y137400D01*
X305600Y137525D01*
X305183Y137692D01*
X304725Y137900D01*
X304100Y138233D01*
Y136567D01*
G01X297017Y124500D02*
Y127000D01*
X298058D01*
X298392Y126875D01*
X298600Y126708D01*
X298683Y126375D01*
X298600Y126042D01*
X298350Y125833D01*
X298058Y125708D01*
X297017D01*
G01X298058D02*
X298683Y124500D01*
G01X300950D02*
Y127000D01*
X300450Y126500D01*
G01Y124500D02*
X301450D01*
G01X304050D02*
Y127000D01*
X303550Y126500D01*
G01Y124500D02*
X304550D01*
G01X307150D02*
Y127000D01*
X306650Y126500D01*
G01Y124500D02*
X307650D01*
G01X296000Y154000D02*
Y165100D01*
G01X301500Y180000D02*
X308000D01*
Y153000D01*
X301600D01*
G01X305000Y168967D02*
X298000D01*
Y174033D01*
G01X301383Y172167D02*
Y168967D01*
G01X303000Y196483D02*
X304792D01*
X305167Y196650D01*
X305417Y196983D01*
X305500Y197400D01*
X305417Y197817D01*
X305167Y198150D01*
X304792Y198317D01*
X303000D01*
G01X305500Y200500D02*
X303000D01*
X303500Y200000D01*
G01X305500D02*
Y201000D01*
G01X305000Y202683D02*
X305292Y202933D01*
X305458Y203267D01*
X305500Y203642D01*
X305458Y203975D01*
X305250Y204308D01*
X305000Y204517D01*
X304750Y204558D01*
X304458Y204475D01*
X304250Y204183D01*
X304167Y203892D01*
Y203517D01*
G01Y203892D02*
X304042Y204142D01*
X303833Y204350D01*
X303583Y204433D01*
X303333Y204350D01*
X303125Y204142D01*
X303000Y203767D01*
X303042Y203392D01*
X303208Y203017D01*
G01X300067Y184000D02*
Y186500D01*
X301108D01*
X301442Y186375D01*
X301650Y186208D01*
X301733Y185875D01*
X301650Y185542D01*
X301400Y185333D01*
X301108Y185208D01*
X300067D01*
G01X301108D02*
X301733Y184000D01*
G01X304000D02*
X304292Y184042D01*
X304625Y184167D01*
X304833Y184375D01*
X304917Y184667D01*
X304833Y184958D01*
X304583Y185208D01*
X304208Y185333D01*
X303792D01*
X303542Y185417D01*
X303333Y185625D01*
X303250Y185917D01*
X303375Y186208D01*
X303667Y186417D01*
X304000Y186500D01*
X304333Y186417D01*
X304625Y186208D01*
X304750Y185917D01*
X304667Y185625D01*
X304458Y185417D01*
X304208Y185333D01*
X303792D01*
X303417Y185208D01*
X303167Y184958D01*
X303083Y184667D01*
X303167Y184375D01*
X303375Y184167D01*
X303708Y184042D01*
X304000Y184000D01*
G01X307600D02*
Y186500D01*
X306058Y184708D01*
X308142D01*
G01X300067Y188500D02*
Y191000D01*
X301108D01*
X301442Y190875D01*
X301650Y190708D01*
X301733Y190375D01*
X301650Y190042D01*
X301400Y189833D01*
X301108Y189708D01*
X300067D01*
G01X301108D02*
X301733Y188500D01*
G01X303208Y189542D02*
X303500Y189833D01*
X303750Y190000D01*
X304083Y190083D01*
X304375Y190000D01*
X304583Y189833D01*
X304750Y189583D01*
X304792Y189292D01*
X304750Y189042D01*
X304583Y188792D01*
X304333Y188583D01*
X304042Y188500D01*
X303708Y188583D01*
X303417Y188833D01*
X303250Y189208D01*
X303208Y189625D01*
X303292Y190167D01*
X303417Y190458D01*
X303625Y190750D01*
X303917Y190958D01*
X304208Y191000D01*
X304500Y190917D01*
X304708Y190708D01*
G01X306308Y189542D02*
X306600Y189833D01*
X306850Y190000D01*
X307183Y190083D01*
X307475Y190000D01*
X307683Y189833D01*
X307850Y189583D01*
X307892Y189292D01*
X307850Y189042D01*
X307683Y188792D01*
X307433Y188583D01*
X307142Y188500D01*
X306808Y188583D01*
X306517Y188833D01*
X306350Y189208D01*
X306308Y189625D01*
X306392Y190167D01*
X306517Y190458D01*
X306725Y190750D01*
X307017Y190958D01*
X307308Y191000D01*
X307600Y190917D01*
X307808Y190708D01*
G01X312162Y201151D02*
G03I-1850J0D01*
G01Y209531D02*
G03I-1850J0D01*
G01X299608Y224117D02*
X299483Y223867D01*
X299400Y223575D01*
Y223242D01*
X299525Y222867D01*
X299733Y222575D01*
X299983Y222367D01*
X300400Y222200D01*
X300775Y222158D01*
X301150Y222242D01*
X301400Y222367D01*
X301650Y222617D01*
X301817Y222908D01*
X301900Y223200D01*
Y223492D01*
X301817Y223783D01*
X301692Y224033D01*
X301525Y224242D01*
G01X301900Y226217D02*
X301358Y226300D01*
X300900Y226425D01*
X300483Y226592D01*
X300025Y226800D01*
X299400Y227133D01*
Y225467D01*
G01X301900Y229400D02*
X301858Y229692D01*
X301733Y230025D01*
X301525Y230233D01*
X301233Y230317D01*
X300942Y230233D01*
X300692Y229983D01*
X300567Y229608D01*
Y229192D01*
X300483Y228942D01*
X300275Y228733D01*
X299983Y228650D01*
X299692Y228775D01*
X299483Y229067D01*
X299400Y229400D01*
X299483Y229733D01*
X299692Y230025D01*
X299983Y230150D01*
X300275Y230067D01*
X300483Y229858D01*
X300567Y229608D01*
Y229192D01*
X300692Y228817D01*
X300942Y228567D01*
X301233Y228483D01*
X301525Y228567D01*
X301733Y228775D01*
X301858Y229108D01*
X301900Y229400D01*
G01X295708Y224117D02*
X295583Y223867D01*
X295500Y223575D01*
Y223242D01*
X295625Y222867D01*
X295833Y222575D01*
X296083Y222367D01*
X296500Y222200D01*
X296875Y222158D01*
X297250Y222242D01*
X297500Y222367D01*
X297750Y222617D01*
X297917Y222908D01*
X298000Y223200D01*
Y223492D01*
X297917Y223783D01*
X297792Y224033D01*
X297625Y224242D01*
G01X298000Y226217D02*
X297458Y226300D01*
X297000Y226425D01*
X296583Y226592D01*
X296125Y226800D01*
X295500Y227133D01*
Y225467D01*
G01X298000Y229317D02*
X297458Y229400D01*
X297000Y229525D01*
X296583Y229692D01*
X296125Y229900D01*
X295500Y230233D01*
Y228567D01*
G01X305817Y221792D02*
X305567Y221917D01*
X305275Y222000D01*
X304942D01*
X304567Y221875D01*
X304275Y221667D01*
X304067Y221417D01*
X303900Y221000D01*
X303858Y220625D01*
X303942Y220250D01*
X304067Y220000D01*
X304317Y219750D01*
X304608Y219583D01*
X304900Y219500D01*
X305192D01*
X305483Y219583D01*
X305733Y219708D01*
X305942Y219875D01*
G01X307917Y219500D02*
X308000Y220042D01*
X308125Y220500D01*
X308292Y220917D01*
X308500Y221375D01*
X308833Y222000D01*
X307167D01*
G01X311100D02*
X310767Y221917D01*
X310517Y221708D01*
X310350Y221458D01*
X310225Y221125D01*
X310183Y220750D01*
X310225Y220375D01*
X310350Y220042D01*
X310517Y219792D01*
X310767Y219583D01*
X311100Y219500D01*
X311433Y219583D01*
X311683Y219792D01*
X311850Y220042D01*
X311975Y220375D01*
X312017Y220750D01*
X311975Y221125D01*
X311850Y221458D01*
X311683Y221708D01*
X311433Y221917D01*
X311100Y222000D01*
G01X304017Y227500D02*
Y230000D01*
X305058D01*
X305392Y229875D01*
X305600Y229708D01*
X305683Y229375D01*
X305600Y229042D01*
X305350Y228833D01*
X305058Y228708D01*
X304017D01*
G01X305058D02*
X305683Y227500D01*
G01X307033Y228000D02*
X307283Y227708D01*
X307617Y227542D01*
X307992Y227500D01*
X308325Y227542D01*
X308658Y227750D01*
X308867Y228000D01*
X308908Y228250D01*
X308825Y228542D01*
X308533Y228750D01*
X308242Y228833D01*
X307867D01*
G01X308242D02*
X308492Y228958D01*
X308700Y229167D01*
X308783Y229417D01*
X308700Y229667D01*
X308492Y229875D01*
X308117Y230000D01*
X307742Y229958D01*
X307367Y229792D01*
G01X311050Y230000D02*
X310717Y229917D01*
X310467Y229708D01*
X310300Y229458D01*
X310175Y229125D01*
X310133Y228750D01*
X310175Y228375D01*
X310300Y228042D01*
X310467Y227792D01*
X310717Y227583D01*
X311050Y227500D01*
X311383Y227583D01*
X311633Y227792D01*
X311800Y228042D01*
X311925Y228375D01*
X311967Y228750D01*
X311925Y229125D01*
X311800Y229458D01*
X311633Y229708D01*
X311383Y229917D01*
X311050Y230000D01*
G01X314150Y227500D02*
Y230000D01*
X313650Y229500D01*
G01Y227500D02*
X314650D01*
G01X304017Y223500D02*
Y226000D01*
X305058D01*
X305392Y225875D01*
X305600Y225708D01*
X305683Y225375D01*
X305600Y225042D01*
X305350Y224833D01*
X305058Y224708D01*
X304017D01*
G01X305058D02*
X305683Y223500D01*
G01X307033Y224000D02*
X307283Y223708D01*
X307617Y223542D01*
X307992Y223500D01*
X308325Y223542D01*
X308658Y223750D01*
X308867Y224000D01*
X308908Y224250D01*
X308825Y224542D01*
X308533Y224750D01*
X308242Y224833D01*
X307867D01*
G01X308242D02*
X308492Y224958D01*
X308700Y225167D01*
X308783Y225417D01*
X308700Y225667D01*
X308492Y225875D01*
X308117Y226000D01*
X307742Y225958D01*
X307367Y225792D01*
G01X311050Y223500D02*
Y226000D01*
X310550Y225500D01*
G01Y223500D02*
X311550D01*
G01X313358Y225583D02*
X313608Y225833D01*
X313900Y225958D01*
X314233Y226000D01*
X314650Y225917D01*
X314942Y225708D01*
X315025Y225458D01*
X314983Y225208D01*
X314817Y225000D01*
X313983Y224583D01*
X313608Y224292D01*
X313358Y223875D01*
X313275Y223500D01*
X315025D01*
G01X298800Y252450D02*
Y232545D01*
G01X309000Y264517D02*
X306500D01*
Y265558D01*
X306625Y265892D01*
X306792Y266100D01*
X307125Y266183D01*
X307458Y266100D01*
X307667Y265850D01*
X307792Y265558D01*
Y264517D01*
G01Y265558D02*
X309000Y266183D01*
G01Y268450D02*
X306500D01*
X307000Y267950D01*
G01X309000D02*
Y268950D01*
G01Y271550D02*
X308958Y271842D01*
X308833Y272175D01*
X308625Y272383D01*
X308333Y272467D01*
X308042Y272383D01*
X307792Y272133D01*
X307667Y271758D01*
Y271342D01*
X307583Y271092D01*
X307375Y270883D01*
X307083Y270800D01*
X306792Y270925D01*
X306583Y271217D01*
X306500Y271550D01*
X306583Y271883D01*
X306792Y272175D01*
X307083Y272300D01*
X307375Y272217D01*
X307583Y272008D01*
X307667Y271758D01*
Y271342D01*
X307792Y270967D01*
X308042Y270717D01*
X308333Y270633D01*
X308625Y270717D01*
X308833Y270925D01*
X308958Y271258D01*
X309000Y271550D01*
G01X308708Y273942D02*
X308917Y274233D01*
X309000Y274567D01*
X308917Y274900D01*
X308667Y275192D01*
X308292Y275400D01*
X307917Y275483D01*
X307458D01*
X307083Y275400D01*
X306750Y275192D01*
X306583Y274942D01*
X306500Y274650D01*
X306583Y274317D01*
X306750Y274067D01*
X307000Y273900D01*
X307333Y273817D01*
X307625Y273900D01*
X307917Y274108D01*
X308083Y274358D01*
X308125Y274650D01*
X308042Y274983D01*
X307833Y275233D01*
X307458Y275483D01*
G01X325500Y75517D02*
X323000D01*
Y76517D01*
X323125Y76850D01*
X323417Y77100D01*
X323750Y77183D01*
X324083Y77100D01*
X324333Y76892D01*
X324458Y76517D01*
Y75517D01*
G01X325500Y78617D02*
X323000D01*
Y79658D01*
X323125Y79992D01*
X323292Y80200D01*
X323625Y80283D01*
X323958Y80200D01*
X324167Y79950D01*
X324292Y79658D01*
Y78617D01*
G01Y79658D02*
X325500Y80283D01*
G01Y83050D02*
X323000D01*
X324792Y81508D01*
Y83592D01*
G01X325500Y85567D02*
X324958Y85650D01*
X324500Y85775D01*
X324083Y85942D01*
X323625Y86150D01*
X323000Y86483D01*
Y84817D01*
G01X322000Y81017D02*
X319500D01*
Y82017D01*
X319625Y82350D01*
X319917Y82600D01*
X320250Y82683D01*
X320583Y82600D01*
X320833Y82392D01*
X320958Y82017D01*
Y81017D01*
G01X322000Y84117D02*
X319500D01*
Y85158D01*
X319625Y85492D01*
X319792Y85700D01*
X320125Y85783D01*
X320458Y85700D01*
X320667Y85450D01*
X320792Y85158D01*
Y84117D01*
G01Y85158D02*
X322000Y85783D01*
G01X321625Y87133D02*
X321833Y87383D01*
X321958Y87675D01*
X322000Y88050D01*
X321917Y88425D01*
X321750Y88717D01*
X321458Y88925D01*
X321125Y88967D01*
X320792Y88883D01*
X320583Y88675D01*
X320417Y88383D01*
X320375Y88092D01*
X320417Y87800D01*
X320583Y87425D01*
X319500Y87550D01*
Y88675D01*
G01Y91150D02*
X319583Y90817D01*
X319792Y90567D01*
X320042Y90400D01*
X320375Y90275D01*
X320750Y90233D01*
X321125Y90275D01*
X321458Y90400D01*
X321708Y90567D01*
X321917Y90817D01*
X322000Y91150D01*
X321917Y91483D01*
X321708Y91733D01*
X321458Y91900D01*
X321125Y92025D01*
X320750Y92067D01*
X320375Y92025D01*
X320042Y91900D01*
X319792Y91733D01*
X319583Y91483D01*
X319500Y91150D01*
G01X434142Y99131D02*
X320582D01*
G01X310312Y100981D02*
Y105661D01*
G01X316882Y99131D02*
X312162D01*
G01X320582D02*
G03I-1850J0D01*
G01X310312Y109361D02*
Y199301D01*
G01Y203001D02*
Y207681D01*
G01X312162Y209531D02*
X316882D01*
G01X320582D02*
X434142D01*
G01X320582D02*
G03I-1850J0D01*
G01X319500Y220017D02*
X317000D01*
Y221058D01*
X317125Y221392D01*
X317292Y221600D01*
X317625Y221683D01*
X317958Y221600D01*
X318167Y221350D01*
X318292Y221058D01*
Y220017D01*
G01Y221058D02*
X319500Y221683D01*
G01Y223950D02*
X317000D01*
X317500Y223450D01*
G01X319500D02*
Y224450D01*
G01X319000Y226133D02*
X319292Y226383D01*
X319458Y226717D01*
X319500Y227092D01*
X319458Y227425D01*
X319250Y227758D01*
X319000Y227967D01*
X318750Y228008D01*
X318458Y227925D01*
X318250Y227633D01*
X318167Y227342D01*
Y226967D01*
G01Y227342D02*
X318042Y227592D01*
X317833Y227800D01*
X317583Y227883D01*
X317333Y227800D01*
X317125Y227592D01*
X317000Y227217D01*
X317042Y226842D01*
X317208Y226467D01*
G01X319500Y230650D02*
X317000D01*
X318792Y229108D01*
Y231192D01*
G01X318708Y235317D02*
X318583Y235067D01*
X318500Y234775D01*
Y234442D01*
X318625Y234067D01*
X318833Y233775D01*
X319083Y233567D01*
X319500Y233400D01*
X319875Y233358D01*
X320250Y233442D01*
X320500Y233567D01*
X320750Y233817D01*
X320917Y234108D01*
X321000Y234400D01*
Y234692D01*
X320917Y234983D01*
X320792Y235233D01*
X320625Y235442D01*
G01X321000Y237500D02*
X320958Y237792D01*
X320833Y238125D01*
X320625Y238333D01*
X320333Y238417D01*
X320042Y238333D01*
X319792Y238083D01*
X319667Y237708D01*
Y237292D01*
X319583Y237042D01*
X319375Y236833D01*
X319083Y236750D01*
X318792Y236875D01*
X318583Y237167D01*
X318500Y237500D01*
X318583Y237833D01*
X318792Y238125D01*
X319083Y238250D01*
X319375Y238167D01*
X319583Y237958D01*
X319667Y237708D01*
Y237292D01*
X319792Y236917D01*
X320042Y236667D01*
X320333Y236583D01*
X320625Y236667D01*
X320833Y236875D01*
X320958Y237208D01*
X321000Y237500D01*
G01X320500Y239683D02*
X320792Y239933D01*
X320958Y240267D01*
X321000Y240642D01*
X320958Y240975D01*
X320750Y241308D01*
X320500Y241517D01*
X320250Y241558D01*
X319958Y241475D01*
X319750Y241183D01*
X319667Y240892D01*
Y240517D01*
G01Y240892D02*
X319542Y241142D01*
X319333Y241350D01*
X319083Y241433D01*
X318833Y241350D01*
X318625Y241142D01*
X318500Y240767D01*
X318542Y240392D01*
X318708Y240017D01*
G01X325208Y240317D02*
X325083Y240067D01*
X325000Y239775D01*
Y239442D01*
X325125Y239067D01*
X325333Y238775D01*
X325583Y238567D01*
X326000Y238400D01*
X326375Y238358D01*
X326750Y238442D01*
X327000Y238567D01*
X327250Y238817D01*
X327417Y239108D01*
X327500Y239400D01*
Y239692D01*
X327417Y239983D01*
X327292Y240233D01*
X327125Y240442D01*
G01X326458Y241708D02*
X326167Y242000D01*
X326000Y242250D01*
X325917Y242583D01*
X326000Y242875D01*
X326167Y243083D01*
X326417Y243250D01*
X326708Y243292D01*
X326958Y243250D01*
X327208Y243083D01*
X327417Y242833D01*
X327500Y242542D01*
X327417Y242208D01*
X327167Y241917D01*
X326792Y241750D01*
X326375Y241708D01*
X325833Y241792D01*
X325542Y241917D01*
X325250Y242125D01*
X325042Y242417D01*
X325000Y242708D01*
X325083Y243000D01*
X325292Y243208D01*
G01X327208Y244892D02*
X327417Y245183D01*
X327500Y245517D01*
X327417Y245850D01*
X327167Y246142D01*
X326792Y246350D01*
X326417Y246433D01*
X325958D01*
X325583Y246350D01*
X325250Y246142D01*
X325083Y245892D01*
X325000Y245600D01*
X325083Y245267D01*
X325250Y245017D01*
X325500Y244850D01*
X325833Y244767D01*
X326125Y244850D01*
X326417Y245058D01*
X326583Y245308D01*
X326625Y245600D01*
X326542Y245933D01*
X326333Y246183D01*
X325958Y246433D01*
G01X321000Y264517D02*
X318500D01*
Y265558D01*
X318625Y265892D01*
X318792Y266100D01*
X319125Y266183D01*
X319458Y266100D01*
X319667Y265850D01*
X319792Y265558D01*
Y264517D01*
G01Y265558D02*
X321000Y266183D01*
G01Y268450D02*
X318500D01*
X319000Y267950D01*
G01X321000D02*
Y268950D01*
G01Y271550D02*
X320958Y271842D01*
X320833Y272175D01*
X320625Y272383D01*
X320333Y272467D01*
X320042Y272383D01*
X319792Y272133D01*
X319667Y271758D01*
Y271342D01*
X319583Y271092D01*
X319375Y270883D01*
X319083Y270800D01*
X318792Y270925D01*
X318583Y271217D01*
X318500Y271550D01*
X318583Y271883D01*
X318792Y272175D01*
X319083Y272300D01*
X319375Y272217D01*
X319583Y272008D01*
X319667Y271758D01*
Y271342D01*
X319792Y270967D01*
X320042Y270717D01*
X320333Y270633D01*
X320625Y270717D01*
X320833Y270925D01*
X320958Y271258D01*
X321000Y271550D01*
G01X319958Y273858D02*
X319667Y274150D01*
X319500Y274400D01*
X319417Y274733D01*
X319500Y275025D01*
X319667Y275233D01*
X319917Y275400D01*
X320208Y275442D01*
X320458Y275400D01*
X320708Y275233D01*
X320917Y274983D01*
X321000Y274692D01*
X320917Y274358D01*
X320667Y274067D01*
X320292Y273900D01*
X319875Y273858D01*
X319333Y273942D01*
X319042Y274067D01*
X318750Y274275D01*
X318542Y274567D01*
X318500Y274858D01*
X318583Y275150D01*
X318792Y275358D01*
G01X325000Y264517D02*
X322500D01*
Y265558D01*
X322625Y265892D01*
X322792Y266100D01*
X323125Y266183D01*
X323458Y266100D01*
X323667Y265850D01*
X323792Y265558D01*
Y264517D01*
G01Y265558D02*
X325000Y266183D01*
G01Y268450D02*
X322500D01*
X323000Y267950D01*
G01X325000D02*
Y268950D01*
G01Y271550D02*
X324958Y271842D01*
X324833Y272175D01*
X324625Y272383D01*
X324333Y272467D01*
X324042Y272383D01*
X323792Y272133D01*
X323667Y271758D01*
Y271342D01*
X323583Y271092D01*
X323375Y270883D01*
X323083Y270800D01*
X322792Y270925D01*
X322583Y271217D01*
X322500Y271550D01*
X322583Y271883D01*
X322792Y272175D01*
X323083Y272300D01*
X323375Y272217D01*
X323583Y272008D01*
X323667Y271758D01*
Y271342D01*
X323792Y270967D01*
X324042Y270717D01*
X324333Y270633D01*
X324625Y270717D01*
X324833Y270925D01*
X324958Y271258D01*
X325000Y271550D01*
G01Y274567D02*
X324458Y274650D01*
X324000Y274775D01*
X323583Y274942D01*
X323125Y275150D01*
X322500Y275483D01*
Y273817D01*
G01X313000Y264517D02*
X310500D01*
Y265558D01*
X310625Y265892D01*
X310792Y266100D01*
X311125Y266183D01*
X311458Y266100D01*
X311667Y265850D01*
X311792Y265558D01*
Y264517D01*
G01Y265558D02*
X313000Y266183D01*
G01Y268450D02*
X310500D01*
X311000Y267950D01*
G01X313000D02*
Y268950D01*
G01Y271467D02*
X312458Y271550D01*
X312000Y271675D01*
X311583Y271842D01*
X311125Y272050D01*
X310500Y272383D01*
Y270717D01*
G01X313000Y274650D02*
X312958Y274942D01*
X312833Y275275D01*
X312625Y275483D01*
X312333Y275567D01*
X312042Y275483D01*
X311792Y275233D01*
X311667Y274858D01*
Y274442D01*
X311583Y274192D01*
X311375Y273983D01*
X311083Y273900D01*
X310792Y274025D01*
X310583Y274317D01*
X310500Y274650D01*
X310583Y274983D01*
X310792Y275275D01*
X311083Y275400D01*
X311375Y275317D01*
X311583Y275108D01*
X311667Y274858D01*
Y274442D01*
X311792Y274067D01*
X312042Y273817D01*
X312333Y273733D01*
X312625Y273817D01*
X312833Y274025D01*
X312958Y274358D01*
X313000Y274650D01*
G01X317000Y264517D02*
X314500D01*
Y265558D01*
X314625Y265892D01*
X314792Y266100D01*
X315125Y266183D01*
X315458Y266100D01*
X315667Y265850D01*
X315792Y265558D01*
Y264517D01*
G01Y265558D02*
X317000Y266183D01*
G01Y268450D02*
X314500D01*
X315000Y267950D01*
G01X317000D02*
Y268950D01*
G01Y271550D02*
X316958Y271842D01*
X316833Y272175D01*
X316625Y272383D01*
X316333Y272467D01*
X316042Y272383D01*
X315792Y272133D01*
X315667Y271758D01*
Y271342D01*
X315583Y271092D01*
X315375Y270883D01*
X315083Y270800D01*
X314792Y270925D01*
X314583Y271217D01*
X314500Y271550D01*
X314583Y271883D01*
X314792Y272175D01*
X315083Y272300D01*
X315375Y272217D01*
X315583Y272008D01*
X315667Y271758D01*
Y271342D01*
X315792Y270967D01*
X316042Y270717D01*
X316333Y270633D01*
X316625Y270717D01*
X316833Y270925D01*
X316958Y271258D01*
X317000Y271550D01*
G01X316500Y273733D02*
X316792Y273983D01*
X316958Y274317D01*
X317000Y274692D01*
X316958Y275025D01*
X316750Y275358D01*
X316500Y275567D01*
X316250Y275608D01*
X315958Y275525D01*
X315750Y275233D01*
X315667Y274942D01*
Y274567D01*
G01Y274942D02*
X315542Y275192D01*
X315333Y275400D01*
X315083Y275483D01*
X314833Y275400D01*
X314625Y275192D01*
X314500Y274817D01*
X314542Y274442D01*
X314708Y274067D01*
G01X336400Y41617D02*
X333900D01*
Y42658D01*
X334025Y42992D01*
X334192Y43200D01*
X334525Y43283D01*
X334858Y43200D01*
X335067Y42950D01*
X335192Y42658D01*
Y41617D01*
G01Y42658D02*
X336400Y43283D01*
G01Y46050D02*
X333900D01*
X335692Y44508D01*
Y46592D01*
G01X336025Y47733D02*
X336233Y47983D01*
X336358Y48275D01*
X336400Y48650D01*
X336317Y49025D01*
X336150Y49317D01*
X335858Y49525D01*
X335525Y49567D01*
X335192Y49483D01*
X334983Y49275D01*
X334817Y48983D01*
X334775Y48692D01*
X334817Y48400D01*
X334983Y48025D01*
X333900Y48150D01*
Y49275D01*
G01X336400Y51750D02*
X336358Y52042D01*
X336233Y52375D01*
X336025Y52583D01*
X335733Y52667D01*
X335442Y52583D01*
X335192Y52333D01*
X335067Y51958D01*
Y51542D01*
X334983Y51292D01*
X334775Y51083D01*
X334483Y51000D01*
X334192Y51125D01*
X333983Y51417D01*
X333900Y51750D01*
X333983Y52083D01*
X334192Y52375D01*
X334483Y52500D01*
X334775Y52417D01*
X334983Y52208D01*
X335067Y51958D01*
Y51542D01*
X335192Y51167D01*
X335442Y50917D01*
X335733Y50833D01*
X336025Y50917D01*
X336233Y51125D01*
X336358Y51458D01*
X336400Y51750D01*
G01X332500Y41717D02*
X330000D01*
Y42758D01*
X330125Y43092D01*
X330292Y43300D01*
X330625Y43383D01*
X330958Y43300D01*
X331167Y43050D01*
X331292Y42758D01*
Y41717D01*
G01Y42758D02*
X332500Y43383D01*
G01Y46150D02*
X330000D01*
X331792Y44608D01*
Y46692D01*
G01X332125Y47833D02*
X332333Y48083D01*
X332458Y48375D01*
X332500Y48750D01*
X332417Y49125D01*
X332250Y49417D01*
X331958Y49625D01*
X331625Y49667D01*
X331292Y49583D01*
X331083Y49375D01*
X330917Y49083D01*
X330875Y48792D01*
X330917Y48500D01*
X331083Y48125D01*
X330000Y48250D01*
Y49375D01*
G01X332208Y51142D02*
X332417Y51433D01*
X332500Y51767D01*
X332417Y52100D01*
X332167Y52392D01*
X331792Y52600D01*
X331417Y52683D01*
X330958D01*
X330583Y52600D01*
X330250Y52392D01*
X330083Y52142D01*
X330000Y51850D01*
X330083Y51517D01*
X330250Y51267D01*
X330500Y51100D01*
X330833Y51017D01*
X331125Y51100D01*
X331417Y51308D01*
X331583Y51558D01*
X331625Y51850D01*
X331542Y52183D01*
X331333Y52433D01*
X330958Y52683D01*
G01X333000Y54967D02*
X330500D01*
Y55967D01*
X330625Y56300D01*
X330917Y56550D01*
X331250Y56633D01*
X331583Y56550D01*
X331833Y56342D01*
X331958Y55967D01*
Y54967D01*
G01X330708Y59817D02*
X330583Y59567D01*
X330500Y59275D01*
Y58942D01*
X330625Y58567D01*
X330833Y58275D01*
X331083Y58067D01*
X331500Y57900D01*
X331875Y57858D01*
X332250Y57942D01*
X332500Y58067D01*
X332750Y58317D01*
X332917Y58608D01*
X333000Y58900D01*
Y59192D01*
X332917Y59483D01*
X332792Y59733D01*
X332625Y59942D01*
G01X333000Y62000D02*
X330500D01*
X331000Y61500D01*
G01X333000D02*
Y62500D01*
G01X332708Y64392D02*
X332917Y64683D01*
X333000Y65017D01*
X332917Y65350D01*
X332667Y65642D01*
X332292Y65850D01*
X331917Y65933D01*
X331458D01*
X331083Y65850D01*
X330750Y65642D01*
X330583Y65392D01*
X330500Y65100D01*
X330583Y64767D01*
X330750Y64517D01*
X331000Y64350D01*
X331333Y64267D01*
X331625Y64350D01*
X331917Y64558D01*
X332083Y64808D01*
X332125Y65100D01*
X332042Y65433D01*
X331833Y65683D01*
X331458Y65933D01*
G01X331958Y67408D02*
X331667Y67700D01*
X331500Y67950D01*
X331417Y68283D01*
X331500Y68575D01*
X331667Y68783D01*
X331917Y68950D01*
X332208Y68992D01*
X332458Y68950D01*
X332708Y68783D01*
X332917Y68533D01*
X333000Y68242D01*
X332917Y67908D01*
X332667Y67617D01*
X332292Y67450D01*
X331875Y67408D01*
X331333Y67492D01*
X331042Y67617D01*
X330750Y67825D01*
X330542Y68117D01*
X330500Y68408D01*
X330583Y68700D01*
X330792Y68908D01*
G01X328500Y54967D02*
X326000D01*
Y55967D01*
X326125Y56300D01*
X326417Y56550D01*
X326750Y56633D01*
X327083Y56550D01*
X327333Y56342D01*
X327458Y55967D01*
Y54967D01*
G01X326208Y59817D02*
X326083Y59567D01*
X326000Y59275D01*
Y58942D01*
X326125Y58567D01*
X326333Y58275D01*
X326583Y58067D01*
X327000Y57900D01*
X327375Y57858D01*
X327750Y57942D01*
X328000Y58067D01*
X328250Y58317D01*
X328417Y58608D01*
X328500Y58900D01*
Y59192D01*
X328417Y59483D01*
X328292Y59733D01*
X328125Y59942D01*
G01X328500Y62000D02*
X326000D01*
X326500Y61500D01*
G01X328500D02*
Y62500D01*
G01X328208Y64392D02*
X328417Y64683D01*
X328500Y65017D01*
X328417Y65350D01*
X328167Y65642D01*
X327792Y65850D01*
X327417Y65933D01*
X326958D01*
X326583Y65850D01*
X326250Y65642D01*
X326083Y65392D01*
X326000Y65100D01*
X326083Y64767D01*
X326250Y64517D01*
X326500Y64350D01*
X326833Y64267D01*
X327125Y64350D01*
X327417Y64558D01*
X327583Y64808D01*
X327625Y65100D01*
X327542Y65433D01*
X327333Y65683D01*
X326958Y65933D01*
G01X328208Y67492D02*
X328417Y67783D01*
X328500Y68117D01*
X328417Y68450D01*
X328167Y68742D01*
X327792Y68950D01*
X327417Y69033D01*
X326958D01*
X326583Y68950D01*
X326250Y68742D01*
X326083Y68492D01*
X326000Y68200D01*
X326083Y67867D01*
X326250Y67617D01*
X326500Y67450D01*
X326833Y67367D01*
X327125Y67450D01*
X327417Y67658D01*
X327583Y67908D01*
X327625Y68200D01*
X327542Y68533D01*
X327333Y68783D01*
X326958Y69033D01*
G01X329500Y79517D02*
X327000D01*
Y80517D01*
X327125Y80850D01*
X327417Y81100D01*
X327750Y81183D01*
X328083Y81100D01*
X328333Y80892D01*
X328458Y80517D01*
Y79517D01*
G01X327208Y84367D02*
X327083Y84117D01*
X327000Y83825D01*
Y83492D01*
X327125Y83117D01*
X327333Y82825D01*
X327583Y82617D01*
X328000Y82450D01*
X328375Y82408D01*
X328750Y82492D01*
X329000Y82617D01*
X329250Y82867D01*
X329417Y83158D01*
X329500Y83450D01*
Y83742D01*
X329417Y84033D01*
X329292Y84283D01*
X329125Y84492D01*
G01Y85633D02*
X329333Y85883D01*
X329458Y86175D01*
X329500Y86550D01*
X329417Y86925D01*
X329250Y87217D01*
X328958Y87425D01*
X328625Y87467D01*
X328292Y87383D01*
X328083Y87175D01*
X327917Y86883D01*
X327875Y86592D01*
X327917Y86300D01*
X328083Y85925D01*
X327000Y86050D01*
Y87175D01*
G01X328458Y88858D02*
X328167Y89150D01*
X328000Y89400D01*
X327917Y89733D01*
X328000Y90025D01*
X328167Y90233D01*
X328417Y90400D01*
X328708Y90442D01*
X328958Y90400D01*
X329208Y90233D01*
X329417Y89983D01*
X329500Y89692D01*
X329417Y89358D01*
X329167Y89067D01*
X328792Y88900D01*
X328375Y88858D01*
X327833Y88942D01*
X327542Y89067D01*
X327250Y89275D01*
X327042Y89567D01*
X327000Y89858D01*
X327083Y90150D01*
X327292Y90358D01*
G01X337500Y78517D02*
X335000D01*
Y79517D01*
X335125Y79850D01*
X335417Y80100D01*
X335750Y80183D01*
X336083Y80100D01*
X336333Y79892D01*
X336458Y79517D01*
Y78517D01*
G01X337500Y81617D02*
X335000D01*
Y82658D01*
X335125Y82992D01*
X335292Y83200D01*
X335625Y83283D01*
X335958Y83200D01*
X336167Y82950D01*
X336292Y82658D01*
Y81617D01*
G01Y82658D02*
X337500Y83283D01*
G01Y85467D02*
X336958Y85550D01*
X336500Y85675D01*
X336083Y85842D01*
X335625Y86050D01*
X335000Y86383D01*
Y84717D01*
G01X337500Y88650D02*
X335000D01*
X335500Y88150D01*
G01X337500D02*
Y89150D01*
G01X377000Y271000D02*
Y248000D01*
X396000D01*
Y238000D01*
X406500D01*
Y241000D01*
X418000D01*
Y227500D01*
X424500D01*
Y212000D01*
X364500D01*
Y245500D01*
X333500D01*
Y288000D01*
G01X335417Y255900D02*
Y258400D01*
X336417D01*
X336750Y258275D01*
X337000Y257983D01*
X337083Y257650D01*
X337000Y257317D01*
X336792Y257067D01*
X336417Y256942D01*
X335417D01*
G01X338517Y255900D02*
Y258400D01*
X339558D01*
X339892Y258275D01*
X340100Y258108D01*
X340183Y257775D01*
X340100Y257442D01*
X339850Y257233D01*
X339558Y257108D01*
X338517D01*
G01X339558D02*
X340183Y255900D01*
G01X341658Y256942D02*
X341950Y257233D01*
X342200Y257400D01*
X342533Y257483D01*
X342825Y257400D01*
X343033Y257233D01*
X343200Y256983D01*
X343242Y256692D01*
X343200Y256442D01*
X343033Y256192D01*
X342783Y255983D01*
X342492Y255900D01*
X342158Y255983D01*
X341867Y256233D01*
X341700Y256608D01*
X341658Y257025D01*
X341742Y257567D01*
X341867Y257858D01*
X342075Y258150D01*
X342367Y258358D01*
X342658Y258400D01*
X342950Y258317D01*
X343158Y258108D01*
G01X344758Y257983D02*
X345008Y258233D01*
X345300Y258358D01*
X345633Y258400D01*
X346050Y258317D01*
X346342Y258108D01*
X346425Y257858D01*
X346383Y257608D01*
X346217Y257400D01*
X345383Y256983D01*
X345008Y256692D01*
X344758Y256275D01*
X344675Y255900D01*
X346425D01*
G01X335717Y247600D02*
Y250100D01*
X336717D01*
X337050Y249975D01*
X337300Y249683D01*
X337383Y249350D01*
X337300Y249017D01*
X337092Y248767D01*
X336717Y248642D01*
X335717D01*
G01X338817Y247600D02*
Y250100D01*
X339858D01*
X340192Y249975D01*
X340400Y249808D01*
X340483Y249475D01*
X340400Y249142D01*
X340150Y248933D01*
X339858Y248808D01*
X338817D01*
G01X339858D02*
X340483Y247600D01*
G01X341958Y248642D02*
X342250Y248933D01*
X342500Y249100D01*
X342833Y249183D01*
X343125Y249100D01*
X343333Y248933D01*
X343500Y248683D01*
X343542Y248392D01*
X343500Y248142D01*
X343333Y247892D01*
X343083Y247683D01*
X342792Y247600D01*
X342458Y247683D01*
X342167Y247933D01*
X342000Y248308D01*
X341958Y248725D01*
X342042Y249267D01*
X342167Y249558D01*
X342375Y249850D01*
X342667Y250058D01*
X342958Y250100D01*
X343250Y250017D01*
X343458Y249808D01*
G01X344933Y248100D02*
X345183Y247808D01*
X345517Y247642D01*
X345892Y247600D01*
X346225Y247642D01*
X346558Y247850D01*
X346767Y248100D01*
X346808Y248350D01*
X346725Y248642D01*
X346433Y248850D01*
X346142Y248933D01*
X345767D01*
G01X346142D02*
X346392Y249058D01*
X346600Y249267D01*
X346683Y249517D01*
X346600Y249767D01*
X346392Y249975D01*
X346017Y250100D01*
X345642Y250058D01*
X345267Y249892D01*
G01X335417Y259900D02*
Y262400D01*
X336417D01*
X336750Y262275D01*
X337000Y261983D01*
X337083Y261650D01*
X337000Y261317D01*
X336792Y261067D01*
X336417Y260942D01*
X335417D01*
G01X338517Y259900D02*
Y262400D01*
X339558D01*
X339892Y262275D01*
X340100Y262108D01*
X340183Y261775D01*
X340100Y261442D01*
X339850Y261233D01*
X339558Y261108D01*
X338517D01*
G01X339558D02*
X340183Y259900D01*
G01X341533Y260275D02*
X341783Y260067D01*
X342075Y259942D01*
X342450Y259900D01*
X342825Y259983D01*
X343117Y260150D01*
X343325Y260442D01*
X343367Y260775D01*
X343283Y261108D01*
X343075Y261317D01*
X342783Y261483D01*
X342492Y261525D01*
X342200Y261483D01*
X341825Y261317D01*
X341950Y262400D01*
X343075D01*
G01X344758Y260942D02*
X345050Y261233D01*
X345300Y261400D01*
X345633Y261483D01*
X345925Y261400D01*
X346133Y261233D01*
X346300Y260983D01*
X346342Y260692D01*
X346300Y260442D01*
X346133Y260192D01*
X345883Y259983D01*
X345592Y259900D01*
X345258Y259983D01*
X344967Y260233D01*
X344800Y260608D01*
X344758Y261025D01*
X344842Y261567D01*
X344967Y261858D01*
X345175Y262150D01*
X345467Y262358D01*
X345758Y262400D01*
X346050Y262317D01*
X346258Y262108D01*
G01X335617Y251600D02*
Y254100D01*
X336617D01*
X336950Y253975D01*
X337200Y253683D01*
X337283Y253350D01*
X337200Y253017D01*
X336992Y252767D01*
X336617Y252642D01*
X335617D01*
G01X338717Y251600D02*
Y254100D01*
X339758D01*
X340092Y253975D01*
X340300Y253808D01*
X340383Y253475D01*
X340300Y253142D01*
X340050Y252933D01*
X339758Y252808D01*
X338717D01*
G01X339758D02*
X340383Y251600D01*
G01X341733Y251975D02*
X341983Y251767D01*
X342275Y251642D01*
X342650Y251600D01*
X343025Y251683D01*
X343317Y251850D01*
X343525Y252142D01*
X343567Y252475D01*
X343483Y252808D01*
X343275Y253017D01*
X342983Y253183D01*
X342692Y253225D01*
X342400Y253183D01*
X342025Y253017D01*
X342150Y254100D01*
X343275D01*
G01X345667Y251600D02*
X345750Y252142D01*
X345875Y252600D01*
X346042Y253017D01*
X346250Y253475D01*
X346583Y254100D01*
X344917D01*
G01X329500Y254017D02*
X327000D01*
Y255058D01*
X327125Y255392D01*
X327292Y255600D01*
X327625Y255683D01*
X327958Y255600D01*
X328167Y255350D01*
X328292Y255058D01*
Y254017D01*
G01Y255058D02*
X329500Y255683D01*
G01Y257950D02*
X327000D01*
X327500Y257450D01*
G01X329500D02*
Y258450D01*
G01X329000Y260133D02*
X329292Y260383D01*
X329458Y260717D01*
X329500Y261092D01*
X329458Y261425D01*
X329250Y261758D01*
X329000Y261967D01*
X328750Y262008D01*
X328458Y261925D01*
X328250Y261633D01*
X328167Y261342D01*
Y260967D01*
G01Y261342D02*
X328042Y261592D01*
X327833Y261800D01*
X327583Y261883D01*
X327333Y261800D01*
X327125Y261592D01*
X327000Y261217D01*
X327042Y260842D01*
X327208Y260467D01*
G01X329000Y263233D02*
X329292Y263483D01*
X329458Y263817D01*
X329500Y264192D01*
X329458Y264525D01*
X329250Y264858D01*
X329000Y265067D01*
X328750Y265108D01*
X328458Y265025D01*
X328250Y264733D01*
X328167Y264442D01*
Y264067D01*
G01Y264442D02*
X328042Y264692D01*
X327833Y264900D01*
X327583Y264983D01*
X327333Y264900D01*
X327125Y264692D01*
X327000Y264317D01*
X327042Y263942D01*
X327208Y263567D01*
G01X335117Y267900D02*
Y270400D01*
X336117D01*
X336450Y270275D01*
X336700Y269983D01*
X336783Y269650D01*
X336700Y269317D01*
X336492Y269067D01*
X336117Y268942D01*
X335117D01*
G01X338217Y267900D02*
Y270400D01*
X339258D01*
X339592Y270275D01*
X339800Y270108D01*
X339883Y269775D01*
X339800Y269442D01*
X339550Y269233D01*
X339258Y269108D01*
X338217D01*
G01X339258D02*
X339883Y267900D01*
G01X342650D02*
Y270400D01*
X341108Y268608D01*
X343192D01*
G01X344458Y269983D02*
X344708Y270233D01*
X345000Y270358D01*
X345333Y270400D01*
X345750Y270317D01*
X346042Y270108D01*
X346125Y269858D01*
X346083Y269608D01*
X345917Y269400D01*
X345083Y268983D01*
X344708Y268692D01*
X344458Y268275D01*
X344375Y267900D01*
X346125D01*
G01X335117Y271900D02*
Y274400D01*
X336117D01*
X336450Y274275D01*
X336700Y273983D01*
X336783Y273650D01*
X336700Y273317D01*
X336492Y273067D01*
X336117Y272942D01*
X335117D01*
G01X338217Y271900D02*
Y274400D01*
X339258D01*
X339592Y274275D01*
X339800Y274108D01*
X339883Y273775D01*
X339800Y273442D01*
X339550Y273233D01*
X339258Y273108D01*
X338217D01*
G01X339258D02*
X339883Y271900D01*
G01X342650D02*
Y274400D01*
X341108Y272608D01*
X343192D01*
G01X345250Y274400D02*
X344917Y274317D01*
X344667Y274108D01*
X344500Y273858D01*
X344375Y273525D01*
X344333Y273150D01*
X344375Y272775D01*
X344500Y272442D01*
X344667Y272192D01*
X344917Y271983D01*
X345250Y271900D01*
X345583Y271983D01*
X345833Y272192D01*
X346000Y272442D01*
X346125Y272775D01*
X346167Y273150D01*
X346125Y273525D01*
X346000Y273858D01*
X345833Y274108D01*
X345583Y274317D01*
X345250Y274400D01*
G01X335267Y264100D02*
Y266600D01*
X336308D01*
X336642Y266475D01*
X336850Y266308D01*
X336933Y265975D01*
X336850Y265642D01*
X336600Y265433D01*
X336308Y265308D01*
X335267D01*
G01X336308D02*
X336933Y264100D01*
G01X338408Y266183D02*
X338658Y266433D01*
X338950Y266558D01*
X339283Y266600D01*
X339700Y266517D01*
X339992Y266308D01*
X340075Y266058D01*
X340033Y265808D01*
X339867Y265600D01*
X339033Y265183D01*
X338658Y264892D01*
X338408Y264475D01*
X338325Y264100D01*
X340075D01*
G01X342300Y266600D02*
X341967Y266517D01*
X341717Y266308D01*
X341550Y266058D01*
X341425Y265725D01*
X341383Y265350D01*
X341425Y264975D01*
X341550Y264642D01*
X341717Y264392D01*
X341967Y264183D01*
X342300Y264100D01*
X342633Y264183D01*
X342883Y264392D01*
X343050Y264642D01*
X343175Y264975D01*
X343217Y265350D01*
X343175Y265725D01*
X343050Y266058D01*
X342883Y266308D01*
X342633Y266517D01*
X342300Y266600D01*
G01X338000Y276517D02*
X335500D01*
Y277517D01*
X335625Y277850D01*
X335917Y278100D01*
X336250Y278183D01*
X336583Y278100D01*
X336833Y277892D01*
X336958Y277517D01*
Y276517D01*
G01X338000Y279617D02*
X335500D01*
Y280658D01*
X335625Y280992D01*
X335792Y281200D01*
X336125Y281283D01*
X336458Y281200D01*
X336667Y280950D01*
X336792Y280658D01*
Y279617D01*
G01Y280658D02*
X338000Y281283D01*
G01X337500Y282633D02*
X337792Y282883D01*
X337958Y283217D01*
X338000Y283592D01*
X337958Y283925D01*
X337750Y284258D01*
X337500Y284467D01*
X337250Y284508D01*
X336958Y284425D01*
X336750Y284133D01*
X336667Y283842D01*
Y283467D01*
G01Y283842D02*
X336542Y284092D01*
X336333Y284300D01*
X336083Y284383D01*
X335833Y284300D01*
X335625Y284092D01*
X335500Y283717D01*
X335542Y283342D01*
X335708Y282967D01*
G01X338000Y286567D02*
X337458Y286650D01*
X337000Y286775D01*
X336583Y286942D01*
X336125Y287150D01*
X335500Y287483D01*
Y285817D01*
G01X341700Y276617D02*
X339200D01*
Y277617D01*
X339325Y277950D01*
X339617Y278200D01*
X339950Y278283D01*
X340283Y278200D01*
X340533Y277992D01*
X340658Y277617D01*
Y276617D01*
G01X341700Y279717D02*
X339200D01*
Y280758D01*
X339325Y281092D01*
X339492Y281300D01*
X339825Y281383D01*
X340158Y281300D01*
X340367Y281050D01*
X340492Y280758D01*
Y279717D01*
G01Y280758D02*
X341700Y281383D01*
G01X341200Y282733D02*
X341492Y282983D01*
X341658Y283317D01*
X341700Y283692D01*
X341658Y284025D01*
X341450Y284358D01*
X341200Y284567D01*
X340950Y284608D01*
X340658Y284525D01*
X340450Y284233D01*
X340367Y283942D01*
Y283567D01*
G01Y283942D02*
X340242Y284192D01*
X340033Y284400D01*
X339783Y284483D01*
X339533Y284400D01*
X339325Y284192D01*
X339200Y283817D01*
X339242Y283442D01*
X339408Y283067D01*
G01X341700Y287250D02*
X339200D01*
X340992Y285708D01*
Y287792D01*
G01X356500Y42217D02*
X354000D01*
Y43258D01*
X354125Y43592D01*
X354292Y43800D01*
X354625Y43883D01*
X354958Y43800D01*
X355167Y43550D01*
X355292Y43258D01*
Y42217D01*
G01Y43258D02*
X356500Y43883D01*
G01Y46650D02*
X354000D01*
X355792Y45108D01*
Y47192D01*
G01X356500Y49750D02*
X354000D01*
X355792Y48208D01*
Y50292D01*
G01X356500Y52850D02*
X354000D01*
X355792Y51308D01*
Y53392D01*
G01X352900Y42317D02*
X350400D01*
Y43358D01*
X350525Y43692D01*
X350692Y43900D01*
X351025Y43983D01*
X351358Y43900D01*
X351567Y43650D01*
X351692Y43358D01*
Y42317D01*
G01Y43358D02*
X352900Y43983D01*
G01Y46750D02*
X350400D01*
X352192Y45208D01*
Y47292D01*
G01X352900Y49850D02*
X350400D01*
X352192Y48308D01*
Y50392D01*
G01X352525Y51533D02*
X352733Y51783D01*
X352858Y52075D01*
X352900Y52450D01*
X352817Y52825D01*
X352650Y53117D01*
X352358Y53325D01*
X352025Y53367D01*
X351692Y53283D01*
X351483Y53075D01*
X351317Y52783D01*
X351275Y52492D01*
X351317Y52200D01*
X351483Y51825D01*
X350400Y51950D01*
Y53075D01*
G01X354708Y70817D02*
X354583Y70567D01*
X354500Y70275D01*
Y69942D01*
X354625Y69567D01*
X354833Y69275D01*
X355083Y69067D01*
X355500Y68900D01*
X355875Y68858D01*
X356250Y68942D01*
X356500Y69067D01*
X356750Y69317D01*
X356917Y69608D01*
X357000Y69900D01*
Y70192D01*
X356917Y70483D01*
X356792Y70733D01*
X356625Y70942D01*
G01Y72083D02*
X356833Y72333D01*
X356958Y72625D01*
X357000Y73000D01*
X356917Y73375D01*
X356750Y73667D01*
X356458Y73875D01*
X356125Y73917D01*
X355792Y73833D01*
X355583Y73625D01*
X355417Y73333D01*
X355375Y73042D01*
X355417Y72750D01*
X355583Y72375D01*
X354500Y72500D01*
Y73625D01*
G01X357000Y76100D02*
X354500D01*
X355000Y75600D01*
G01X357000D02*
Y76600D01*
G01X350208Y69817D02*
X350083Y69567D01*
X350000Y69275D01*
Y68942D01*
X350125Y68567D01*
X350333Y68275D01*
X350583Y68067D01*
X351000Y67900D01*
X351375Y67858D01*
X351750Y67942D01*
X352000Y68067D01*
X352250Y68317D01*
X352417Y68608D01*
X352500Y68900D01*
Y69192D01*
X352417Y69483D01*
X352292Y69733D01*
X352125Y69942D01*
G01Y71083D02*
X352333Y71333D01*
X352458Y71625D01*
X352500Y72000D01*
X352417Y72375D01*
X352250Y72667D01*
X351958Y72875D01*
X351625Y72917D01*
X351292Y72833D01*
X351083Y72625D01*
X350917Y72333D01*
X350875Y72042D01*
X350917Y71750D01*
X351083Y71375D01*
X350000Y71500D01*
Y72625D01*
G01X352000Y74183D02*
X352292Y74433D01*
X352458Y74767D01*
X352500Y75142D01*
X352458Y75475D01*
X352250Y75808D01*
X352000Y76017D01*
X351750Y76058D01*
X351458Y75975D01*
X351250Y75683D01*
X351167Y75392D01*
Y75017D01*
G01Y75392D02*
X351042Y75642D01*
X350833Y75850D01*
X350583Y75933D01*
X350333Y75850D01*
X350125Y75642D01*
X350000Y75267D01*
X350042Y74892D01*
X350208Y74517D01*
G01X345500Y77417D02*
X343000D01*
Y78417D01*
X343125Y78750D01*
X343417Y79000D01*
X343750Y79083D01*
X344083Y79000D01*
X344333Y78792D01*
X344458Y78417D01*
Y77417D01*
G01X343208Y82267D02*
X343083Y82017D01*
X343000Y81725D01*
Y81392D01*
X343125Y81017D01*
X343333Y80725D01*
X343583Y80517D01*
X344000Y80350D01*
X344375Y80308D01*
X344750Y80392D01*
X345000Y80517D01*
X345250Y80767D01*
X345417Y81058D01*
X345500Y81350D01*
Y81642D01*
X345417Y81933D01*
X345292Y82183D01*
X345125Y82392D01*
G01X343417Y83658D02*
X343167Y83908D01*
X343042Y84200D01*
X343000Y84533D01*
X343083Y84950D01*
X343292Y85242D01*
X343542Y85325D01*
X343792Y85283D01*
X344000Y85117D01*
X344417Y84283D01*
X344708Y83908D01*
X345125Y83658D01*
X345500Y83575D01*
Y85325D01*
G01X345000Y86633D02*
X345292Y86883D01*
X345458Y87217D01*
X345500Y87592D01*
X345458Y87925D01*
X345250Y88258D01*
X345000Y88467D01*
X344750Y88508D01*
X344458Y88425D01*
X344250Y88133D01*
X344167Y87842D01*
Y87467D01*
G01Y87842D02*
X344042Y88092D01*
X343833Y88300D01*
X343583Y88383D01*
X343333Y88300D01*
X343125Y88092D01*
X343000Y87717D01*
X343042Y87342D01*
X343208Y86967D01*
G01X349500Y77417D02*
X347000D01*
Y78417D01*
X347125Y78750D01*
X347417Y79000D01*
X347750Y79083D01*
X348083Y79000D01*
X348333Y78792D01*
X348458Y78417D01*
Y77417D01*
G01X347208Y82267D02*
X347083Y82017D01*
X347000Y81725D01*
Y81392D01*
X347125Y81017D01*
X347333Y80725D01*
X347583Y80517D01*
X348000Y80350D01*
X348375Y80308D01*
X348750Y80392D01*
X349000Y80517D01*
X349250Y80767D01*
X349417Y81058D01*
X349500Y81350D01*
Y81642D01*
X349417Y81933D01*
X349292Y82183D01*
X349125Y82392D01*
G01X347417Y83658D02*
X347167Y83908D01*
X347042Y84200D01*
X347000Y84533D01*
X347083Y84950D01*
X347292Y85242D01*
X347542Y85325D01*
X347792Y85283D01*
X348000Y85117D01*
X348417Y84283D01*
X348708Y83908D01*
X349125Y83658D01*
X349500Y83575D01*
Y85325D01*
G01X347000Y87550D02*
X347083Y87217D01*
X347292Y86967D01*
X347542Y86800D01*
X347875Y86675D01*
X348250Y86633D01*
X348625Y86675D01*
X348958Y86800D01*
X349208Y86967D01*
X349417Y87217D01*
X349500Y87550D01*
X349417Y87883D01*
X349208Y88133D01*
X348958Y88300D01*
X348625Y88425D01*
X348250Y88467D01*
X347875Y88425D01*
X347542Y88300D01*
X347292Y88133D01*
X347083Y87883D01*
X347000Y87550D01*
G01X350867Y257600D02*
Y264600D01*
X353533D01*
X354600Y264250D01*
X355400Y263783D01*
X356067Y263083D01*
X356600Y262267D01*
X356733Y261100D01*
X356600Y259933D01*
X356067Y259117D01*
X355400Y258416D01*
X354600Y257950D01*
X353533Y257600D01*
X350867D01*
G01X355017Y272000D02*
Y274500D01*
X356017D01*
X356350Y274375D01*
X356600Y274083D01*
X356683Y273750D01*
X356600Y273417D01*
X356392Y273167D01*
X356017Y273042D01*
X355017D01*
G01X359867Y274292D02*
X359617Y274417D01*
X359325Y274500D01*
X358992D01*
X358617Y274375D01*
X358325Y274167D01*
X358117Y273917D01*
X357950Y273500D01*
X357908Y273125D01*
X357992Y272750D01*
X358117Y272500D01*
X358367Y272250D01*
X358658Y272083D01*
X358950Y272000D01*
X359242D01*
X359533Y272083D01*
X359783Y272208D01*
X359992Y272375D01*
G01X362050Y272000D02*
Y274500D01*
X361550Y274000D01*
G01Y272000D02*
X362550D01*
G01X364233Y272375D02*
X364483Y272167D01*
X364775Y272042D01*
X365150Y272000D01*
X365525Y272083D01*
X365817Y272250D01*
X366025Y272542D01*
X366067Y272875D01*
X365983Y273208D01*
X365775Y273417D01*
X365483Y273583D01*
X365192Y273625D01*
X364900Y273583D01*
X364525Y273417D01*
X364650Y274500D01*
X365775D01*
G01X345500Y276717D02*
X343000D01*
Y277717D01*
X343125Y278050D01*
X343417Y278300D01*
X343750Y278383D01*
X344083Y278300D01*
X344333Y278092D01*
X344458Y277717D01*
Y276717D01*
G01X343208Y281567D02*
X343083Y281317D01*
X343000Y281025D01*
Y280692D01*
X343125Y280317D01*
X343333Y280025D01*
X343583Y279817D01*
X344000Y279650D01*
X344375Y279608D01*
X344750Y279692D01*
X345000Y279817D01*
X345250Y280067D01*
X345417Y280358D01*
X345500Y280650D01*
Y280942D01*
X345417Y281233D01*
X345292Y281483D01*
X345125Y281692D01*
G01X343417Y282958D02*
X343167Y283208D01*
X343042Y283500D01*
X343000Y283833D01*
X343083Y284250D01*
X343292Y284542D01*
X343542Y284625D01*
X343792Y284583D01*
X344000Y284417D01*
X344417Y283583D01*
X344708Y283208D01*
X345125Y282958D01*
X345500Y282875D01*
Y284625D01*
G01Y287350D02*
X343000D01*
X344792Y285808D01*
Y287892D01*
G01X347417Y280900D02*
Y283400D01*
X348417D01*
X348750Y283275D01*
X349000Y282983D01*
X349083Y282650D01*
X349000Y282317D01*
X348792Y282067D01*
X348417Y281942D01*
X347417D01*
G01X352267Y283192D02*
X352017Y283317D01*
X351725Y283400D01*
X351392D01*
X351017Y283275D01*
X350725Y283067D01*
X350517Y282817D01*
X350350Y282400D01*
X350308Y282025D01*
X350392Y281650D01*
X350517Y281400D01*
X350767Y281150D01*
X351058Y280983D01*
X351350Y280900D01*
X351642D01*
X351933Y280983D01*
X352183Y281108D01*
X352392Y281275D01*
G01X353658Y282983D02*
X353908Y283233D01*
X354200Y283358D01*
X354533Y283400D01*
X354950Y283317D01*
X355242Y283108D01*
X355325Y282858D01*
X355283Y282608D01*
X355117Y282400D01*
X354283Y281983D01*
X353908Y281692D01*
X353658Y281275D01*
X353575Y280900D01*
X355325D01*
G01X356758Y282983D02*
X357008Y283233D01*
X357300Y283358D01*
X357633Y283400D01*
X358050Y283317D01*
X358342Y283108D01*
X358425Y282858D01*
X358383Y282608D01*
X358217Y282400D01*
X357383Y281983D01*
X357008Y281692D01*
X356758Y281275D01*
X356675Y280900D01*
X358425D01*
G01X347717Y276900D02*
Y279400D01*
X348717D01*
X349050Y279275D01*
X349300Y278983D01*
X349383Y278650D01*
X349300Y278317D01*
X349092Y278067D01*
X348717Y277942D01*
X347717D01*
G01X350817Y276900D02*
Y279400D01*
X351858D01*
X352192Y279275D01*
X352400Y279108D01*
X352483Y278775D01*
X352400Y278442D01*
X352150Y278233D01*
X351858Y278108D01*
X350817D01*
G01X351858D02*
X352483Y276900D01*
G01X353833Y277400D02*
X354083Y277108D01*
X354417Y276942D01*
X354792Y276900D01*
X355125Y276942D01*
X355458Y277150D01*
X355667Y277400D01*
X355708Y277650D01*
X355625Y277942D01*
X355333Y278150D01*
X355042Y278233D01*
X354667D01*
G01X355042D02*
X355292Y278358D01*
X355500Y278567D01*
X355583Y278817D01*
X355500Y279067D01*
X355292Y279275D01*
X354917Y279400D01*
X354542Y279358D01*
X354167Y279192D01*
G01X357850Y279400D02*
X357517Y279317D01*
X357267Y279108D01*
X357100Y278858D01*
X356975Y278525D01*
X356933Y278150D01*
X356975Y277775D01*
X357100Y277442D01*
X357267Y277192D01*
X357517Y276983D01*
X357850Y276900D01*
X358183Y276983D01*
X358433Y277192D01*
X358600Y277442D01*
X358725Y277775D01*
X358767Y278150D01*
X358725Y278525D01*
X358600Y278858D01*
X358433Y279108D01*
X358183Y279317D01*
X357850Y279400D01*
G01X370208Y50267D02*
X370083Y50017D01*
X370000Y49725D01*
Y49392D01*
X370125Y49017D01*
X370333Y48725D01*
X370583Y48517D01*
X371000Y48350D01*
X371375Y48308D01*
X371750Y48392D01*
X372000Y48517D01*
X372250Y48767D01*
X372417Y49058D01*
X372500Y49350D01*
Y49642D01*
X372417Y49933D01*
X372292Y50183D01*
X372125Y50392D01*
G01X372000Y51533D02*
X372292Y51783D01*
X372458Y52117D01*
X372500Y52492D01*
X372458Y52825D01*
X372250Y53158D01*
X372000Y53367D01*
X371750Y53408D01*
X371458Y53325D01*
X371250Y53033D01*
X371167Y52742D01*
Y52367D01*
G01Y52742D02*
X371042Y52992D01*
X370833Y53200D01*
X370583Y53283D01*
X370333Y53200D01*
X370125Y52992D01*
X370000Y52617D01*
X370042Y52242D01*
X370208Y51867D01*
G01X372500Y55550D02*
X370000D01*
X370500Y55050D01*
G01X372500D02*
Y56050D01*
G01X372208Y57942D02*
X372417Y58233D01*
X372500Y58567D01*
X372417Y58900D01*
X372167Y59192D01*
X371792Y59400D01*
X371417Y59483D01*
X370958D01*
X370583Y59400D01*
X370250Y59192D01*
X370083Y58942D01*
X370000Y58650D01*
X370083Y58317D01*
X370250Y58067D01*
X370500Y57900D01*
X370833Y57817D01*
X371125Y57900D01*
X371417Y58108D01*
X371583Y58358D01*
X371625Y58650D01*
X371542Y58983D01*
X371333Y59233D01*
X370958Y59483D01*
G01X367817Y66292D02*
X367567Y66417D01*
X367275Y66500D01*
X366942D01*
X366567Y66375D01*
X366275Y66167D01*
X366067Y65917D01*
X365900Y65500D01*
X365858Y65125D01*
X365942Y64750D01*
X366067Y64500D01*
X366317Y64250D01*
X366608Y64083D01*
X366900Y64000D01*
X367192D01*
X367483Y64083D01*
X367733Y64208D01*
X367942Y64375D01*
G01X369208Y66083D02*
X369458Y66333D01*
X369750Y66458D01*
X370083Y66500D01*
X370500Y66417D01*
X370792Y66208D01*
X370875Y65958D01*
X370833Y65708D01*
X370667Y65500D01*
X369833Y65083D01*
X369458Y64792D01*
X369208Y64375D01*
X369125Y64000D01*
X370875D01*
G01X372183Y64375D02*
X372433Y64167D01*
X372725Y64042D01*
X373100Y64000D01*
X373475Y64083D01*
X373767Y64250D01*
X373975Y64542D01*
X374017Y64875D01*
X373933Y65208D01*
X373725Y65417D01*
X373433Y65583D01*
X373142Y65625D01*
X372850Y65583D01*
X372475Y65417D01*
X372600Y66500D01*
X373725D01*
G01X360708Y70317D02*
X360583Y70067D01*
X360500Y69775D01*
Y69442D01*
X360625Y69067D01*
X360833Y68775D01*
X361083Y68567D01*
X361500Y68400D01*
X361875Y68358D01*
X362250Y68442D01*
X362500Y68567D01*
X362750Y68817D01*
X362917Y69108D01*
X363000Y69400D01*
Y69692D01*
X362917Y69983D01*
X362792Y70233D01*
X362625Y70442D01*
G01Y71583D02*
X362833Y71833D01*
X362958Y72125D01*
X363000Y72500D01*
X362917Y72875D01*
X362750Y73167D01*
X362458Y73375D01*
X362125Y73417D01*
X361792Y73333D01*
X361583Y73125D01*
X361417Y72833D01*
X361375Y72542D01*
X361417Y72250D01*
X361583Y71875D01*
X360500Y72000D01*
Y73125D01*
G01X360917Y74808D02*
X360667Y75058D01*
X360542Y75350D01*
X360500Y75683D01*
X360583Y76100D01*
X360792Y76392D01*
X361042Y76475D01*
X361292Y76433D01*
X361500Y76267D01*
X361917Y75433D01*
X362208Y75058D01*
X362625Y74808D01*
X363000Y74725D01*
Y76475D01*
G01X367817Y77792D02*
X367567Y77917D01*
X367275Y78000D01*
X366942D01*
X366567Y77875D01*
X366275Y77667D01*
X366067Y77417D01*
X365900Y77000D01*
X365858Y76625D01*
X365942Y76250D01*
X366067Y76000D01*
X366317Y75750D01*
X366608Y75583D01*
X366900Y75500D01*
X367192D01*
X367483Y75583D01*
X367733Y75708D01*
X367942Y75875D01*
G01X369083Y76000D02*
X369333Y75708D01*
X369667Y75542D01*
X370042Y75500D01*
X370375Y75542D01*
X370708Y75750D01*
X370917Y76000D01*
X370958Y76250D01*
X370875Y76542D01*
X370583Y76750D01*
X370292Y76833D01*
X369917D01*
G01X370292D02*
X370542Y76958D01*
X370750Y77167D01*
X370833Y77417D01*
X370750Y77667D01*
X370542Y77875D01*
X370167Y78000D01*
X369792Y77958D01*
X369417Y77792D01*
G01X372183Y75875D02*
X372433Y75667D01*
X372725Y75542D01*
X373100Y75500D01*
X373475Y75583D01*
X373767Y75750D01*
X373975Y76042D01*
X374017Y76375D01*
X373933Y76708D01*
X373725Y76917D01*
X373433Y77083D01*
X373142Y77125D01*
X372850Y77083D01*
X372475Y76917D01*
X372600Y78000D01*
X373725D01*
G01X367817Y70292D02*
X367567Y70417D01*
X367275Y70500D01*
X366942D01*
X366567Y70375D01*
X366275Y70167D01*
X366067Y69917D01*
X365900Y69500D01*
X365858Y69125D01*
X365942Y68750D01*
X366067Y68500D01*
X366317Y68250D01*
X366608Y68083D01*
X366900Y68000D01*
X367192D01*
X367483Y68083D01*
X367733Y68208D01*
X367942Y68375D01*
G01X369208Y70083D02*
X369458Y70333D01*
X369750Y70458D01*
X370083Y70500D01*
X370500Y70417D01*
X370792Y70208D01*
X370875Y69958D01*
X370833Y69708D01*
X370667Y69500D01*
X369833Y69083D01*
X369458Y68792D01*
X369208Y68375D01*
X369125Y68000D01*
X370875D01*
G01X373600D02*
Y70500D01*
X372058Y68708D01*
X374142D01*
G01X368000Y81017D02*
X365500D01*
Y82017D01*
X365625Y82350D01*
X365917Y82600D01*
X366250Y82683D01*
X366583Y82600D01*
X366833Y82392D01*
X366958Y82017D01*
Y81017D01*
G01X365708Y85867D02*
X365583Y85617D01*
X365500Y85325D01*
Y84992D01*
X365625Y84617D01*
X365833Y84325D01*
X366083Y84117D01*
X366500Y83950D01*
X366875Y83908D01*
X367250Y83992D01*
X367500Y84117D01*
X367750Y84367D01*
X367917Y84658D01*
X368000Y84950D01*
Y85242D01*
X367917Y85533D01*
X367792Y85783D01*
X367625Y85992D01*
G01X367500Y87133D02*
X367792Y87383D01*
X367958Y87717D01*
X368000Y88092D01*
X367958Y88425D01*
X367750Y88758D01*
X367500Y88967D01*
X367250Y89008D01*
X366958Y88925D01*
X366750Y88633D01*
X366667Y88342D01*
Y87967D01*
G01Y88342D02*
X366542Y88592D01*
X366333Y88800D01*
X366083Y88883D01*
X365833Y88800D01*
X365625Y88592D01*
X365500Y88217D01*
X365542Y87842D01*
X365708Y87467D01*
G01X365917Y90358D02*
X365667Y90608D01*
X365542Y90900D01*
X365500Y91233D01*
X365583Y91650D01*
X365792Y91942D01*
X366042Y92025D01*
X366292Y91983D01*
X366500Y91817D01*
X366917Y90983D01*
X367208Y90608D01*
X367625Y90358D01*
X368000Y90275D01*
Y92025D01*
G01X364000Y80017D02*
X361500D01*
Y81017D01*
X361625Y81350D01*
X361917Y81600D01*
X362250Y81683D01*
X362583Y81600D01*
X362833Y81392D01*
X362958Y81017D01*
Y80017D01*
G01X361708Y84867D02*
X361583Y84617D01*
X361500Y84325D01*
Y83992D01*
X361625Y83617D01*
X361833Y83325D01*
X362083Y83117D01*
X362500Y82950D01*
X362875Y82908D01*
X363250Y82992D01*
X363500Y83117D01*
X363750Y83367D01*
X363917Y83658D01*
X364000Y83950D01*
Y84242D01*
X363917Y84533D01*
X363792Y84783D01*
X363625Y84992D01*
G01X363500Y86133D02*
X363792Y86383D01*
X363958Y86717D01*
X364000Y87092D01*
X363958Y87425D01*
X363750Y87758D01*
X363500Y87967D01*
X363250Y88008D01*
X362958Y87925D01*
X362750Y87633D01*
X362667Y87342D01*
Y86967D01*
G01Y87342D02*
X362542Y87592D01*
X362333Y87800D01*
X362083Y87883D01*
X361833Y87800D01*
X361625Y87592D01*
X361500Y87217D01*
X361542Y86842D01*
X361708Y86467D01*
G01X363500Y89233D02*
X363792Y89483D01*
X363958Y89817D01*
X364000Y90192D01*
X363958Y90525D01*
X363750Y90858D01*
X363500Y91067D01*
X363250Y91108D01*
X362958Y91025D01*
X362750Y90733D01*
X362667Y90442D01*
Y90067D01*
G01Y90442D02*
X362542Y90692D01*
X362333Y90900D01*
X362083Y90983D01*
X361833Y90900D01*
X361625Y90692D01*
X361500Y90317D01*
X361542Y89942D01*
X361708Y89567D01*
G01X372000Y81017D02*
X369500D01*
Y82017D01*
X369625Y82350D01*
X369917Y82600D01*
X370250Y82683D01*
X370583Y82600D01*
X370833Y82392D01*
X370958Y82017D01*
Y81017D01*
G01X372000Y84117D02*
X369500D01*
Y85158D01*
X369625Y85492D01*
X369792Y85700D01*
X370125Y85783D01*
X370458Y85700D01*
X370667Y85450D01*
X370792Y85158D01*
Y84117D01*
G01Y85158D02*
X372000Y85783D01*
G01X371500Y87133D02*
X371792Y87383D01*
X371958Y87717D01*
X372000Y88092D01*
X371958Y88425D01*
X371750Y88758D01*
X371500Y88967D01*
X371250Y89008D01*
X370958Y88925D01*
X370750Y88633D01*
X370667Y88342D01*
Y87967D01*
G01Y88342D02*
X370542Y88592D01*
X370333Y88800D01*
X370083Y88883D01*
X369833Y88800D01*
X369625Y88592D01*
X369500Y88217D01*
X369542Y87842D01*
X369708Y87467D01*
G01X369917Y90358D02*
X369667Y90608D01*
X369542Y90900D01*
X369500Y91233D01*
X369583Y91650D01*
X369792Y91942D01*
X370042Y92025D01*
X370292Y91983D01*
X370500Y91817D01*
X370917Y90983D01*
X371208Y90608D01*
X371625Y90358D01*
X372000Y90275D01*
Y92025D01*
G01X360000Y79517D02*
X357500D01*
Y80517D01*
X357625Y80850D01*
X357917Y81100D01*
X358250Y81183D01*
X358583Y81100D01*
X358833Y80892D01*
X358958Y80517D01*
Y79517D01*
G01X357708Y84367D02*
X357583Y84117D01*
X357500Y83825D01*
Y83492D01*
X357625Y83117D01*
X357833Y82825D01*
X358083Y82617D01*
X358500Y82450D01*
X358875Y82408D01*
X359250Y82492D01*
X359500Y82617D01*
X359750Y82867D01*
X359917Y83158D01*
X360000Y83450D01*
Y83742D01*
X359917Y84033D01*
X359792Y84283D01*
X359625Y84492D01*
G01X360000Y86550D02*
X357500D01*
X358000Y86050D01*
G01X360000D02*
Y87050D01*
G01Y89650D02*
X359958Y89942D01*
X359833Y90275D01*
X359625Y90483D01*
X359333Y90567D01*
X359042Y90483D01*
X358792Y90233D01*
X358667Y89858D01*
Y89442D01*
X358583Y89192D01*
X358375Y88983D01*
X358083Y88900D01*
X357792Y89025D01*
X357583Y89317D01*
X357500Y89650D01*
X357583Y89983D01*
X357792Y90275D01*
X358083Y90400D01*
X358375Y90317D01*
X358583Y90108D01*
X358667Y89858D01*
Y89442D01*
X358792Y89067D01*
X359042Y88817D01*
X359333Y88733D01*
X359625Y88817D01*
X359833Y89025D01*
X359958Y89358D01*
X360000Y89650D01*
G01X366767Y225800D02*
Y228300D01*
X367767D01*
X368100Y228175D01*
X368350Y227883D01*
X368433Y227550D01*
X368350Y227217D01*
X368142Y226967D01*
X367767Y226842D01*
X366767D01*
G01X371617Y228092D02*
X371367Y228217D01*
X371075Y228300D01*
X370742D01*
X370367Y228175D01*
X370075Y227967D01*
X369867Y227717D01*
X369700Y227300D01*
X369658Y226925D01*
X369742Y226550D01*
X369867Y226300D01*
X370117Y226050D01*
X370408Y225883D01*
X370700Y225800D01*
X370992D01*
X371283Y225883D01*
X371533Y226008D01*
X371742Y226175D01*
G01X373800Y225800D02*
Y228300D01*
X373300Y227800D01*
G01Y225800D02*
X374300D01*
G01X377400D02*
Y228300D01*
X375858Y226508D01*
X377942D01*
G01X379917Y225800D02*
X380000Y226342D01*
X380125Y226800D01*
X380292Y227217D01*
X380500Y227675D01*
X380833Y228300D01*
X379167D01*
G01X366467Y221500D02*
Y224000D01*
X367467D01*
X367800Y223875D01*
X368050Y223583D01*
X368133Y223250D01*
X368050Y222917D01*
X367842Y222667D01*
X367467Y222542D01*
X366467D01*
G01X371317Y223792D02*
X371067Y223917D01*
X370775Y224000D01*
X370442D01*
X370067Y223875D01*
X369775Y223667D01*
X369567Y223417D01*
X369400Y223000D01*
X369358Y222625D01*
X369442Y222250D01*
X369567Y222000D01*
X369817Y221750D01*
X370108Y221583D01*
X370400Y221500D01*
X370692D01*
X370983Y221583D01*
X371233Y221708D01*
X371442Y221875D01*
G01X373500Y221500D02*
Y224000D01*
X373000Y223500D01*
G01Y221500D02*
X374000D01*
G01X377100D02*
Y224000D01*
X375558Y222208D01*
X377642D01*
G01X379700Y221500D02*
X379992Y221542D01*
X380325Y221667D01*
X380533Y221875D01*
X380617Y222167D01*
X380533Y222458D01*
X380283Y222708D01*
X379908Y222833D01*
X379492D01*
X379242Y222917D01*
X379033Y223125D01*
X378950Y223417D01*
X379075Y223708D01*
X379367Y223917D01*
X379700Y224000D01*
X380033Y223917D01*
X380325Y223708D01*
X380450Y223417D01*
X380367Y223125D01*
X380158Y222917D01*
X379908Y222833D01*
X379492D01*
X379117Y222708D01*
X378867Y222458D01*
X378783Y222167D01*
X378867Y221875D01*
X379075Y221667D01*
X379408Y221542D01*
X379700Y221500D01*
G01X372500Y231017D02*
X370000D01*
Y232017D01*
X370125Y232350D01*
X370417Y232600D01*
X370750Y232683D01*
X371083Y232600D01*
X371333Y232392D01*
X371458Y232017D01*
Y231017D01*
G01X370208Y235867D02*
X370083Y235617D01*
X370000Y235325D01*
Y234992D01*
X370125Y234617D01*
X370333Y234325D01*
X370583Y234117D01*
X371000Y233950D01*
X371375Y233908D01*
X371750Y233992D01*
X372000Y234117D01*
X372250Y234367D01*
X372417Y234658D01*
X372500Y234950D01*
Y235242D01*
X372417Y235533D01*
X372292Y235783D01*
X372125Y235992D01*
G01Y237133D02*
X372333Y237383D01*
X372458Y237675D01*
X372500Y238050D01*
X372417Y238425D01*
X372250Y238717D01*
X371958Y238925D01*
X371625Y238967D01*
X371292Y238883D01*
X371083Y238675D01*
X370917Y238383D01*
X370875Y238092D01*
X370917Y237800D01*
X371083Y237425D01*
X370000Y237550D01*
Y238675D01*
G01X372500Y241067D02*
X371958Y241150D01*
X371500Y241275D01*
X371083Y241442D01*
X370625Y241650D01*
X370000Y241983D01*
Y240317D01*
G01X368817Y244300D02*
Y246800D01*
X369817D01*
X370150Y246675D01*
X370400Y246383D01*
X370483Y246050D01*
X370400Y245717D01*
X370192Y245467D01*
X369817Y245342D01*
X368817D01*
G01X371917Y244300D02*
Y246800D01*
X372958D01*
X373292Y246675D01*
X373500Y246508D01*
X373583Y246175D01*
X373500Y245842D01*
X373250Y245633D01*
X372958Y245508D01*
X371917D01*
G01X372958D02*
X373583Y244300D01*
G01X376350D02*
Y246800D01*
X374808Y245008D01*
X376892D01*
G01X378950Y244300D02*
X379242Y244342D01*
X379575Y244467D01*
X379783Y244675D01*
X379867Y244967D01*
X379783Y245258D01*
X379533Y245508D01*
X379158Y245633D01*
X378742D01*
X378492Y245717D01*
X378283Y245925D01*
X378200Y246217D01*
X378325Y246508D01*
X378617Y246717D01*
X378950Y246800D01*
X379283Y246717D01*
X379575Y246508D01*
X379700Y246217D01*
X379617Y245925D01*
X379408Y245717D01*
X379158Y245633D01*
X378742D01*
X378367Y245508D01*
X378117Y245258D01*
X378033Y244967D01*
X378117Y244675D01*
X378325Y244467D01*
X378658Y244342D01*
X378950Y244300D01*
G01X362600Y255967D02*
X360100D01*
Y256967D01*
X360225Y257300D01*
X360517Y257550D01*
X360850Y257633D01*
X361183Y257550D01*
X361433Y257342D01*
X361558Y256967D01*
Y255967D01*
G01X360100Y258983D02*
X361892D01*
X362267Y259150D01*
X362517Y259483D01*
X362600Y259900D01*
X362517Y260317D01*
X362267Y260650D01*
X361892Y260817D01*
X360100D01*
G01X362100Y262083D02*
X362392Y262333D01*
X362558Y262667D01*
X362600Y263042D01*
X362558Y263375D01*
X362350Y263708D01*
X362100Y263917D01*
X361850Y263958D01*
X361558Y263875D01*
X361350Y263583D01*
X361267Y263292D01*
Y262917D01*
G01Y263292D02*
X361142Y263542D01*
X360933Y263750D01*
X360683Y263833D01*
X360433Y263750D01*
X360225Y263542D01*
X360100Y263167D01*
X360142Y262792D01*
X360308Y262417D01*
G01X368500Y270500D02*
Y268000D01*
G01X367542Y270500D02*
X369458D01*
G01X370767Y268000D02*
Y270500D01*
X371767D01*
X372100Y270375D01*
X372350Y270083D01*
X372433Y269750D01*
X372350Y269417D01*
X372142Y269167D01*
X371767Y269042D01*
X370767D01*
G01X374700Y268000D02*
Y270500D01*
X374200Y270000D01*
G01Y268000D02*
X375200D01*
G01X371700Y273117D02*
X369200D01*
Y274117D01*
X369325Y274450D01*
X369617Y274700D01*
X369950Y274783D01*
X370283Y274700D01*
X370533Y274492D01*
X370658Y274117D01*
Y273117D01*
G01X371700Y276217D02*
X369200D01*
Y277258D01*
X369325Y277592D01*
X369492Y277800D01*
X369825Y277883D01*
X370158Y277800D01*
X370367Y277550D01*
X370492Y277258D01*
Y276217D01*
G01Y277258D02*
X371700Y277883D01*
G01X369617Y279358D02*
X369367Y279608D01*
X369242Y279900D01*
X369200Y280233D01*
X369283Y280650D01*
X369492Y280942D01*
X369742Y281025D01*
X369992Y280983D01*
X370200Y280817D01*
X370617Y279983D01*
X370908Y279608D01*
X371325Y279358D01*
X371700Y279275D01*
Y281025D01*
G01Y283250D02*
X371658Y283542D01*
X371533Y283875D01*
X371325Y284083D01*
X371033Y284167D01*
X370742Y284083D01*
X370492Y283833D01*
X370367Y283458D01*
Y283042D01*
X370283Y282792D01*
X370075Y282583D01*
X369783Y282500D01*
X369492Y282625D01*
X369283Y282917D01*
X369200Y283250D01*
X369283Y283583D01*
X369492Y283875D01*
X369783Y284000D01*
X370075Y283917D01*
X370283Y283708D01*
X370367Y283458D01*
Y283042D01*
X370492Y282667D01*
X370742Y282417D01*
X371033Y282333D01*
X371325Y282417D01*
X371533Y282625D01*
X371658Y282958D01*
X371700Y283250D01*
G01X368017Y286300D02*
Y288800D01*
X369017D01*
X369350Y288675D01*
X369600Y288383D01*
X369683Y288050D01*
X369600Y287717D01*
X369392Y287467D01*
X369017Y287342D01*
X368017D01*
G01X372867Y288592D02*
X372617Y288717D01*
X372325Y288800D01*
X371992D01*
X371617Y288675D01*
X371325Y288467D01*
X371117Y288217D01*
X370950Y287800D01*
X370908Y287425D01*
X370992Y287050D01*
X371117Y286800D01*
X371367Y286550D01*
X371658Y286383D01*
X371950Y286300D01*
X372242D01*
X372533Y286383D01*
X372783Y286508D01*
X372992Y286675D01*
G01X375050Y286300D02*
Y288800D01*
X374550Y288300D01*
G01Y286300D02*
X375550D01*
G01X378150Y288800D02*
X377817Y288717D01*
X377567Y288508D01*
X377400Y288258D01*
X377275Y287925D01*
X377233Y287550D01*
X377275Y287175D01*
X377400Y286842D01*
X377567Y286592D01*
X377817Y286383D01*
X378150Y286300D01*
X378483Y286383D01*
X378733Y286592D01*
X378900Y286842D01*
X379025Y287175D01*
X379067Y287550D01*
X379025Y287925D01*
X378900Y288258D01*
X378733Y288508D01*
X378483Y288717D01*
X378150Y288800D01*
G01X363400Y276517D02*
X360900D01*
Y277517D01*
X361025Y277850D01*
X361317Y278100D01*
X361650Y278183D01*
X361983Y278100D01*
X362233Y277892D01*
X362358Y277517D01*
Y276517D01*
G01X363400Y279617D02*
X360900D01*
Y280658D01*
X361025Y280992D01*
X361192Y281200D01*
X361525Y281283D01*
X361858Y281200D01*
X362067Y280950D01*
X362192Y280658D01*
Y279617D01*
G01Y280658D02*
X363400Y281283D01*
G01X361317Y282758D02*
X361067Y283008D01*
X360942Y283300D01*
X360900Y283633D01*
X360983Y284050D01*
X361192Y284342D01*
X361442Y284425D01*
X361692Y284383D01*
X361900Y284217D01*
X362317Y283383D01*
X362608Y283008D01*
X363025Y282758D01*
X363400Y282675D01*
Y284425D01*
G01X360900Y286650D02*
X360983Y286317D01*
X361192Y286067D01*
X361442Y285900D01*
X361775Y285775D01*
X362150Y285733D01*
X362525Y285775D01*
X362858Y285900D01*
X363108Y286067D01*
X363317Y286317D01*
X363400Y286650D01*
X363317Y286983D01*
X363108Y287233D01*
X362858Y287400D01*
X362525Y287525D01*
X362150Y287567D01*
X361775Y287525D01*
X361442Y287400D01*
X361192Y287233D01*
X360983Y286983D01*
X360900Y286650D01*
G01X378650Y43750D02*
X379483D01*
Y43000D01*
X379233Y42750D01*
X378942Y42583D01*
X378525Y42500D01*
X378108Y42583D01*
X377817Y42750D01*
X377567Y43000D01*
X377400Y43292D01*
X377317Y43625D01*
Y43917D01*
X377400Y44167D01*
X377567Y44458D01*
X377817Y44708D01*
X378067Y44875D01*
X378400Y45000D01*
X378692D01*
X379025Y44917D01*
X379275Y44750D01*
G01X380708Y42500D02*
Y45000D01*
X382292D01*
G01X381708Y43792D02*
X380708D01*
G01X384600Y42500D02*
Y45000D01*
X384100Y44500D01*
G01Y42500D02*
X385100D01*
G01X387700Y49217D02*
X385200D01*
Y50258D01*
X385325Y50592D01*
X385492Y50800D01*
X385825Y50883D01*
X386158Y50800D01*
X386367Y50550D01*
X386492Y50258D01*
Y49217D01*
G01Y50258D02*
X387700Y50883D01*
G01Y53150D02*
X385200D01*
X385700Y52650D01*
G01X387700D02*
Y53650D01*
G01X387408Y55542D02*
X387617Y55833D01*
X387700Y56167D01*
X387617Y56500D01*
X387367Y56792D01*
X386992Y57000D01*
X386617Y57083D01*
X386158D01*
X385783Y57000D01*
X385450Y56792D01*
X385283Y56542D01*
X385200Y56250D01*
X385283Y55917D01*
X385450Y55667D01*
X385700Y55500D01*
X386033Y55417D01*
X386325Y55500D01*
X386617Y55708D01*
X386783Y55958D01*
X386825Y56250D01*
X386742Y56583D01*
X386533Y56833D01*
X386158Y57083D01*
G01X387700Y59850D02*
X385200D01*
X386992Y58308D01*
Y60392D01*
G01X382500Y65467D02*
X380000D01*
Y66467D01*
X380125Y66800D01*
X380417Y67050D01*
X380750Y67133D01*
X381083Y67050D01*
X381333Y66842D01*
X381458Y66467D01*
Y65467D01*
G01X382500Y68567D02*
X380000D01*
Y69608D01*
X380125Y69942D01*
X380292Y70150D01*
X380625Y70233D01*
X380958Y70150D01*
X381167Y69900D01*
X381292Y69608D01*
Y68567D01*
G01Y69608D02*
X382500Y70233D01*
G01Y72500D02*
X380000D01*
X380500Y72000D01*
G01X382500D02*
Y73000D01*
G01X382125Y74683D02*
X382333Y74933D01*
X382458Y75225D01*
X382500Y75600D01*
X382417Y75975D01*
X382250Y76267D01*
X381958Y76475D01*
X381625Y76517D01*
X381292Y76433D01*
X381083Y76225D01*
X380917Y75933D01*
X380875Y75642D01*
X380917Y75350D01*
X381083Y74975D01*
X380000Y75100D01*
Y76225D01*
G01X382000Y77783D02*
X382292Y78033D01*
X382458Y78367D01*
X382500Y78742D01*
X382458Y79075D01*
X382250Y79408D01*
X382000Y79617D01*
X381750Y79658D01*
X381458Y79575D01*
X381250Y79283D01*
X381167Y78992D01*
Y78617D01*
G01Y78992D02*
X381042Y79242D01*
X380833Y79450D01*
X380583Y79533D01*
X380333Y79450D01*
X380125Y79242D01*
X380000Y78867D01*
X380042Y78492D01*
X380208Y78117D01*
G01X386500Y65467D02*
X384000D01*
Y66467D01*
X384125Y66800D01*
X384417Y67050D01*
X384750Y67133D01*
X385083Y67050D01*
X385333Y66842D01*
X385458Y66467D01*
Y65467D01*
G01X384208Y70317D02*
X384083Y70067D01*
X384000Y69775D01*
Y69442D01*
X384125Y69067D01*
X384333Y68775D01*
X384583Y68567D01*
X385000Y68400D01*
X385375Y68358D01*
X385750Y68442D01*
X386000Y68567D01*
X386250Y68817D01*
X386417Y69108D01*
X386500Y69400D01*
Y69692D01*
X386417Y69983D01*
X386292Y70233D01*
X386125Y70442D01*
G01X386500Y72500D02*
X384000D01*
X384500Y72000D01*
G01X386500D02*
Y73000D01*
G01Y75600D02*
X384000D01*
X384500Y75100D01*
G01X386500D02*
Y76100D01*
G01X384000Y78700D02*
X384083Y78367D01*
X384292Y78117D01*
X384542Y77950D01*
X384875Y77825D01*
X385250Y77783D01*
X385625Y77825D01*
X385958Y77950D01*
X386208Y78117D01*
X386417Y78367D01*
X386500Y78700D01*
X386417Y79033D01*
X386208Y79283D01*
X385958Y79450D01*
X385625Y79575D01*
X385250Y79617D01*
X384875Y79575D01*
X384542Y79450D01*
X384292Y79283D01*
X384083Y79033D01*
X384000Y78700D01*
G01X375500Y67567D02*
X378000D01*
Y69233D01*
G01Y71500D02*
X375500D01*
X376000Y71000D01*
G01X378000D02*
Y72000D01*
G01Y75100D02*
X375500D01*
X377292Y73558D01*
Y75642D01*
G01X393933Y91417D02*
X393133Y91767D01*
X392200Y92000D01*
X391133D01*
X389933Y91650D01*
X389000Y91067D01*
X388333Y90367D01*
X387800Y89200D01*
X387667Y88150D01*
X387933Y87100D01*
X388333Y86400D01*
X389133Y85700D01*
X390067Y85233D01*
X391000Y85000D01*
X391933D01*
X392867Y85233D01*
X393667Y85583D01*
X394333Y86050D01*
G01X380300Y85567D02*
X377800D01*
Y86608D01*
X377925Y86942D01*
X378092Y87150D01*
X378425Y87233D01*
X378758Y87150D01*
X378967Y86900D01*
X379092Y86608D01*
Y85567D01*
G01Y86608D02*
X380300Y87233D01*
G01Y89500D02*
X377800D01*
X378300Y89000D01*
G01X380300D02*
Y90000D01*
G01Y92600D02*
X377800D01*
X378300Y92100D01*
G01X380300D02*
Y93100D01*
G01X379800Y94783D02*
X380092Y95033D01*
X380258Y95367D01*
X380300Y95742D01*
X380258Y96075D01*
X380050Y96408D01*
X379800Y96617D01*
X379550Y96658D01*
X379258Y96575D01*
X379050Y96283D01*
X378967Y95992D01*
Y95617D01*
G01Y95992D02*
X378842Y96242D01*
X378633Y96450D01*
X378383Y96533D01*
X378133Y96450D01*
X377925Y96242D01*
X377800Y95867D01*
X377842Y95492D01*
X378008Y95117D01*
G01X376000Y81017D02*
X373500D01*
Y82017D01*
X373625Y82350D01*
X373917Y82600D01*
X374250Y82683D01*
X374583Y82600D01*
X374833Y82392D01*
X374958Y82017D01*
Y81017D01*
G01X373708Y85867D02*
X373583Y85617D01*
X373500Y85325D01*
Y84992D01*
X373625Y84617D01*
X373833Y84325D01*
X374083Y84117D01*
X374500Y83950D01*
X374875Y83908D01*
X375250Y83992D01*
X375500Y84117D01*
X375750Y84367D01*
X375917Y84658D01*
X376000Y84950D01*
Y85242D01*
X375917Y85533D01*
X375792Y85783D01*
X375625Y85992D01*
G01X375500Y87133D02*
X375792Y87383D01*
X375958Y87717D01*
X376000Y88092D01*
X375958Y88425D01*
X375750Y88758D01*
X375500Y88967D01*
X375250Y89008D01*
X374958Y88925D01*
X374750Y88633D01*
X374667Y88342D01*
Y87967D01*
G01Y88342D02*
X374542Y88592D01*
X374333Y88800D01*
X374083Y88883D01*
X373833Y88800D01*
X373625Y88592D01*
X373500Y88217D01*
X373542Y87842D01*
X373708Y87467D01*
G01X376000Y91650D02*
X373500D01*
X375292Y90108D01*
Y92192D01*
G01X382300Y88667D02*
X384800D01*
Y90333D01*
G01Y92600D02*
X382300D01*
X382800Y92100D01*
G01X384800D02*
Y93100D01*
G01X378367Y84000D02*
Y81500D01*
X380033D01*
G01X382300D02*
Y84000D01*
X381800Y83500D01*
G01Y81500D02*
X382800D01*
G01X384608Y83583D02*
X384858Y83833D01*
X385150Y83958D01*
X385483Y84000D01*
X385900Y83917D01*
X386192Y83708D01*
X386275Y83458D01*
X386233Y83208D01*
X386067Y83000D01*
X385233Y82583D01*
X384858Y82292D01*
X384608Y81875D01*
X384525Y81500D01*
X386275D01*
G01X389200Y220117D02*
X386700D01*
Y221117D01*
X386825Y221450D01*
X387117Y221700D01*
X387450Y221783D01*
X387783Y221700D01*
X388033Y221492D01*
X388158Y221117D01*
Y220117D01*
G01X389200Y223217D02*
X386700D01*
Y224258D01*
X386825Y224592D01*
X386992Y224800D01*
X387325Y224883D01*
X387658Y224800D01*
X387867Y224550D01*
X387992Y224258D01*
Y223217D01*
G01Y224258D02*
X389200Y224883D01*
G01Y227150D02*
X389158Y227442D01*
X389033Y227775D01*
X388825Y227983D01*
X388533Y228067D01*
X388242Y227983D01*
X387992Y227733D01*
X387867Y227358D01*
Y226942D01*
X387783Y226692D01*
X387575Y226483D01*
X387283Y226400D01*
X386992Y226525D01*
X386783Y226817D01*
X386700Y227150D01*
X386783Y227483D01*
X386992Y227775D01*
X387283Y227900D01*
X387575Y227817D01*
X387783Y227608D01*
X387867Y227358D01*
Y226942D01*
X387992Y226567D01*
X388242Y226317D01*
X388533Y226233D01*
X388825Y226317D01*
X389033Y226525D01*
X389158Y226858D01*
X389200Y227150D01*
G01Y230250D02*
X389158Y230542D01*
X389033Y230875D01*
X388825Y231083D01*
X388533Y231167D01*
X388242Y231083D01*
X387992Y230833D01*
X387867Y230458D01*
Y230042D01*
X387783Y229792D01*
X387575Y229583D01*
X387283Y229500D01*
X386992Y229625D01*
X386783Y229917D01*
X386700Y230250D01*
X386783Y230583D01*
X386992Y230875D01*
X387283Y231000D01*
X387575Y230917D01*
X387783Y230708D01*
X387867Y230458D01*
Y230042D01*
X387992Y229667D01*
X388242Y229417D01*
X388533Y229333D01*
X388825Y229417D01*
X389033Y229625D01*
X389158Y229958D01*
X389200Y230250D01*
G01X374217Y214500D02*
Y217000D01*
X375217D01*
X375550Y216875D01*
X375800Y216583D01*
X375883Y216250D01*
X375800Y215917D01*
X375592Y215667D01*
X375217Y215542D01*
X374217D01*
G01X379067Y216792D02*
X378817Y216917D01*
X378525Y217000D01*
X378192D01*
X377817Y216875D01*
X377525Y216667D01*
X377317Y216417D01*
X377150Y216000D01*
X377108Y215625D01*
X377192Y215250D01*
X377317Y215000D01*
X377567Y214750D01*
X377858Y214583D01*
X378150Y214500D01*
X378442D01*
X378733Y214583D01*
X378983Y214708D01*
X379192Y214875D01*
G01X380458Y215542D02*
X380750Y215833D01*
X381000Y216000D01*
X381333Y216083D01*
X381625Y216000D01*
X381833Y215833D01*
X382000Y215583D01*
X382042Y215292D01*
X382000Y215042D01*
X381833Y214792D01*
X381583Y214583D01*
X381292Y214500D01*
X380958Y214583D01*
X380667Y214833D01*
X380500Y215208D01*
X380458Y215625D01*
X380542Y216167D01*
X380667Y216458D01*
X380875Y216750D01*
X381167Y216958D01*
X381458Y217000D01*
X381750Y216917D01*
X381958Y216708D01*
G01X384267Y214500D02*
X384350Y215042D01*
X384475Y215500D01*
X384642Y215917D01*
X384850Y216375D01*
X385183Y217000D01*
X383517D01*
G01X385000Y219967D02*
X382500D01*
Y220967D01*
X382625Y221300D01*
X382917Y221550D01*
X383250Y221633D01*
X383583Y221550D01*
X383833Y221342D01*
X383958Y220967D01*
Y219967D01*
G01X385000Y223067D02*
X382500D01*
Y224108D01*
X382625Y224442D01*
X382792Y224650D01*
X383125Y224733D01*
X383458Y224650D01*
X383667Y224400D01*
X383792Y224108D01*
Y223067D01*
G01Y224108D02*
X385000Y224733D01*
G01Y227000D02*
X382500D01*
X383000Y226500D01*
G01X385000D02*
Y227500D01*
G01Y230100D02*
X384958Y230392D01*
X384833Y230725D01*
X384625Y230933D01*
X384333Y231017D01*
X384042Y230933D01*
X383792Y230683D01*
X383667Y230308D01*
Y229892D01*
X383583Y229642D01*
X383375Y229433D01*
X383083Y229350D01*
X382792Y229475D01*
X382583Y229767D01*
X382500Y230100D01*
X382583Y230433D01*
X382792Y230725D01*
X383083Y230850D01*
X383375Y230767D01*
X383583Y230558D01*
X383667Y230308D01*
Y229892D01*
X383792Y229517D01*
X384042Y229267D01*
X384333Y229183D01*
X384625Y229267D01*
X384833Y229475D01*
X384958Y229808D01*
X385000Y230100D01*
G01Y233200D02*
X384958Y233492D01*
X384833Y233825D01*
X384625Y234033D01*
X384333Y234117D01*
X384042Y234033D01*
X383792Y233783D01*
X383667Y233408D01*
Y232992D01*
X383583Y232742D01*
X383375Y232533D01*
X383083Y232450D01*
X382792Y232575D01*
X382583Y232867D01*
X382500Y233200D01*
X382583Y233533D01*
X382792Y233825D01*
X383083Y233950D01*
X383375Y233867D01*
X383583Y233658D01*
X383667Y233408D01*
Y232992D01*
X383792Y232617D01*
X384042Y232367D01*
X384333Y232283D01*
X384625Y232367D01*
X384833Y232575D01*
X384958Y232908D01*
X385000Y233200D01*
G01X389500Y233517D02*
X387000D01*
Y234517D01*
X387125Y234850D01*
X387417Y235100D01*
X387750Y235183D01*
X388083Y235100D01*
X388333Y234892D01*
X388458Y234517D01*
Y233517D01*
G01X387208Y238367D02*
X387083Y238117D01*
X387000Y237825D01*
Y237492D01*
X387125Y237117D01*
X387333Y236825D01*
X387583Y236617D01*
X388000Y236450D01*
X388375Y236408D01*
X388750Y236492D01*
X389000Y236617D01*
X389250Y236867D01*
X389417Y237158D01*
X389500Y237450D01*
Y237742D01*
X389417Y238033D01*
X389292Y238283D01*
X389125Y238492D01*
G01X389500Y240467D02*
X388958Y240550D01*
X388500Y240675D01*
X388083Y240842D01*
X387625Y241050D01*
X387000Y241383D01*
Y239717D01*
G01X387417Y242858D02*
X387167Y243108D01*
X387042Y243400D01*
X387000Y243733D01*
X387083Y244150D01*
X387292Y244442D01*
X387542Y244525D01*
X387792Y244483D01*
X388000Y244317D01*
X388417Y243483D01*
X388708Y243108D01*
X389125Y242858D01*
X389500Y242775D01*
Y244525D01*
G01X376700Y231017D02*
X374200D01*
Y232017D01*
X374325Y232350D01*
X374617Y232600D01*
X374950Y232683D01*
X375283Y232600D01*
X375533Y232392D01*
X375658Y232017D01*
Y231017D01*
G01X376700Y234117D02*
X374200D01*
Y235158D01*
X374325Y235492D01*
X374492Y235700D01*
X374825Y235783D01*
X375158Y235700D01*
X375367Y235450D01*
X375492Y235158D01*
Y234117D01*
G01Y235158D02*
X376700Y235783D01*
G01Y237967D02*
X376158Y238050D01*
X375700Y238175D01*
X375283Y238342D01*
X374825Y238550D01*
X374200Y238883D01*
Y237217D01*
G01X375658Y240358D02*
X375367Y240650D01*
X375200Y240900D01*
X375117Y241233D01*
X375200Y241525D01*
X375367Y241733D01*
X375617Y241900D01*
X375908Y241942D01*
X376158Y241900D01*
X376408Y241733D01*
X376617Y241483D01*
X376700Y241192D01*
X376617Y240858D01*
X376367Y240567D01*
X375992Y240400D01*
X375575Y240358D01*
X375033Y240442D01*
X374742Y240567D01*
X374450Y240775D01*
X374242Y241067D01*
X374200Y241358D01*
X374283Y241650D01*
X374492Y241858D01*
G01X375500Y254517D02*
X373000D01*
Y255517D01*
X373125Y255850D01*
X373417Y256100D01*
X373750Y256183D01*
X374083Y256100D01*
X374333Y255892D01*
X374458Y255517D01*
Y254517D01*
G01X375500Y257617D02*
X373000D01*
Y258658D01*
X373125Y258992D01*
X373292Y259200D01*
X373625Y259283D01*
X373958Y259200D01*
X374167Y258950D01*
X374292Y258658D01*
Y257617D01*
G01Y258658D02*
X375500Y259283D01*
G01X373417Y260758D02*
X373167Y261008D01*
X373042Y261300D01*
X373000Y261633D01*
X373083Y262050D01*
X373292Y262342D01*
X373542Y262425D01*
X373792Y262383D01*
X374000Y262217D01*
X374417Y261383D01*
X374708Y261008D01*
X375125Y260758D01*
X375500Y260675D01*
Y262425D01*
G01X375125Y263733D02*
X375333Y263983D01*
X375458Y264275D01*
X375500Y264650D01*
X375417Y265025D01*
X375250Y265317D01*
X374958Y265525D01*
X374625Y265567D01*
X374292Y265483D01*
X374083Y265275D01*
X373917Y264983D01*
X373875Y264692D01*
X373917Y264400D01*
X374083Y264025D01*
X373000Y264150D01*
Y265275D01*
G01X380500Y259900D02*
X383000D01*
G01X380500Y258942D02*
Y260858D01*
G01X383000Y262167D02*
X380500D01*
Y263167D01*
X380625Y263500D01*
X380917Y263750D01*
X381250Y263833D01*
X381583Y263750D01*
X381833Y263542D01*
X381958Y263167D01*
Y262167D01*
G01X380917Y265308D02*
X380667Y265558D01*
X380542Y265850D01*
X380500Y266183D01*
X380583Y266600D01*
X380792Y266892D01*
X381042Y266975D01*
X381292Y266933D01*
X381500Y266767D01*
X381917Y265933D01*
X382208Y265558D01*
X382625Y265308D01*
X383000Y265225D01*
Y266975D01*
G01X385000Y259900D02*
X387500D01*
G01X385000Y258942D02*
Y260858D01*
G01X387500Y262167D02*
X385000D01*
Y263167D01*
X385125Y263500D01*
X385417Y263750D01*
X385750Y263833D01*
X386083Y263750D01*
X386333Y263542D01*
X386458Y263167D01*
Y262167D01*
G01X387000Y265183D02*
X387292Y265433D01*
X387458Y265767D01*
X387500Y266142D01*
X387458Y266475D01*
X387250Y266808D01*
X387000Y267017D01*
X386750Y267058D01*
X386458Y266975D01*
X386250Y266683D01*
X386167Y266392D01*
Y266017D01*
G01Y266392D02*
X386042Y266642D01*
X385833Y266850D01*
X385583Y266933D01*
X385333Y266850D01*
X385125Y266642D01*
X385000Y266267D01*
X385042Y265892D01*
X385208Y265517D01*
G01X382000Y274500D02*
X393000D01*
Y288500D01*
G01X375800Y273217D02*
X373300D01*
Y274217D01*
X373425Y274550D01*
X373717Y274800D01*
X374050Y274883D01*
X374383Y274800D01*
X374633Y274592D01*
X374758Y274217D01*
Y273217D01*
G01X375800Y276317D02*
X373300D01*
Y277358D01*
X373425Y277692D01*
X373592Y277900D01*
X373925Y277983D01*
X374258Y277900D01*
X374467Y277650D01*
X374592Y277358D01*
Y276317D01*
G01Y277358D02*
X375800Y277983D01*
G01X373717Y279458D02*
X373467Y279708D01*
X373342Y280000D01*
X373300Y280333D01*
X373383Y280750D01*
X373592Y281042D01*
X373842Y281125D01*
X374092Y281083D01*
X374300Y280917D01*
X374717Y280083D01*
X375008Y279708D01*
X375425Y279458D01*
X375800Y279375D01*
Y281125D01*
G01X375508Y282642D02*
X375717Y282933D01*
X375800Y283267D01*
X375717Y283600D01*
X375467Y283892D01*
X375092Y284100D01*
X374717Y284183D01*
X374258D01*
X373883Y284100D01*
X373550Y283892D01*
X373383Y283642D01*
X373300Y283350D01*
X373383Y283017D01*
X373550Y282767D01*
X373800Y282600D01*
X374133Y282517D01*
X374425Y282600D01*
X374717Y282808D01*
X374883Y283058D01*
X374925Y283350D01*
X374842Y283683D01*
X374633Y283933D01*
X374258Y284183D01*
G01X388920Y277117D02*
X386420D01*
Y278117D01*
X386545Y278450D01*
X386837Y278700D01*
X387170Y278783D01*
X387503Y278700D01*
X387753Y278492D01*
X387878Y278117D01*
Y277117D01*
G01X388920Y280217D02*
X386420D01*
Y281258D01*
X386545Y281592D01*
X386712Y281800D01*
X387045Y281883D01*
X387378Y281800D01*
X387587Y281550D01*
X387712Y281258D01*
Y280217D01*
G01Y281258D02*
X388920Y281883D01*
G01Y284150D02*
X386420D01*
X386920Y283650D01*
G01X388920D02*
Y284650D01*
G01X388420Y286333D02*
X388712Y286583D01*
X388878Y286917D01*
X388920Y287292D01*
X388878Y287625D01*
X388670Y287958D01*
X388420Y288167D01*
X388170Y288208D01*
X387878Y288125D01*
X387670Y287833D01*
X387587Y287542D01*
Y287167D01*
G01Y287542D02*
X387462Y287792D01*
X387253Y288000D01*
X387003Y288083D01*
X386753Y288000D01*
X386545Y287792D01*
X386420Y287417D01*
X386462Y287042D01*
X386628Y286667D01*
G01X384720Y277117D02*
X382220D01*
Y278117D01*
X382345Y278450D01*
X382637Y278700D01*
X382970Y278783D01*
X383303Y278700D01*
X383553Y278492D01*
X383678Y278117D01*
Y277117D01*
G01X382428Y281967D02*
X382303Y281717D01*
X382220Y281425D01*
Y281092D01*
X382345Y280717D01*
X382553Y280425D01*
X382803Y280217D01*
X383220Y280050D01*
X383595Y280008D01*
X383970Y280092D01*
X384220Y280217D01*
X384470Y280467D01*
X384637Y280758D01*
X384720Y281050D01*
Y281342D01*
X384637Y281633D01*
X384512Y281883D01*
X384345Y282092D01*
G01X384720Y284150D02*
X382220D01*
X382720Y283650D01*
G01X384720D02*
Y284650D01*
G01X384220Y286333D02*
X384512Y286583D01*
X384678Y286917D01*
X384720Y287292D01*
X384678Y287625D01*
X384470Y287958D01*
X384220Y288167D01*
X383970Y288208D01*
X383678Y288125D01*
X383470Y287833D01*
X383387Y287542D01*
Y287167D01*
G01Y287542D02*
X383262Y287792D01*
X383053Y288000D01*
X382803Y288083D01*
X382553Y288000D01*
X382345Y287792D01*
X382220Y287417D01*
X382262Y287042D01*
X382428Y286667D01*
G01X390500Y53000D02*
Y48500D01*
X395500D01*
G01X402500Y53983D02*
X404292D01*
X404667Y54150D01*
X404917Y54483D01*
X405000Y54900D01*
X404917Y55317D01*
X404667Y55650D01*
X404292Y55817D01*
X402500D01*
G01X405000Y58500D02*
X402500D01*
X404292Y56958D01*
Y59042D01*
G01X403958Y60308D02*
X403667Y60600D01*
X403500Y60850D01*
X403417Y61183D01*
X403500Y61475D01*
X403667Y61683D01*
X403917Y61850D01*
X404208Y61892D01*
X404458Y61850D01*
X404708Y61683D01*
X404917Y61433D01*
X405000Y61142D01*
X404917Y60808D01*
X404667Y60517D01*
X404292Y60350D01*
X403875Y60308D01*
X403333Y60392D01*
X403042Y60517D01*
X402750Y60725D01*
X402542Y61017D01*
X402500Y61308D01*
X402583Y61600D01*
X402792Y61808D01*
G01X392000Y65017D02*
X389500D01*
Y66058D01*
X389625Y66392D01*
X389792Y66600D01*
X390125Y66683D01*
X390458Y66600D01*
X390667Y66350D01*
X390792Y66058D01*
Y65017D01*
G01Y66058D02*
X392000Y66683D01*
G01X389917Y68158D02*
X389667Y68408D01*
X389542Y68700D01*
X389500Y69033D01*
X389583Y69450D01*
X389792Y69742D01*
X390042Y69825D01*
X390292Y69783D01*
X390500Y69617D01*
X390917Y68783D01*
X391208Y68408D01*
X391625Y68158D01*
X392000Y68075D01*
Y69825D01*
G01Y71967D02*
X391458Y72050D01*
X391000Y72175D01*
X390583Y72342D01*
X390125Y72550D01*
X389500Y72883D01*
Y71217D01*
G01X392000Y75150D02*
X389500D01*
X390000Y74650D01*
G01X392000D02*
Y75650D01*
G01X396000Y65017D02*
X393500D01*
Y66058D01*
X393625Y66392D01*
X393792Y66600D01*
X394125Y66683D01*
X394458Y66600D01*
X394667Y66350D01*
X394792Y66058D01*
Y65017D01*
G01Y66058D02*
X396000Y66683D01*
G01X393917Y68158D02*
X393667Y68408D01*
X393542Y68700D01*
X393500Y69033D01*
X393583Y69450D01*
X393792Y69742D01*
X394042Y69825D01*
X394292Y69783D01*
X394500Y69617D01*
X394917Y68783D01*
X395208Y68408D01*
X395625Y68158D01*
X396000Y68075D01*
Y69825D01*
G01Y72550D02*
X393500D01*
X395292Y71008D01*
Y73092D01*
G01X396000Y75650D02*
X393500D01*
X395292Y74108D01*
Y76192D01*
G01X404000Y65017D02*
X401500D01*
Y66058D01*
X401625Y66392D01*
X401792Y66600D01*
X402125Y66683D01*
X402458Y66600D01*
X402667Y66350D01*
X402792Y66058D01*
Y65017D01*
G01Y66058D02*
X404000Y66683D01*
G01X401917Y68158D02*
X401667Y68408D01*
X401542Y68700D01*
X401500Y69033D01*
X401583Y69450D01*
X401792Y69742D01*
X402042Y69825D01*
X402292Y69783D01*
X402500Y69617D01*
X402917Y68783D01*
X403208Y68408D01*
X403625Y68158D01*
X404000Y68075D01*
Y69825D01*
G01Y72550D02*
X401500D01*
X403292Y71008D01*
Y73092D01*
G01X401917Y74358D02*
X401667Y74608D01*
X401542Y74900D01*
X401500Y75233D01*
X401583Y75650D01*
X401792Y75942D01*
X402042Y76025D01*
X402292Y75983D01*
X402500Y75817D01*
X402917Y74983D01*
X403208Y74608D01*
X403625Y74358D01*
X404000Y74275D01*
Y76025D01*
G01X400000Y65017D02*
X397500D01*
Y66058D01*
X397625Y66392D01*
X397792Y66600D01*
X398125Y66683D01*
X398458Y66600D01*
X398667Y66350D01*
X398792Y66058D01*
Y65017D01*
G01Y66058D02*
X400000Y66683D01*
G01X397917Y68158D02*
X397667Y68408D01*
X397542Y68700D01*
X397500Y69033D01*
X397583Y69450D01*
X397792Y69742D01*
X398042Y69825D01*
X398292Y69783D01*
X398500Y69617D01*
X398917Y68783D01*
X399208Y68408D01*
X399625Y68158D01*
X400000Y68075D01*
Y69825D01*
G01Y72550D02*
X397500D01*
X399292Y71008D01*
Y73092D01*
G01X399500Y74233D02*
X399792Y74483D01*
X399958Y74817D01*
X400000Y75192D01*
X399958Y75525D01*
X399750Y75858D01*
X399500Y76067D01*
X399250Y76108D01*
X398958Y76025D01*
X398750Y75733D01*
X398667Y75442D01*
Y75067D01*
G01Y75442D02*
X398542Y75692D01*
X398333Y75900D01*
X398083Y75983D01*
X397833Y75900D01*
X397625Y75692D01*
X397500Y75317D01*
X397542Y74942D01*
X397708Y74567D01*
G01X396000Y78500D02*
X407000D01*
Y81000D01*
G01X400517Y91500D02*
Y94000D01*
X401558D01*
X401892Y93875D01*
X402100Y93708D01*
X402183Y93375D01*
X402100Y93042D01*
X401850Y92833D01*
X401558Y92708D01*
X400517D01*
G01X401558D02*
X402183Y91500D01*
G01X404450D02*
Y94000D01*
X403950Y93500D01*
G01Y91500D02*
X404950D01*
G01X406758Y92542D02*
X407050Y92833D01*
X407300Y93000D01*
X407633Y93083D01*
X407925Y93000D01*
X408133Y92833D01*
X408300Y92583D01*
X408342Y92292D01*
X408300Y92042D01*
X408133Y91792D01*
X407883Y91583D01*
X407592Y91500D01*
X407258Y91583D01*
X406967Y91833D01*
X406800Y92208D01*
X406758Y92625D01*
X406842Y93167D01*
X406967Y93458D01*
X407175Y93750D01*
X407467Y93958D01*
X407758Y94000D01*
X408050Y93917D01*
X408258Y93708D01*
G01X409733Y91875D02*
X409983Y91667D01*
X410275Y91542D01*
X410650Y91500D01*
X411025Y91583D01*
X411317Y91750D01*
X411525Y92042D01*
X411567Y92375D01*
X411483Y92708D01*
X411275Y92917D01*
X410983Y93083D01*
X410692Y93125D01*
X410400Y93083D01*
X410025Y92917D01*
X410150Y94000D01*
X411275D01*
G01X398017Y95500D02*
Y98000D01*
X399058D01*
X399392Y97875D01*
X399600Y97708D01*
X399683Y97375D01*
X399600Y97042D01*
X399350Y96833D01*
X399058Y96708D01*
X398017D01*
G01X399058D02*
X399683Y95500D01*
G01X401950D02*
Y98000D01*
X401450Y97500D01*
G01Y95500D02*
X402450D01*
G01X404258Y96542D02*
X404550Y96833D01*
X404800Y97000D01*
X405133Y97083D01*
X405425Y97000D01*
X405633Y96833D01*
X405800Y96583D01*
X405842Y96292D01*
X405800Y96042D01*
X405633Y95792D01*
X405383Y95583D01*
X405092Y95500D01*
X404758Y95583D01*
X404467Y95833D01*
X404300Y96208D01*
X404258Y96625D01*
X404342Y97167D01*
X404467Y97458D01*
X404675Y97750D01*
X404967Y97958D01*
X405258Y98000D01*
X405550Y97917D01*
X405758Y97708D01*
G01X407358Y97583D02*
X407608Y97833D01*
X407900Y97958D01*
X408233Y98000D01*
X408650Y97917D01*
X408942Y97708D01*
X409025Y97458D01*
X408983Y97208D01*
X408817Y97000D01*
X407983Y96583D01*
X407608Y96292D01*
X407358Y95875D01*
X407275Y95500D01*
X409025D01*
G01X393300Y220017D02*
X390800D01*
Y221017D01*
X390925Y221350D01*
X391217Y221600D01*
X391550Y221683D01*
X391883Y221600D01*
X392133Y221392D01*
X392258Y221017D01*
Y220017D01*
G01X393300Y223117D02*
X390800D01*
Y224158D01*
X390925Y224492D01*
X391092Y224700D01*
X391425Y224783D01*
X391758Y224700D01*
X391967Y224450D01*
X392092Y224158D01*
Y223117D01*
G01Y224158D02*
X393300Y224783D01*
G01X393008Y226342D02*
X393217Y226633D01*
X393300Y226967D01*
X393217Y227300D01*
X392967Y227592D01*
X392592Y227800D01*
X392217Y227883D01*
X391758D01*
X391383Y227800D01*
X391050Y227592D01*
X390883Y227342D01*
X390800Y227050D01*
X390883Y226717D01*
X391050Y226467D01*
X391300Y226300D01*
X391633Y226217D01*
X391925Y226300D01*
X392217Y226508D01*
X392383Y226758D01*
X392425Y227050D01*
X392342Y227383D01*
X392133Y227633D01*
X391758Y227883D01*
G01X393300Y230650D02*
X390800D01*
X392592Y229108D01*
Y231192D01*
G01X402900Y222117D02*
X400400D01*
Y223117D01*
X400525Y223450D01*
X400817Y223700D01*
X401150Y223783D01*
X401483Y223700D01*
X401733Y223492D01*
X401858Y223117D01*
Y222117D01*
G01X400608Y226967D02*
X400483Y226717D01*
X400400Y226425D01*
Y226092D01*
X400525Y225717D01*
X400733Y225425D01*
X400983Y225217D01*
X401400Y225050D01*
X401775Y225008D01*
X402150Y225092D01*
X402400Y225217D01*
X402650Y225467D01*
X402817Y225758D01*
X402900Y226050D01*
Y226342D01*
X402817Y226633D01*
X402692Y226883D01*
X402525Y227092D01*
G01Y228233D02*
X402733Y228483D01*
X402858Y228775D01*
X402900Y229150D01*
X402817Y229525D01*
X402650Y229817D01*
X402358Y230025D01*
X402025Y230067D01*
X401692Y229983D01*
X401483Y229775D01*
X401317Y229483D01*
X401275Y229192D01*
X401317Y228900D01*
X401483Y228525D01*
X400400Y228650D01*
Y229775D01*
G01X402525Y231333D02*
X402733Y231583D01*
X402858Y231875D01*
X402900Y232250D01*
X402817Y232625D01*
X402650Y232917D01*
X402358Y233125D01*
X402025Y233167D01*
X401692Y233083D01*
X401483Y232875D01*
X401317Y232583D01*
X401275Y232292D01*
X401317Y232000D01*
X401483Y231625D01*
X400400Y231750D01*
Y232875D01*
G01X399000Y222017D02*
X396500D01*
Y223017D01*
X396625Y223350D01*
X396917Y223600D01*
X397250Y223683D01*
X397583Y223600D01*
X397833Y223392D01*
X397958Y223017D01*
Y222017D01*
G01X399000Y225117D02*
X396500D01*
Y226158D01*
X396625Y226492D01*
X396792Y226700D01*
X397125Y226783D01*
X397458Y226700D01*
X397667Y226450D01*
X397792Y226158D01*
Y225117D01*
G01Y226158D02*
X399000Y226783D01*
G01Y228967D02*
X398458Y229050D01*
X398000Y229175D01*
X397583Y229342D01*
X397125Y229550D01*
X396500Y229883D01*
Y228217D01*
G01X398625Y231233D02*
X398833Y231483D01*
X398958Y231775D01*
X399000Y232150D01*
X398917Y232525D01*
X398750Y232817D01*
X398458Y233025D01*
X398125Y233067D01*
X397792Y232983D01*
X397583Y232775D01*
X397417Y232483D01*
X397375Y232192D01*
X397417Y231900D01*
X397583Y231525D01*
X396500Y231650D01*
Y232775D01*
G01X388017Y214500D02*
Y217000D01*
X389017D01*
X389350Y216875D01*
X389600Y216583D01*
X389683Y216250D01*
X389600Y215917D01*
X389392Y215667D01*
X389017Y215542D01*
X388017D01*
G01X391117Y214500D02*
Y217000D01*
X392158D01*
X392492Y216875D01*
X392700Y216708D01*
X392783Y216375D01*
X392700Y216042D01*
X392450Y215833D01*
X392158Y215708D01*
X391117D01*
G01X392158D02*
X392783Y214500D01*
G01X395550D02*
Y217000D01*
X394008Y215208D01*
X396092D01*
G01X397358Y215542D02*
X397650Y215833D01*
X397900Y216000D01*
X398233Y216083D01*
X398525Y216000D01*
X398733Y215833D01*
X398900Y215583D01*
X398942Y215292D01*
X398900Y215042D01*
X398733Y214792D01*
X398483Y214583D01*
X398192Y214500D01*
X397858Y214583D01*
X397567Y214833D01*
X397400Y215208D01*
X397358Y215625D01*
X397442Y216167D01*
X397567Y216458D01*
X397775Y216750D01*
X398067Y216958D01*
X398358Y217000D01*
X398650Y216917D01*
X398858Y216708D01*
G01X394000Y233517D02*
X391500D01*
Y234517D01*
X391625Y234850D01*
X391917Y235100D01*
X392250Y235183D01*
X392583Y235100D01*
X392833Y234892D01*
X392958Y234517D01*
Y233517D01*
G01X394000Y236617D02*
X391500D01*
Y237658D01*
X391625Y237992D01*
X391792Y238200D01*
X392125Y238283D01*
X392458Y238200D01*
X392667Y237950D01*
X392792Y237658D01*
Y236617D01*
G01Y237658D02*
X394000Y238283D01*
G01X393708Y239842D02*
X393917Y240133D01*
X394000Y240467D01*
X393917Y240800D01*
X393667Y241092D01*
X393292Y241300D01*
X392917Y241383D01*
X392458D01*
X392083Y241300D01*
X391750Y241092D01*
X391583Y240842D01*
X391500Y240550D01*
X391583Y240217D01*
X391750Y239967D01*
X392000Y239800D01*
X392333Y239717D01*
X392625Y239800D01*
X392917Y240008D01*
X393083Y240258D01*
X393125Y240550D01*
X393042Y240883D01*
X392833Y241133D01*
X392458Y241383D01*
G01X393500Y242733D02*
X393792Y242983D01*
X393958Y243317D01*
X394000Y243692D01*
X393958Y244025D01*
X393750Y244358D01*
X393500Y244567D01*
X393250Y244608D01*
X392958Y244525D01*
X392750Y244233D01*
X392667Y243942D01*
Y243567D01*
G01Y243942D02*
X392542Y244192D01*
X392333Y244400D01*
X392083Y244483D01*
X391833Y244400D01*
X391625Y244192D01*
X391500Y243817D01*
X391542Y243442D01*
X391708Y243067D01*
G01X400500Y288500D02*
Y248500D01*
X419500D01*
Y264500D01*
X422500D01*
Y288500D01*
G01X405000Y253017D02*
X402500D01*
Y254017D01*
X402625Y254350D01*
X402917Y254600D01*
X403250Y254683D01*
X403583Y254600D01*
X403833Y254392D01*
X403958Y254017D01*
Y253017D01*
G01X402708Y257867D02*
X402583Y257617D01*
X402500Y257325D01*
Y256992D01*
X402625Y256617D01*
X402833Y256325D01*
X403083Y256117D01*
X403500Y255950D01*
X403875Y255908D01*
X404250Y255992D01*
X404500Y256117D01*
X404750Y256367D01*
X404917Y256658D01*
X405000Y256950D01*
Y257242D01*
X404917Y257533D01*
X404792Y257783D01*
X404625Y257992D01*
G01X405000Y259967D02*
X404458Y260050D01*
X404000Y260175D01*
X403583Y260342D01*
X403125Y260550D01*
X402500Y260883D01*
Y259217D01*
G01X403958Y262358D02*
X403667Y262650D01*
X403500Y262900D01*
X403417Y263233D01*
X403500Y263525D01*
X403667Y263733D01*
X403917Y263900D01*
X404208Y263942D01*
X404458Y263900D01*
X404708Y263733D01*
X404917Y263483D01*
X405000Y263192D01*
X404917Y262858D01*
X404667Y262567D01*
X404292Y262400D01*
X403875Y262358D01*
X403333Y262442D01*
X403042Y262567D01*
X402750Y262775D01*
X402542Y263067D01*
X402500Y263358D01*
X402583Y263650D01*
X402792Y263858D01*
G01X390567Y258000D02*
Y260500D01*
X391567D01*
X391900Y260375D01*
X392150Y260083D01*
X392233Y259750D01*
X392150Y259417D01*
X391942Y259167D01*
X391567Y259042D01*
X390567D01*
G01X393667Y258000D02*
Y260500D01*
X394708D01*
X395042Y260375D01*
X395250Y260208D01*
X395333Y259875D01*
X395250Y259542D01*
X395000Y259333D01*
X394708Y259208D01*
X393667D01*
G01X394708D02*
X395333Y258000D01*
G01X397600D02*
X397892Y258042D01*
X398225Y258167D01*
X398433Y258375D01*
X398517Y258667D01*
X398433Y258958D01*
X398183Y259208D01*
X397808Y259333D01*
X397392D01*
X397142Y259417D01*
X396933Y259625D01*
X396850Y259917D01*
X396975Y260208D01*
X397267Y260417D01*
X397600Y260500D01*
X397933Y260417D01*
X398225Y260208D01*
X398350Y259917D01*
X398267Y259625D01*
X398058Y259417D01*
X397808Y259333D01*
X397392D01*
X397017Y259208D01*
X396767Y258958D01*
X396683Y258667D01*
X396767Y258375D01*
X396975Y258167D01*
X397308Y258042D01*
X397600Y258000D01*
G01X390567Y250000D02*
Y252500D01*
X391567D01*
X391900Y252375D01*
X392150Y252083D01*
X392233Y251750D01*
X392150Y251417D01*
X391942Y251167D01*
X391567Y251042D01*
X390567D01*
G01X393667Y250000D02*
Y252500D01*
X394708D01*
X395042Y252375D01*
X395250Y252208D01*
X395333Y251875D01*
X395250Y251542D01*
X395000Y251333D01*
X394708Y251208D01*
X393667D01*
G01X394708D02*
X395333Y250000D01*
G01X397517D02*
X397600Y250542D01*
X397725Y251000D01*
X397892Y251417D01*
X398100Y251875D01*
X398433Y252500D01*
X396767D01*
G01X390567Y254000D02*
Y256500D01*
X391567D01*
X391900Y256375D01*
X392150Y256083D01*
X392233Y255750D01*
X392150Y255417D01*
X391942Y255167D01*
X391567Y255042D01*
X390567D01*
G01X393667Y254000D02*
Y256500D01*
X394708D01*
X395042Y256375D01*
X395250Y256208D01*
X395333Y255875D01*
X395250Y255542D01*
X395000Y255333D01*
X394708Y255208D01*
X393667D01*
G01X394708D02*
X395333Y254000D01*
G01X396892Y254292D02*
X397183Y254083D01*
X397517Y254000D01*
X397850Y254083D01*
X398142Y254333D01*
X398350Y254708D01*
X398433Y255083D01*
Y255542D01*
X398350Y255917D01*
X398142Y256250D01*
X397892Y256417D01*
X397600Y256500D01*
X397267Y256417D01*
X397017Y256250D01*
X396850Y256000D01*
X396767Y255667D01*
X396850Y255375D01*
X397058Y255083D01*
X397308Y254917D01*
X397600Y254875D01*
X397933Y254958D01*
X398183Y255167D01*
X398433Y255542D01*
G01X405000Y266067D02*
X402500D01*
Y267067D01*
X402625Y267400D01*
X402917Y267650D01*
X403250Y267733D01*
X403583Y267650D01*
X403833Y267442D01*
X403958Y267067D01*
Y266067D01*
G01X403750Y270250D02*
Y271083D01*
X404500D01*
X404750Y270833D01*
X404917Y270542D01*
X405000Y270125D01*
X404917Y269708D01*
X404750Y269417D01*
X404500Y269167D01*
X404208Y269000D01*
X403875Y268917D01*
X403583D01*
X403333Y269000D01*
X403042Y269167D01*
X402792Y269417D01*
X402625Y269667D01*
X402500Y270000D01*
Y270292D01*
X402583Y270625D01*
X402750Y270875D01*
G01X403958Y272308D02*
X403667Y272600D01*
X403500Y272850D01*
X403417Y273183D01*
X403500Y273475D01*
X403667Y273683D01*
X403917Y273850D01*
X404208Y273892D01*
X404458Y273850D01*
X404708Y273683D01*
X404917Y273433D01*
X405000Y273142D01*
X404917Y272808D01*
X404667Y272517D01*
X404292Y272350D01*
X403875Y272308D01*
X403333Y272392D01*
X403042Y272517D01*
X402750Y272725D01*
X402542Y273017D01*
X402500Y273308D01*
X402583Y273600D01*
X402792Y273808D01*
G01X404500Y280567D02*
X402000D01*
Y281567D01*
X402125Y281900D01*
X402417Y282150D01*
X402750Y282233D01*
X403083Y282150D01*
X403333Y281942D01*
X403458Y281567D01*
Y280567D01*
G01X402000Y283667D02*
X404500D01*
Y285333D01*
G01X404208Y286892D02*
X404417Y287183D01*
X404500Y287517D01*
X404417Y287850D01*
X404167Y288142D01*
X403792Y288350D01*
X403417Y288433D01*
X402958D01*
X402583Y288350D01*
X402250Y288142D01*
X402083Y287892D01*
X402000Y287600D01*
X402083Y287267D01*
X402250Y287017D01*
X402500Y286850D01*
X402833Y286767D01*
X403125Y286850D01*
X403417Y287058D01*
X403583Y287308D01*
X403625Y287600D01*
X403542Y287933D01*
X403333Y288183D01*
X402958Y288433D01*
G01X416000Y40500D02*
Y4000D01*
X419500D01*
G01X420500Y6017D02*
X418000D01*
Y7058D01*
X418125Y7392D01*
X418292Y7600D01*
X418625Y7683D01*
X418958Y7600D01*
X419167Y7350D01*
X419292Y7058D01*
Y6017D01*
G01Y7058D02*
X420500Y7683D01*
G01X420000Y9033D02*
X420292Y9283D01*
X420458Y9617D01*
X420500Y9992D01*
X420458Y10325D01*
X420250Y10658D01*
X420000Y10867D01*
X419750Y10908D01*
X419458Y10825D01*
X419250Y10533D01*
X419167Y10242D01*
Y9867D01*
G01Y10242D02*
X419042Y10492D01*
X418833Y10700D01*
X418583Y10783D01*
X418333Y10700D01*
X418125Y10492D01*
X418000Y10117D01*
X418042Y9742D01*
X418208Y9367D01*
G01X419458Y12258D02*
X419167Y12550D01*
X419000Y12800D01*
X418917Y13133D01*
X419000Y13425D01*
X419167Y13633D01*
X419417Y13800D01*
X419708Y13842D01*
X419958Y13800D01*
X420208Y13633D01*
X420417Y13383D01*
X420500Y13092D01*
X420417Y12758D01*
X420167Y12467D01*
X419792Y12300D01*
X419375Y12258D01*
X418833Y12342D01*
X418542Y12467D01*
X418250Y12675D01*
X418042Y12967D01*
X418000Y13258D01*
X418083Y13550D01*
X418292Y13758D01*
G01X420000Y15233D02*
X420292Y15483D01*
X420458Y15817D01*
X420500Y16192D01*
X420458Y16525D01*
X420250Y16858D01*
X420000Y17067D01*
X419750Y17108D01*
X419458Y17025D01*
X419250Y16733D01*
X419167Y16442D01*
Y16067D01*
G01Y16442D02*
X419042Y16692D01*
X418833Y16900D01*
X418583Y16983D01*
X418333Y16900D01*
X418125Y16692D01*
X418000Y16317D01*
X418042Y15942D01*
X418208Y15567D01*
G01X417517Y27500D02*
Y30000D01*
X418558D01*
X418892Y29875D01*
X419100Y29708D01*
X419183Y29375D01*
X419100Y29042D01*
X418850Y28833D01*
X418558Y28708D01*
X417517D01*
G01X418558D02*
X419183Y27500D01*
G01X420658Y29583D02*
X420908Y29833D01*
X421200Y29958D01*
X421533Y30000D01*
X421950Y29917D01*
X422242Y29708D01*
X422325Y29458D01*
X422283Y29208D01*
X422117Y29000D01*
X421283Y28583D01*
X420908Y28292D01*
X420658Y27875D01*
X420575Y27500D01*
X422325D01*
G01X425050D02*
Y30000D01*
X423508Y28208D01*
X425592D01*
G01X426858Y28542D02*
X427150Y28833D01*
X427400Y29000D01*
X427733Y29083D01*
X428025Y29000D01*
X428233Y28833D01*
X428400Y28583D01*
X428442Y28292D01*
X428400Y28042D01*
X428233Y27792D01*
X427983Y27583D01*
X427692Y27500D01*
X427358Y27583D01*
X427067Y27833D01*
X426900Y28208D01*
X426858Y28625D01*
X426942Y29167D01*
X427067Y29458D01*
X427275Y29750D01*
X427567Y29958D01*
X427858Y30000D01*
X428150Y29917D01*
X428358Y29708D01*
G01X417517Y23500D02*
Y26000D01*
X418558D01*
X418892Y25875D01*
X419100Y25708D01*
X419183Y25375D01*
X419100Y25042D01*
X418850Y24833D01*
X418558Y24708D01*
X417517D01*
G01X418558D02*
X419183Y23500D01*
G01X420658Y25583D02*
X420908Y25833D01*
X421200Y25958D01*
X421533Y26000D01*
X421950Y25917D01*
X422242Y25708D01*
X422325Y25458D01*
X422283Y25208D01*
X422117Y25000D01*
X421283Y24583D01*
X420908Y24292D01*
X420658Y23875D01*
X420575Y23500D01*
X422325D01*
G01X425050D02*
Y26000D01*
X423508Y24208D01*
X425592D01*
G01X427567Y23500D02*
X427650Y24042D01*
X427775Y24500D01*
X427942Y24917D01*
X428150Y25375D01*
X428483Y26000D01*
X426817D01*
G01X419767Y39792D02*
X419517Y39917D01*
X419225Y40000D01*
X418892D01*
X418517Y39875D01*
X418225Y39667D01*
X418017Y39417D01*
X417850Y39000D01*
X417808Y38625D01*
X417892Y38250D01*
X418017Y38000D01*
X418267Y37750D01*
X418558Y37583D01*
X418850Y37500D01*
X419142D01*
X419433Y37583D01*
X419683Y37708D01*
X419892Y37875D01*
G01X421950Y37500D02*
Y40000D01*
X421450Y39500D01*
G01Y37500D02*
X422450D01*
G01X425050D02*
Y40000D01*
X424550Y39500D01*
G01Y37500D02*
X425550D01*
G01X427233Y37875D02*
X427483Y37667D01*
X427775Y37542D01*
X428150Y37500D01*
X428525Y37583D01*
X428817Y37750D01*
X429025Y38042D01*
X429067Y38375D01*
X428983Y38708D01*
X428775Y38917D01*
X428483Y39083D01*
X428192Y39125D01*
X427900Y39083D01*
X427525Y38917D01*
X427650Y40000D01*
X428775D01*
G01X418350Y34500D02*
Y32000D01*
G01X417392Y34500D02*
X419308D01*
G01X420617Y32000D02*
Y34500D01*
X421617D01*
X421950Y34375D01*
X422200Y34083D01*
X422283Y33750D01*
X422200Y33417D01*
X421992Y33167D01*
X421617Y33042D01*
X420617D01*
G01X424550Y32000D02*
Y34500D01*
X424050Y34000D01*
G01Y32000D02*
X425050D01*
G01X426942Y32292D02*
X427233Y32083D01*
X427567Y32000D01*
X427900Y32083D01*
X428192Y32333D01*
X428400Y32708D01*
X428483Y33083D01*
Y33542D01*
X428400Y33917D01*
X428192Y34250D01*
X427942Y34417D01*
X427650Y34500D01*
X427317Y34417D01*
X427067Y34250D01*
X426900Y34000D01*
X426817Y33667D01*
X426900Y33375D01*
X427108Y33083D01*
X427358Y32917D01*
X427650Y32875D01*
X427983Y32958D01*
X428233Y33167D01*
X428483Y33542D01*
G01X416017Y43000D02*
Y45500D01*
X417058D01*
X417392Y45375D01*
X417600Y45208D01*
X417683Y44875D01*
X417600Y44542D01*
X417350Y44333D01*
X417058Y44208D01*
X416017D01*
G01X417058D02*
X417683Y43000D01*
G01X419158Y45083D02*
X419408Y45333D01*
X419700Y45458D01*
X420033Y45500D01*
X420450Y45417D01*
X420742Y45208D01*
X420825Y44958D01*
X420783Y44708D01*
X420617Y44500D01*
X419783Y44083D01*
X419408Y43792D01*
X419158Y43375D01*
X419075Y43000D01*
X420825D01*
G01X423550D02*
Y45500D01*
X422008Y43708D01*
X424092D01*
G01X426150Y43000D02*
Y45500D01*
X425650Y45000D01*
G01Y43000D02*
X426650D01*
G01X408000Y49000D02*
X411500D01*
Y48500D01*
G01X415708Y50317D02*
X415583Y50067D01*
X415500Y49775D01*
Y49442D01*
X415625Y49067D01*
X415833Y48775D01*
X416083Y48567D01*
X416500Y48400D01*
X416875Y48358D01*
X417250Y48442D01*
X417500Y48567D01*
X417750Y48817D01*
X417917Y49108D01*
X418000Y49400D01*
Y49692D01*
X417917Y49983D01*
X417792Y50233D01*
X417625Y50442D01*
G01X415917Y51708D02*
X415667Y51958D01*
X415542Y52250D01*
X415500Y52583D01*
X415583Y53000D01*
X415792Y53292D01*
X416042Y53375D01*
X416292Y53333D01*
X416500Y53167D01*
X416917Y52333D01*
X417208Y51958D01*
X417625Y51708D01*
X418000Y51625D01*
Y53375D01*
G01Y55600D02*
X417958Y55892D01*
X417833Y56225D01*
X417625Y56433D01*
X417333Y56517D01*
X417042Y56433D01*
X416792Y56183D01*
X416667Y55808D01*
Y55392D01*
X416583Y55142D01*
X416375Y54933D01*
X416083Y54850D01*
X415792Y54975D01*
X415583Y55267D01*
X415500Y55600D01*
X415583Y55933D01*
X415792Y56225D01*
X416083Y56350D01*
X416375Y56267D01*
X416583Y56058D01*
X416667Y55808D01*
Y55392D01*
X416792Y55017D01*
X417042Y54767D01*
X417333Y54683D01*
X417625Y54767D01*
X417833Y54975D01*
X417958Y55308D01*
X418000Y55600D01*
G01X407208Y53267D02*
X407083Y53017D01*
X407000Y52725D01*
Y52392D01*
X407125Y52017D01*
X407333Y51725D01*
X407583Y51517D01*
X408000Y51350D01*
X408375Y51308D01*
X408750Y51392D01*
X409000Y51517D01*
X409250Y51767D01*
X409417Y52058D01*
X409500Y52350D01*
Y52642D01*
X409417Y52933D01*
X409292Y53183D01*
X409125Y53392D01*
G01X409000Y54533D02*
X409292Y54783D01*
X409458Y55117D01*
X409500Y55492D01*
X409458Y55825D01*
X409250Y56158D01*
X409000Y56367D01*
X408750Y56408D01*
X408458Y56325D01*
X408250Y56033D01*
X408167Y55742D01*
Y55367D01*
G01Y55742D02*
X408042Y55992D01*
X407833Y56200D01*
X407583Y56283D01*
X407333Y56200D01*
X407125Y55992D01*
X407000Y55617D01*
X407042Y55242D01*
X407208Y54867D01*
G01X409500Y58550D02*
X407000D01*
X407500Y58050D01*
G01X409500D02*
Y59050D01*
G01Y62150D02*
X407000D01*
X408792Y60608D01*
Y62692D01*
G01X411517Y59000D02*
Y61500D01*
X412558D01*
X412892Y61375D01*
X413100Y61208D01*
X413183Y60875D01*
X413100Y60542D01*
X412850Y60333D01*
X412558Y60208D01*
X411517D01*
G01X412558D02*
X413183Y59000D01*
G01X414658Y61083D02*
X414908Y61333D01*
X415200Y61458D01*
X415533Y61500D01*
X415950Y61417D01*
X416242Y61208D01*
X416325Y60958D01*
X416283Y60708D01*
X416117Y60500D01*
X415283Y60083D01*
X414908Y59792D01*
X414658Y59375D01*
X414575Y59000D01*
X416325D01*
G01X417633Y59375D02*
X417883Y59167D01*
X418175Y59042D01*
X418550Y59000D01*
X418925Y59083D01*
X419217Y59250D01*
X419425Y59542D01*
X419467Y59875D01*
X419383Y60208D01*
X419175Y60417D01*
X418883Y60583D01*
X418592Y60625D01*
X418300Y60583D01*
X417925Y60417D01*
X418050Y61500D01*
X419175D01*
G01X421650Y59000D02*
Y61500D01*
X421150Y61000D01*
G01Y59000D02*
X422150D01*
G01X409500Y70850D02*
X412000D01*
G01X409500Y69892D02*
Y71808D01*
G01X412000Y73117D02*
X409500D01*
Y74117D01*
X409625Y74450D01*
X409917Y74700D01*
X410250Y74783D01*
X410583Y74700D01*
X410833Y74492D01*
X410958Y74117D01*
Y73117D01*
G01X409917Y76258D02*
X409667Y76508D01*
X409542Y76800D01*
X409500Y77133D01*
X409583Y77550D01*
X409792Y77842D01*
X410042Y77925D01*
X410292Y77883D01*
X410500Y77717D01*
X410917Y76883D01*
X411208Y76508D01*
X411625Y76258D01*
X412000Y76175D01*
Y77925D01*
G01X409500Y80150D02*
X409583Y79817D01*
X409792Y79567D01*
X410042Y79400D01*
X410375Y79275D01*
X410750Y79233D01*
X411125Y79275D01*
X411458Y79400D01*
X411708Y79567D01*
X411917Y79817D01*
X412000Y80150D01*
X411917Y80483D01*
X411708Y80733D01*
X411458Y80900D01*
X411125Y81025D01*
X410750Y81067D01*
X410375Y81025D01*
X410042Y80900D01*
X409792Y80733D01*
X409583Y80483D01*
X409500Y80150D01*
G01X417000Y68567D02*
X414500D01*
Y69608D01*
X414625Y69942D01*
X414792Y70150D01*
X415125Y70233D01*
X415458Y70150D01*
X415667Y69900D01*
X415792Y69608D01*
Y68567D01*
G01Y69608D02*
X417000Y70233D01*
G01X415958Y71708D02*
X415667Y72000D01*
X415500Y72250D01*
X415417Y72583D01*
X415500Y72875D01*
X415667Y73083D01*
X415917Y73250D01*
X416208Y73292D01*
X416458Y73250D01*
X416708Y73083D01*
X416917Y72833D01*
X417000Y72542D01*
X416917Y72208D01*
X416667Y71917D01*
X416292Y71750D01*
X415875Y71708D01*
X415333Y71792D01*
X415042Y71917D01*
X414750Y72125D01*
X414542Y72417D01*
X414500Y72708D01*
X414583Y73000D01*
X414792Y73208D01*
G01X416708Y74892D02*
X416917Y75183D01*
X417000Y75517D01*
X416917Y75850D01*
X416667Y76142D01*
X416292Y76350D01*
X415917Y76433D01*
X415458D01*
X415083Y76350D01*
X414750Y76142D01*
X414583Y75892D01*
X414500Y75600D01*
X414583Y75267D01*
X414750Y75017D01*
X415000Y74850D01*
X415333Y74767D01*
X415625Y74850D01*
X415917Y75058D01*
X416083Y75308D01*
X416125Y75600D01*
X416042Y75933D01*
X415833Y76183D01*
X415458Y76433D01*
G01X407500Y65017D02*
X405000D01*
Y66058D01*
X405125Y66392D01*
X405292Y66600D01*
X405625Y66683D01*
X405958Y66600D01*
X406167Y66350D01*
X406292Y66058D01*
Y65017D01*
G01Y66058D02*
X407500Y66683D01*
G01X405417Y68158D02*
X405167Y68408D01*
X405042Y68700D01*
X405000Y69033D01*
X405083Y69450D01*
X405292Y69742D01*
X405542Y69825D01*
X405792Y69783D01*
X406000Y69617D01*
X406417Y68783D01*
X406708Y68408D01*
X407125Y68158D01*
X407500Y68075D01*
Y69825D01*
G01Y72550D02*
X405000D01*
X406792Y71008D01*
Y73092D01*
G01X407208Y74442D02*
X407417Y74733D01*
X407500Y75067D01*
X407417Y75400D01*
X407167Y75692D01*
X406792Y75900D01*
X406417Y75983D01*
X405958D01*
X405583Y75900D01*
X405250Y75692D01*
X405083Y75442D01*
X405000Y75150D01*
X405083Y74817D01*
X405250Y74567D01*
X405500Y74400D01*
X405833Y74317D01*
X406125Y74400D01*
X406417Y74608D01*
X406583Y74858D01*
X406625Y75150D01*
X406542Y75483D01*
X406333Y75733D01*
X405958Y75983D01*
G01X414017Y87500D02*
Y90000D01*
X415058D01*
X415392Y89875D01*
X415600Y89708D01*
X415683Y89375D01*
X415600Y89042D01*
X415350Y88833D01*
X415058Y88708D01*
X414017D01*
G01X415058D02*
X415683Y87500D01*
G01X417950D02*
Y90000D01*
X417450Y89500D01*
G01Y87500D02*
X418450D01*
G01X420258Y88542D02*
X420550Y88833D01*
X420800Y89000D01*
X421133Y89083D01*
X421425Y89000D01*
X421633Y88833D01*
X421800Y88583D01*
X421842Y88292D01*
X421800Y88042D01*
X421633Y87792D01*
X421383Y87583D01*
X421092Y87500D01*
X420758Y87583D01*
X420467Y87833D01*
X420300Y88208D01*
X420258Y88625D01*
X420342Y89167D01*
X420467Y89458D01*
X420675Y89750D01*
X420967Y89958D01*
X421258Y90000D01*
X421550Y89917D01*
X421758Y89708D01*
G01X424067Y87500D02*
X424150Y88042D01*
X424275Y88500D01*
X424442Y88917D01*
X424650Y89375D01*
X424983Y90000D01*
X423317D01*
G01X414017Y91500D02*
Y94000D01*
X415058D01*
X415392Y93875D01*
X415600Y93708D01*
X415683Y93375D01*
X415600Y93042D01*
X415350Y92833D01*
X415058Y92708D01*
X414017D01*
G01X415058D02*
X415683Y91500D01*
G01X417950D02*
Y94000D01*
X417450Y93500D01*
G01Y91500D02*
X418450D01*
G01X420258Y92542D02*
X420550Y92833D01*
X420800Y93000D01*
X421133Y93083D01*
X421425Y93000D01*
X421633Y92833D01*
X421800Y92583D01*
X421842Y92292D01*
X421800Y92042D01*
X421633Y91792D01*
X421383Y91583D01*
X421092Y91500D01*
X420758Y91583D01*
X420467Y91833D01*
X420300Y92208D01*
X420258Y92625D01*
X420342Y93167D01*
X420467Y93458D01*
X420675Y93750D01*
X420967Y93958D01*
X421258Y94000D01*
X421550Y93917D01*
X421758Y93708D01*
G01X424150Y94000D02*
X423817Y93917D01*
X423567Y93708D01*
X423400Y93458D01*
X423275Y93125D01*
X423233Y92750D01*
X423275Y92375D01*
X423400Y92042D01*
X423567Y91792D01*
X423817Y91583D01*
X424150Y91500D01*
X424483Y91583D01*
X424733Y91792D01*
X424900Y92042D01*
X425025Y92375D01*
X425067Y92750D01*
X425025Y93125D01*
X424900Y93458D01*
X424733Y93708D01*
X424483Y93917D01*
X424150Y94000D01*
G01X411517Y95500D02*
Y98000D01*
X412558D01*
X412892Y97875D01*
X413100Y97708D01*
X413183Y97375D01*
X413100Y97042D01*
X412850Y96833D01*
X412558Y96708D01*
X411517D01*
G01X412558D02*
X413183Y95500D01*
G01X415450D02*
Y98000D01*
X414950Y97500D01*
G01Y95500D02*
X415950D01*
G01X418467D02*
X418550Y96042D01*
X418675Y96500D01*
X418842Y96917D01*
X419050Y97375D01*
X419383Y98000D01*
X417717D01*
G01X421650D02*
X421317Y97917D01*
X421067Y97708D01*
X420900Y97458D01*
X420775Y97125D01*
X420733Y96750D01*
X420775Y96375D01*
X420900Y96042D01*
X421067Y95792D01*
X421317Y95583D01*
X421650Y95500D01*
X421983Y95583D01*
X422233Y95792D01*
X422400Y96042D01*
X422525Y96375D01*
X422567Y96750D01*
X422525Y97125D01*
X422400Y97458D01*
X422233Y97708D01*
X421983Y97917D01*
X421650Y98000D01*
G01X420500Y213717D02*
X418000D01*
Y214717D01*
X418125Y215050D01*
X418417Y215300D01*
X418750Y215383D01*
X419083Y215300D01*
X419333Y215092D01*
X419458Y214717D01*
Y213717D01*
G01X418208Y218567D02*
X418083Y218317D01*
X418000Y218025D01*
Y217692D01*
X418125Y217317D01*
X418333Y217025D01*
X418583Y216817D01*
X419000Y216650D01*
X419375Y216608D01*
X419750Y216692D01*
X420000Y216817D01*
X420250Y217067D01*
X420417Y217358D01*
X420500Y217650D01*
Y217942D01*
X420417Y218233D01*
X420292Y218483D01*
X420125Y218692D01*
G01Y219833D02*
X420333Y220083D01*
X420458Y220375D01*
X420500Y220750D01*
X420417Y221125D01*
X420250Y221417D01*
X419958Y221625D01*
X419625Y221667D01*
X419292Y221583D01*
X419083Y221375D01*
X418917Y221083D01*
X418875Y220792D01*
X418917Y220500D01*
X419083Y220125D01*
X418000Y220250D01*
Y221375D01*
G01X420500Y223850D02*
X420458Y224142D01*
X420333Y224475D01*
X420125Y224683D01*
X419833Y224767D01*
X419542Y224683D01*
X419292Y224433D01*
X419167Y224058D01*
Y223642D01*
X419083Y223392D01*
X418875Y223183D01*
X418583Y223100D01*
X418292Y223225D01*
X418083Y223517D01*
X418000Y223850D01*
X418083Y224183D01*
X418292Y224475D01*
X418583Y224600D01*
X418875Y224517D01*
X419083Y224308D01*
X419167Y224058D01*
Y223642D01*
X419292Y223267D01*
X419542Y223017D01*
X419833Y222933D01*
X420125Y223017D01*
X420333Y223225D01*
X420458Y223558D01*
X420500Y223850D01*
G01X410300Y227617D02*
X407800D01*
Y228617D01*
X407925Y228950D01*
X408217Y229200D01*
X408550Y229283D01*
X408883Y229200D01*
X409133Y228992D01*
X409258Y228617D01*
Y227617D01*
G01X408008Y232467D02*
X407883Y232217D01*
X407800Y231925D01*
Y231592D01*
X407925Y231217D01*
X408133Y230925D01*
X408383Y230717D01*
X408800Y230550D01*
X409175Y230508D01*
X409550Y230592D01*
X409800Y230717D01*
X410050Y230967D01*
X410217Y231258D01*
X410300Y231550D01*
Y231842D01*
X410217Y232133D01*
X410092Y232383D01*
X409925Y232592D01*
G01X409258Y233858D02*
X408967Y234150D01*
X408800Y234400D01*
X408717Y234733D01*
X408800Y235025D01*
X408967Y235233D01*
X409217Y235400D01*
X409508Y235442D01*
X409758Y235400D01*
X410008Y235233D01*
X410217Y234983D01*
X410300Y234692D01*
X410217Y234358D01*
X409967Y234067D01*
X409592Y233900D01*
X409175Y233858D01*
X408633Y233942D01*
X408342Y234067D01*
X408050Y234275D01*
X407842Y234567D01*
X407800Y234858D01*
X407883Y235150D01*
X408092Y235358D01*
G01X410300Y237750D02*
X407800D01*
X408300Y237250D01*
G01X410300D02*
Y238250D01*
G01X411500Y214517D02*
X409000D01*
Y215517D01*
X409125Y215850D01*
X409417Y216100D01*
X409750Y216183D01*
X410083Y216100D01*
X410333Y215892D01*
X410458Y215517D01*
Y214517D01*
G01X411500Y217617D02*
X409000D01*
Y218658D01*
X409125Y218992D01*
X409292Y219200D01*
X409625Y219283D01*
X409958Y219200D01*
X410167Y218950D01*
X410292Y218658D01*
Y217617D01*
G01Y218658D02*
X411500Y219283D01*
G01Y221550D02*
X411458Y221842D01*
X411333Y222175D01*
X411125Y222383D01*
X410833Y222467D01*
X410542Y222383D01*
X410292Y222133D01*
X410167Y221758D01*
Y221342D01*
X410083Y221092D01*
X409875Y220883D01*
X409583Y220800D01*
X409292Y220925D01*
X409083Y221217D01*
X409000Y221550D01*
X409083Y221883D01*
X409292Y222175D01*
X409583Y222300D01*
X409875Y222217D01*
X410083Y222008D01*
X410167Y221758D01*
Y221342D01*
X410292Y220967D01*
X410542Y220717D01*
X410833Y220633D01*
X411125Y220717D01*
X411333Y220925D01*
X411458Y221258D01*
X411500Y221550D01*
G01X411000Y223733D02*
X411292Y223983D01*
X411458Y224317D01*
X411500Y224692D01*
X411458Y225025D01*
X411250Y225358D01*
X411000Y225567D01*
X410750Y225608D01*
X410458Y225525D01*
X410250Y225233D01*
X410167Y224942D01*
Y224567D01*
G01Y224942D02*
X410042Y225192D01*
X409833Y225400D01*
X409583Y225483D01*
X409333Y225400D01*
X409125Y225192D01*
X409000Y224817D01*
X409042Y224442D01*
X409208Y224067D01*
G01X407000Y214517D02*
X404500D01*
Y215517D01*
X404625Y215850D01*
X404917Y216100D01*
X405250Y216183D01*
X405583Y216100D01*
X405833Y215892D01*
X405958Y215517D01*
Y214517D01*
G01X407000Y217617D02*
X404500D01*
Y218658D01*
X404625Y218992D01*
X404792Y219200D01*
X405125Y219283D01*
X405458Y219200D01*
X405667Y218950D01*
X405792Y218658D01*
Y217617D01*
G01Y218658D02*
X407000Y219283D01*
G01Y221550D02*
X406958Y221842D01*
X406833Y222175D01*
X406625Y222383D01*
X406333Y222467D01*
X406042Y222383D01*
X405792Y222133D01*
X405667Y221758D01*
Y221342D01*
X405583Y221092D01*
X405375Y220883D01*
X405083Y220800D01*
X404792Y220925D01*
X404583Y221217D01*
X404500Y221550D01*
X404583Y221883D01*
X404792Y222175D01*
X405083Y222300D01*
X405375Y222217D01*
X405583Y222008D01*
X405667Y221758D01*
Y221342D01*
X405792Y220967D01*
X406042Y220717D01*
X406333Y220633D01*
X406625Y220717D01*
X406833Y220925D01*
X406958Y221258D01*
X407000Y221550D01*
G01X404917Y223858D02*
X404667Y224108D01*
X404542Y224400D01*
X404500Y224733D01*
X404583Y225150D01*
X404792Y225442D01*
X405042Y225525D01*
X405292Y225483D01*
X405500Y225317D01*
X405917Y224483D01*
X406208Y224108D01*
X406625Y223858D01*
X407000Y223775D01*
Y225525D01*
G01X416300Y213917D02*
X413800D01*
Y214917D01*
X413925Y215250D01*
X414217Y215500D01*
X414550Y215583D01*
X414883Y215500D01*
X415133Y215292D01*
X415258Y214917D01*
Y213917D01*
G01X416300Y217017D02*
X413800D01*
Y218058D01*
X413925Y218392D01*
X414092Y218600D01*
X414425Y218683D01*
X414758Y218600D01*
X414967Y218350D01*
X415092Y218058D01*
Y217017D01*
G01Y218058D02*
X416300Y218683D01*
G01Y220867D02*
X415758Y220950D01*
X415300Y221075D01*
X414883Y221242D01*
X414425Y221450D01*
X413800Y221783D01*
Y220117D01*
G01X416300Y223967D02*
X415758Y224050D01*
X415300Y224175D01*
X414883Y224342D01*
X414425Y224550D01*
X413800Y224883D01*
Y223217D01*
G01X415800Y227617D02*
X413300D01*
Y228617D01*
X413425Y228950D01*
X413717Y229200D01*
X414050Y229283D01*
X414383Y229200D01*
X414633Y228992D01*
X414758Y228617D01*
Y227617D01*
G01X415800Y230717D02*
X413300D01*
Y231758D01*
X413425Y232092D01*
X413592Y232300D01*
X413925Y232383D01*
X414258Y232300D01*
X414467Y232050D01*
X414592Y231758D01*
Y230717D01*
G01Y231758D02*
X415800Y232383D01*
G01X414758Y233858D02*
X414467Y234150D01*
X414300Y234400D01*
X414217Y234733D01*
X414300Y235025D01*
X414467Y235233D01*
X414717Y235400D01*
X415008Y235442D01*
X415258Y235400D01*
X415508Y235233D01*
X415717Y234983D01*
X415800Y234692D01*
X415717Y234358D01*
X415467Y234067D01*
X415092Y233900D01*
X414675Y233858D01*
X414133Y233942D01*
X413842Y234067D01*
X413550Y234275D01*
X413342Y234567D01*
X413300Y234858D01*
X413383Y235150D01*
X413592Y235358D01*
G01X415508Y237042D02*
X415717Y237333D01*
X415800Y237667D01*
X415717Y238000D01*
X415467Y238292D01*
X415092Y238500D01*
X414717Y238583D01*
X414258D01*
X413883Y238500D01*
X413550Y238292D01*
X413383Y238042D01*
X413300Y237750D01*
X413383Y237417D01*
X413550Y237167D01*
X413800Y237000D01*
X414133Y236917D01*
X414425Y237000D01*
X414717Y237208D01*
X414883Y237458D01*
X414925Y237750D01*
X414842Y238083D01*
X414633Y238333D01*
X414258Y238583D01*
G01X416067Y259233D02*
X416600Y259583D01*
X417000Y260167D01*
X417267Y260983D01*
X417000Y261683D01*
X416467Y262150D01*
X415533Y262500D01*
X411933D01*
Y255500D01*
X416333D01*
X417267Y255967D01*
X417800Y256667D01*
X418067Y257483D01*
X417800Y258300D01*
X417000Y259000D01*
X416067Y259233D01*
X411933D01*
G01X409000Y249967D02*
X406500D01*
Y250967D01*
X406625Y251300D01*
X406917Y251550D01*
X407250Y251633D01*
X407583Y251550D01*
X407833Y251342D01*
X407958Y250967D01*
Y249967D01*
G01X409000Y253067D02*
X406500D01*
Y254108D01*
X406625Y254442D01*
X406792Y254650D01*
X407125Y254733D01*
X407458Y254650D01*
X407667Y254400D01*
X407792Y254108D01*
Y253067D01*
G01Y254108D02*
X409000Y254733D01*
G01Y257000D02*
X406500D01*
X407000Y256500D01*
G01X409000D02*
Y257500D01*
G01X406500Y260100D02*
X406583Y259767D01*
X406792Y259517D01*
X407042Y259350D01*
X407375Y259225D01*
X407750Y259183D01*
X408125Y259225D01*
X408458Y259350D01*
X408708Y259517D01*
X408917Y259767D01*
X409000Y260100D01*
X408917Y260433D01*
X408708Y260683D01*
X408458Y260850D01*
X408125Y260975D01*
X407750Y261017D01*
X407375Y260975D01*
X407042Y260850D01*
X406792Y260683D01*
X406583Y260433D01*
X406500Y260100D01*
G01Y263200D02*
X406583Y262867D01*
X406792Y262617D01*
X407042Y262450D01*
X407375Y262325D01*
X407750Y262283D01*
X408125Y262325D01*
X408458Y262450D01*
X408708Y262617D01*
X408917Y262867D01*
X409000Y263200D01*
X408917Y263533D01*
X408708Y263783D01*
X408458Y263950D01*
X408125Y264075D01*
X407750Y264117D01*
X407375Y264075D01*
X407042Y263950D01*
X406792Y263783D01*
X406583Y263533D01*
X406500Y263200D01*
G01X413000Y265967D02*
X410500D01*
Y266967D01*
X410625Y267300D01*
X410917Y267550D01*
X411250Y267633D01*
X411583Y267550D01*
X411833Y267342D01*
X411958Y266967D01*
Y265967D01*
G01X410708Y270817D02*
X410583Y270567D01*
X410500Y270275D01*
Y269942D01*
X410625Y269567D01*
X410833Y269275D01*
X411083Y269067D01*
X411500Y268900D01*
X411875Y268858D01*
X412250Y268942D01*
X412500Y269067D01*
X412750Y269317D01*
X412917Y269608D01*
X413000Y269900D01*
Y270192D01*
X412917Y270483D01*
X412792Y270733D01*
X412625Y270942D01*
G01X413000Y273000D02*
X410500D01*
X411000Y272500D01*
G01X413000D02*
Y273500D01*
G01Y276017D02*
X412458Y276100D01*
X412000Y276225D01*
X411583Y276392D01*
X411125Y276600D01*
X410500Y276933D01*
Y275267D01*
G01X412500Y278283D02*
X412792Y278533D01*
X412958Y278867D01*
X413000Y279242D01*
X412958Y279575D01*
X412750Y279908D01*
X412500Y280117D01*
X412250Y280158D01*
X411958Y280075D01*
X411750Y279783D01*
X411667Y279492D01*
Y279117D01*
G01Y279492D02*
X411542Y279742D01*
X411333Y279950D01*
X411083Y280033D01*
X410833Y279950D01*
X410625Y279742D01*
X410500Y279367D01*
X410542Y278992D01*
X410708Y278617D01*
G01X409000Y265967D02*
X406500D01*
Y266967D01*
X406625Y267300D01*
X406917Y267550D01*
X407250Y267633D01*
X407583Y267550D01*
X407833Y267342D01*
X407958Y266967D01*
Y265967D01*
G01X409000Y269067D02*
X406500D01*
Y270108D01*
X406625Y270442D01*
X406792Y270650D01*
X407125Y270733D01*
X407458Y270650D01*
X407667Y270400D01*
X407792Y270108D01*
Y269067D01*
G01Y270108D02*
X409000Y270733D01*
G01Y273000D02*
X406500D01*
X407000Y272500D01*
G01X409000D02*
Y273500D01*
G01X408708Y275392D02*
X408917Y275683D01*
X409000Y276017D01*
X408917Y276350D01*
X408667Y276642D01*
X408292Y276850D01*
X407917Y276933D01*
X407458D01*
X407083Y276850D01*
X406750Y276642D01*
X406583Y276392D01*
X406500Y276100D01*
X406583Y275767D01*
X406750Y275517D01*
X407000Y275350D01*
X407333Y275267D01*
X407625Y275350D01*
X407917Y275558D01*
X408083Y275808D01*
X408125Y276100D01*
X408042Y276433D01*
X407833Y276683D01*
X407458Y276933D01*
G01X408708Y278492D02*
X408917Y278783D01*
X409000Y279117D01*
X408917Y279450D01*
X408667Y279742D01*
X408292Y279950D01*
X407917Y280033D01*
X407458D01*
X407083Y279950D01*
X406750Y279742D01*
X406583Y279492D01*
X406500Y279200D01*
X406583Y278867D01*
X406750Y278617D01*
X407000Y278450D01*
X407333Y278367D01*
X407625Y278450D01*
X407917Y278658D01*
X408083Y278908D01*
X408125Y279200D01*
X408042Y279533D01*
X407833Y279783D01*
X407458Y280033D01*
G01X417000Y266017D02*
X414500D01*
Y267058D01*
X414625Y267392D01*
X414792Y267600D01*
X415125Y267683D01*
X415458Y267600D01*
X415667Y267350D01*
X415792Y267058D01*
Y266017D01*
G01Y267058D02*
X417000Y267683D01*
G01X416500Y269033D02*
X416792Y269283D01*
X416958Y269617D01*
X417000Y269992D01*
X416958Y270325D01*
X416750Y270658D01*
X416500Y270867D01*
X416250Y270908D01*
X415958Y270825D01*
X415750Y270533D01*
X415667Y270242D01*
Y269867D01*
G01Y270242D02*
X415542Y270492D01*
X415333Y270700D01*
X415083Y270783D01*
X414833Y270700D01*
X414625Y270492D01*
X414500Y270117D01*
X414542Y269742D01*
X414708Y269367D01*
G01X417000Y273050D02*
X414500D01*
X415000Y272550D01*
G01X417000D02*
Y273550D01*
G01X416708Y275442D02*
X416917Y275733D01*
X417000Y276067D01*
X416917Y276400D01*
X416667Y276692D01*
X416292Y276900D01*
X415917Y276983D01*
X415458D01*
X415083Y276900D01*
X414750Y276692D01*
X414583Y276442D01*
X414500Y276150D01*
X414583Y275817D01*
X414750Y275567D01*
X415000Y275400D01*
X415333Y275317D01*
X415625Y275400D01*
X415917Y275608D01*
X416083Y275858D01*
X416125Y276150D01*
X416042Y276483D01*
X415833Y276733D01*
X415458Y276983D01*
G01X406467Y286000D02*
Y288500D01*
X407467D01*
X407800Y288375D01*
X408050Y288083D01*
X408133Y287750D01*
X408050Y287417D01*
X407842Y287167D01*
X407467Y287042D01*
X406467D01*
G01X411317Y288292D02*
X411067Y288417D01*
X410775Y288500D01*
X410442D01*
X410067Y288375D01*
X409775Y288167D01*
X409567Y287917D01*
X409400Y287500D01*
X409358Y287125D01*
X409442Y286750D01*
X409567Y286500D01*
X409817Y286250D01*
X410108Y286083D01*
X410400Y286000D01*
X410692D01*
X410983Y286083D01*
X411233Y286208D01*
X411442Y286375D01*
G01X413500Y286000D02*
Y288500D01*
X413000Y288000D01*
G01Y286000D02*
X414000D01*
G01X416600D02*
X416892Y286042D01*
X417225Y286167D01*
X417433Y286375D01*
X417517Y286667D01*
X417433Y286958D01*
X417183Y287208D01*
X416808Y287333D01*
X416392D01*
X416142Y287417D01*
X415933Y287625D01*
X415850Y287917D01*
X415975Y288208D01*
X416267Y288417D01*
X416600Y288500D01*
X416933Y288417D01*
X417225Y288208D01*
X417350Y287917D01*
X417267Y287625D01*
X417058Y287417D01*
X416808Y287333D01*
X416392D01*
X416017Y287208D01*
X415767Y286958D01*
X415683Y286667D01*
X415767Y286375D01*
X415975Y286167D01*
X416308Y286042D01*
X416600Y286000D01*
G01X419700D02*
Y288500D01*
X419200Y288000D01*
G01Y286000D02*
X420200D01*
G01X406517Y282000D02*
Y284500D01*
X407517D01*
X407850Y284375D01*
X408100Y284083D01*
X408183Y283750D01*
X408100Y283417D01*
X407892Y283167D01*
X407517Y283042D01*
X406517D01*
G01X409533Y284500D02*
Y282708D01*
X409700Y282333D01*
X410033Y282083D01*
X410450Y282000D01*
X410867Y282083D01*
X411200Y282333D01*
X411367Y282708D01*
Y284500D01*
G01X413550Y282000D02*
Y284500D01*
X413050Y284000D01*
G01Y282000D02*
X414050D01*
G01X415733Y282375D02*
X415983Y282167D01*
X416275Y282042D01*
X416650Y282000D01*
X417025Y282083D01*
X417317Y282250D01*
X417525Y282542D01*
X417567Y282875D01*
X417483Y283208D01*
X417275Y283417D01*
X416983Y283583D01*
X416692Y283625D01*
X416400Y283583D01*
X416025Y283417D01*
X416150Y284500D01*
X417275D01*
G01X432500Y5017D02*
X430000D01*
Y6058D01*
X430125Y6392D01*
X430292Y6600D01*
X430625Y6683D01*
X430958Y6600D01*
X431167Y6350D01*
X431292Y6058D01*
Y5017D01*
G01Y6058D02*
X432500Y6683D01*
G01X432000Y8033D02*
X432292Y8283D01*
X432458Y8617D01*
X432500Y8992D01*
X432458Y9325D01*
X432250Y9658D01*
X432000Y9867D01*
X431750Y9908D01*
X431458Y9825D01*
X431250Y9533D01*
X431167Y9242D01*
Y8867D01*
G01Y9242D02*
X431042Y9492D01*
X430833Y9700D01*
X430583Y9783D01*
X430333Y9700D01*
X430125Y9492D01*
X430000Y9117D01*
X430042Y8742D01*
X430208Y8367D01*
G01X430417Y11258D02*
X430167Y11508D01*
X430042Y11800D01*
X430000Y12133D01*
X430083Y12550D01*
X430292Y12842D01*
X430542Y12925D01*
X430792Y12883D01*
X431000Y12717D01*
X431417Y11883D01*
X431708Y11508D01*
X432125Y11258D01*
X432500Y11175D01*
Y12925D01*
G01X431458Y14358D02*
X431167Y14650D01*
X431000Y14900D01*
X430917Y15233D01*
X431000Y15525D01*
X431167Y15733D01*
X431417Y15900D01*
X431708Y15942D01*
X431958Y15900D01*
X432208Y15733D01*
X432417Y15483D01*
X432500Y15192D01*
X432417Y14858D01*
X432167Y14567D01*
X431792Y14400D01*
X431375Y14358D01*
X430833Y14442D01*
X430542Y14567D01*
X430250Y14775D01*
X430042Y15067D01*
X430000Y15358D01*
X430083Y15650D01*
X430292Y15858D01*
G01X424500Y6517D02*
X422000D01*
Y7558D01*
X422125Y7892D01*
X422292Y8100D01*
X422625Y8183D01*
X422958Y8100D01*
X423167Y7850D01*
X423292Y7558D01*
Y6517D01*
G01Y7558D02*
X424500Y8183D01*
G01X424000Y9533D02*
X424292Y9783D01*
X424458Y10117D01*
X424500Y10492D01*
X424458Y10825D01*
X424250Y11158D01*
X424000Y11367D01*
X423750Y11408D01*
X423458Y11325D01*
X423250Y11033D01*
X423167Y10742D01*
Y10367D01*
G01Y10742D02*
X423042Y10992D01*
X422833Y11200D01*
X422583Y11283D01*
X422333Y11200D01*
X422125Y10992D01*
X422000Y10617D01*
X422042Y10242D01*
X422208Y9867D01*
G01X424500Y14050D02*
X422000D01*
X423792Y12508D01*
Y14592D01*
G01X424500Y16650D02*
X422000D01*
X422500Y16150D01*
G01X424500D02*
Y17150D01*
G01X428500Y6017D02*
X426000D01*
Y7058D01*
X426125Y7392D01*
X426292Y7600D01*
X426625Y7683D01*
X426958Y7600D01*
X427167Y7350D01*
X427292Y7058D01*
Y6017D01*
G01Y7058D02*
X428500Y7683D01*
G01X428000Y9033D02*
X428292Y9283D01*
X428458Y9617D01*
X428500Y9992D01*
X428458Y10325D01*
X428250Y10658D01*
X428000Y10867D01*
X427750Y10908D01*
X427458Y10825D01*
X427250Y10533D01*
X427167Y10242D01*
Y9867D01*
G01Y10242D02*
X427042Y10492D01*
X426833Y10700D01*
X426583Y10783D01*
X426333Y10700D01*
X426125Y10492D01*
X426000Y10117D01*
X426042Y9742D01*
X426208Y9367D01*
G01X428500Y13550D02*
X426000D01*
X427792Y12008D01*
Y14092D01*
G01X428000Y15233D02*
X428292Y15483D01*
X428458Y15817D01*
X428500Y16192D01*
X428458Y16525D01*
X428250Y16858D01*
X428000Y17067D01*
X427750Y17108D01*
X427458Y17025D01*
X427250Y16733D01*
X427167Y16442D01*
Y16067D01*
G01Y16442D02*
X427042Y16692D01*
X426833Y16900D01*
X426583Y16983D01*
X426333Y16900D01*
X426125Y16692D01*
X426000Y16317D01*
X426042Y15942D01*
X426208Y15567D01*
G01X420267Y21292D02*
X420017Y21417D01*
X419725Y21500D01*
X419392D01*
X419017Y21375D01*
X418725Y21167D01*
X418517Y20917D01*
X418350Y20500D01*
X418308Y20125D01*
X418392Y19750D01*
X418517Y19500D01*
X418767Y19250D01*
X419058Y19083D01*
X419350Y19000D01*
X419642D01*
X419933Y19083D01*
X420183Y19208D01*
X420392Y19375D01*
G01X421658Y21083D02*
X421908Y21333D01*
X422200Y21458D01*
X422533Y21500D01*
X422950Y21417D01*
X423242Y21208D01*
X423325Y20958D01*
X423283Y20708D01*
X423117Y20500D01*
X422283Y20083D01*
X421908Y19792D01*
X421658Y19375D01*
X421575Y19000D01*
X423325D01*
G01X425550Y21500D02*
X425217Y21417D01*
X424967Y21208D01*
X424800Y20958D01*
X424675Y20625D01*
X424633Y20250D01*
X424675Y19875D01*
X424800Y19542D01*
X424967Y19292D01*
X425217Y19083D01*
X425550Y19000D01*
X425883Y19083D01*
X426133Y19292D01*
X426300Y19542D01*
X426425Y19875D01*
X426467Y20250D01*
X426425Y20625D01*
X426300Y20958D01*
X426133Y21208D01*
X425883Y21417D01*
X425550Y21500D01*
G01X427858Y20042D02*
X428150Y20333D01*
X428400Y20500D01*
X428733Y20583D01*
X429025Y20500D01*
X429233Y20333D01*
X429400Y20083D01*
X429442Y19792D01*
X429400Y19542D01*
X429233Y19292D01*
X428983Y19083D01*
X428692Y19000D01*
X428358Y19083D01*
X428067Y19333D01*
X427900Y19708D01*
X427858Y20125D01*
X427942Y20667D01*
X428067Y20958D01*
X428275Y21250D01*
X428567Y21458D01*
X428858Y21500D01*
X429150Y21417D01*
X429358Y21208D01*
G01X430208Y25267D02*
X430083Y25017D01*
X430000Y24725D01*
Y24392D01*
X430125Y24017D01*
X430333Y23725D01*
X430583Y23517D01*
X431000Y23350D01*
X431375Y23308D01*
X431750Y23392D01*
X432000Y23517D01*
X432250Y23767D01*
X432417Y24058D01*
X432500Y24350D01*
Y24642D01*
X432417Y24933D01*
X432292Y25183D01*
X432125Y25392D01*
G01X432000Y26533D02*
X432292Y26783D01*
X432458Y27117D01*
X432500Y27492D01*
X432458Y27825D01*
X432250Y28158D01*
X432000Y28367D01*
X431750Y28408D01*
X431458Y28325D01*
X431250Y28033D01*
X431167Y27742D01*
Y27367D01*
G01Y27742D02*
X431042Y27992D01*
X430833Y28200D01*
X430583Y28283D01*
X430333Y28200D01*
X430125Y27992D01*
X430000Y27617D01*
X430042Y27242D01*
X430208Y26867D01*
G01X432500Y30550D02*
X430000D01*
X430500Y30050D01*
G01X432500D02*
Y31050D01*
G01X430000Y33650D02*
X430083Y33317D01*
X430292Y33067D01*
X430542Y32900D01*
X430875Y32775D01*
X431250Y32733D01*
X431625Y32775D01*
X431958Y32900D01*
X432208Y33067D01*
X432417Y33317D01*
X432500Y33650D01*
X432417Y33983D01*
X432208Y34233D01*
X431958Y34400D01*
X431625Y34525D01*
X431250Y34567D01*
X430875Y34525D01*
X430542Y34400D01*
X430292Y34233D01*
X430083Y33983D01*
X430000Y33650D01*
G01X426500Y51017D02*
X424000D01*
Y52058D01*
X424125Y52392D01*
X424292Y52600D01*
X424625Y52683D01*
X424958Y52600D01*
X425167Y52350D01*
X425292Y52058D01*
Y51017D01*
G01Y52058D02*
X426500Y52683D01*
G01X424417Y54158D02*
X424167Y54408D01*
X424042Y54700D01*
X424000Y55033D01*
X424083Y55450D01*
X424292Y55742D01*
X424542Y55825D01*
X424792Y55783D01*
X425000Y55617D01*
X425417Y54783D01*
X425708Y54408D01*
X426125Y54158D01*
X426500Y54075D01*
Y55825D01*
G01Y58550D02*
X424000D01*
X425792Y57008D01*
Y59092D01*
G01X426125Y60233D02*
X426333Y60483D01*
X426458Y60775D01*
X426500Y61150D01*
X426417Y61525D01*
X426250Y61817D01*
X425958Y62025D01*
X425625Y62067D01*
X425292Y61983D01*
X425083Y61775D01*
X424917Y61483D01*
X424875Y61192D01*
X424917Y60900D01*
X425083Y60525D01*
X424000Y60650D01*
Y61775D01*
G01X428708Y53767D02*
X428583Y53517D01*
X428500Y53225D01*
Y52892D01*
X428625Y52517D01*
X428833Y52225D01*
X429083Y52017D01*
X429500Y51850D01*
X429875Y51808D01*
X430250Y51892D01*
X430500Y52017D01*
X430750Y52267D01*
X430917Y52558D01*
X431000Y52850D01*
Y53142D01*
X430917Y53433D01*
X430792Y53683D01*
X430625Y53892D01*
G01X430500Y55033D02*
X430792Y55283D01*
X430958Y55617D01*
X431000Y55992D01*
X430958Y56325D01*
X430750Y56658D01*
X430500Y56867D01*
X430250Y56908D01*
X429958Y56825D01*
X429750Y56533D01*
X429667Y56242D01*
Y55867D01*
G01Y56242D02*
X429542Y56492D01*
X429333Y56700D01*
X429083Y56783D01*
X428833Y56700D01*
X428625Y56492D01*
X428500Y56117D01*
X428542Y55742D01*
X428708Y55367D01*
G01X430500Y58133D02*
X430792Y58383D01*
X430958Y58717D01*
X431000Y59092D01*
X430958Y59425D01*
X430750Y59758D01*
X430500Y59967D01*
X430250Y60008D01*
X429958Y59925D01*
X429750Y59633D01*
X429667Y59342D01*
Y58967D01*
G01Y59342D02*
X429542Y59592D01*
X429333Y59800D01*
X429083Y59883D01*
X428833Y59800D01*
X428625Y59592D01*
X428500Y59217D01*
X428542Y58842D01*
X428708Y58467D01*
G01X430708Y61442D02*
X430917Y61733D01*
X431000Y62067D01*
X430917Y62400D01*
X430667Y62692D01*
X430292Y62900D01*
X429917Y62983D01*
X429458D01*
X429083Y62900D01*
X428750Y62692D01*
X428583Y62442D01*
X428500Y62150D01*
X428583Y61817D01*
X428750Y61567D01*
X429000Y61400D01*
X429333Y61317D01*
X429625Y61400D01*
X429917Y61608D01*
X430083Y61858D01*
X430125Y62150D01*
X430042Y62483D01*
X429833Y62733D01*
X429458Y62983D01*
G01X432708Y53767D02*
X432583Y53517D01*
X432500Y53225D01*
Y52892D01*
X432625Y52517D01*
X432833Y52225D01*
X433083Y52017D01*
X433500Y51850D01*
X433875Y51808D01*
X434250Y51892D01*
X434500Y52017D01*
X434750Y52267D01*
X434917Y52558D01*
X435000Y52850D01*
Y53142D01*
X434917Y53433D01*
X434792Y53683D01*
X434625Y53892D01*
G01X435000Y55950D02*
X432500D01*
X433000Y55450D01*
G01X435000D02*
Y56450D01*
G01Y59050D02*
X432500D01*
X433000Y58550D01*
G01X435000D02*
Y59550D01*
G01X433958Y61358D02*
X433667Y61650D01*
X433500Y61900D01*
X433417Y62233D01*
X433500Y62525D01*
X433667Y62733D01*
X433917Y62900D01*
X434208Y62942D01*
X434458Y62900D01*
X434708Y62733D01*
X434917Y62483D01*
X435000Y62192D01*
X434917Y61858D01*
X434667Y61567D01*
X434292Y61400D01*
X433875Y61358D01*
X433333Y61442D01*
X433042Y61567D01*
X432750Y61775D01*
X432542Y62067D01*
X432500Y62358D01*
X432583Y62650D01*
X432792Y62858D01*
G01X424708Y66217D02*
X424583Y65967D01*
X424500Y65675D01*
Y65342D01*
X424625Y64967D01*
X424833Y64675D01*
X425083Y64467D01*
X425500Y64300D01*
X425875Y64258D01*
X426250Y64342D01*
X426500Y64467D01*
X426750Y64717D01*
X426917Y65008D01*
X427000Y65300D01*
Y65592D01*
X426917Y65883D01*
X426792Y66133D01*
X426625Y66342D01*
G01X424917Y67608D02*
X424667Y67858D01*
X424542Y68150D01*
X424500Y68483D01*
X424583Y68900D01*
X424792Y69192D01*
X425042Y69275D01*
X425292Y69233D01*
X425500Y69067D01*
X425917Y68233D01*
X426208Y67858D01*
X426625Y67608D01*
X427000Y67525D01*
Y69275D01*
G01X424917Y70708D02*
X424667Y70958D01*
X424542Y71250D01*
X424500Y71583D01*
X424583Y72000D01*
X424792Y72292D01*
X425042Y72375D01*
X425292Y72333D01*
X425500Y72167D01*
X425917Y71333D01*
X426208Y70958D01*
X426625Y70708D01*
X427000Y70625D01*
Y72375D01*
G01X429483Y68000D02*
Y66208D01*
X429650Y65833D01*
X429983Y65583D01*
X430400Y65500D01*
X430817Y65583D01*
X431150Y65833D01*
X431317Y66208D01*
Y68000D01*
G01X433500Y65500D02*
Y68000D01*
X433000Y67500D01*
G01Y65500D02*
X434000D01*
G01X435808Y67583D02*
X436058Y67833D01*
X436350Y67958D01*
X436683Y68000D01*
X437100Y67917D01*
X437392Y67708D01*
X437475Y67458D01*
X437433Y67208D01*
X437267Y67000D01*
X436433Y66583D01*
X436058Y66292D01*
X435808Y65875D01*
X435725Y65500D01*
X437475D01*
G01X429483Y72000D02*
Y70208D01*
X429650Y69833D01*
X429983Y69583D01*
X430400Y69500D01*
X430817Y69583D01*
X431150Y69833D01*
X431317Y70208D01*
Y72000D01*
G01X433500Y69500D02*
Y72000D01*
X433000Y71500D01*
G01Y69500D02*
X434000D01*
G01X436600Y72000D02*
X436267Y71917D01*
X436017Y71708D01*
X435850Y71458D01*
X435725Y71125D01*
X435683Y70750D01*
X435725Y70375D01*
X435850Y70042D01*
X436017Y69792D01*
X436267Y69583D01*
X436600Y69500D01*
X436933Y69583D01*
X437183Y69792D01*
X437350Y70042D01*
X437475Y70375D01*
X437517Y70750D01*
X437475Y71125D01*
X437350Y71458D01*
X437183Y71708D01*
X436933Y71917D01*
X436600Y72000D01*
G01X427017Y87500D02*
Y90000D01*
X428058D01*
X428392Y89875D01*
X428600Y89708D01*
X428683Y89375D01*
X428600Y89042D01*
X428350Y88833D01*
X428058Y88708D01*
X427017D01*
G01X428058D02*
X428683Y87500D01*
G01X430950D02*
Y90000D01*
X430450Y89500D01*
G01Y87500D02*
X431450D01*
G01X433258Y88542D02*
X433550Y88833D01*
X433800Y89000D01*
X434133Y89083D01*
X434425Y89000D01*
X434633Y88833D01*
X434800Y88583D01*
X434842Y88292D01*
X434800Y88042D01*
X434633Y87792D01*
X434383Y87583D01*
X434092Y87500D01*
X433758Y87583D01*
X433467Y87833D01*
X433300Y88208D01*
X433258Y88625D01*
X433342Y89167D01*
X433467Y89458D01*
X433675Y89750D01*
X433967Y89958D01*
X434258Y90000D01*
X434550Y89917D01*
X434758Y89708D01*
G01X437150Y87500D02*
X437442Y87542D01*
X437775Y87667D01*
X437983Y87875D01*
X438067Y88167D01*
X437983Y88458D01*
X437733Y88708D01*
X437358Y88833D01*
X436942D01*
X436692Y88917D01*
X436483Y89125D01*
X436400Y89417D01*
X436525Y89708D01*
X436817Y89917D01*
X437150Y90000D01*
X437483Y89917D01*
X437775Y89708D01*
X437900Y89417D01*
X437817Y89125D01*
X437608Y88917D01*
X437358Y88833D01*
X436942D01*
X436567Y88708D01*
X436317Y88458D01*
X436233Y88167D01*
X436317Y87875D01*
X436525Y87667D01*
X436858Y87542D01*
X437150Y87500D01*
G01X427017Y91500D02*
Y94000D01*
X428058D01*
X428392Y93875D01*
X428600Y93708D01*
X428683Y93375D01*
X428600Y93042D01*
X428350Y92833D01*
X428058Y92708D01*
X427017D01*
G01X428058D02*
X428683Y91500D01*
G01X430950D02*
Y94000D01*
X430450Y93500D01*
G01Y91500D02*
X431450D01*
G01X433258Y92542D02*
X433550Y92833D01*
X433800Y93000D01*
X434133Y93083D01*
X434425Y93000D01*
X434633Y92833D01*
X434800Y92583D01*
X434842Y92292D01*
X434800Y92042D01*
X434633Y91792D01*
X434383Y91583D01*
X434092Y91500D01*
X433758Y91583D01*
X433467Y91833D01*
X433300Y92208D01*
X433258Y92625D01*
X433342Y93167D01*
X433467Y93458D01*
X433675Y93750D01*
X433967Y93958D01*
X434258Y94000D01*
X434550Y93917D01*
X434758Y93708D01*
G01X437150Y91500D02*
Y94000D01*
X436650Y93500D01*
G01Y91500D02*
X437650D01*
G01X422708Y245367D02*
X422583Y245117D01*
X422500Y244825D01*
Y244492D01*
X422625Y244117D01*
X422833Y243825D01*
X423083Y243617D01*
X423500Y243450D01*
X423875Y243408D01*
X424250Y243492D01*
X424500Y243617D01*
X424750Y243867D01*
X424917Y244158D01*
X425000Y244450D01*
Y244742D01*
X424917Y245033D01*
X424792Y245283D01*
X424625Y245492D01*
G01X425000Y247550D02*
X424958Y247842D01*
X424833Y248175D01*
X424625Y248383D01*
X424333Y248467D01*
X424042Y248383D01*
X423792Y248133D01*
X423667Y247758D01*
Y247342D01*
X423583Y247092D01*
X423375Y246883D01*
X423083Y246800D01*
X422792Y246925D01*
X422583Y247217D01*
X422500Y247550D01*
X422583Y247883D01*
X422792Y248175D01*
X423083Y248300D01*
X423375Y248217D01*
X423583Y248008D01*
X423667Y247758D01*
Y247342D01*
X423792Y246967D01*
X424042Y246717D01*
X424333Y246633D01*
X424625Y246717D01*
X424833Y246925D01*
X424958Y247258D01*
X425000Y247550D01*
G01X429533Y248500D02*
Y246708D01*
X429700Y246333D01*
X430033Y246083D01*
X430450Y246000D01*
X430867Y246083D01*
X431200Y246333D01*
X431367Y246708D01*
Y248500D01*
G01X434050Y246000D02*
Y248500D01*
X432508Y246708D01*
X434592D01*
G01X430200Y258450D02*
X432800D01*
G01X430200Y250550D02*
Y258450D01*
G01X432800Y250550D02*
X430200D01*
G01X432800Y258450D02*
Y250550D01*
G01X426367Y265292D02*
X426117Y265417D01*
X425825Y265500D01*
X425492D01*
X425117Y265375D01*
X424825Y265167D01*
X424617Y264917D01*
X424450Y264500D01*
X424408Y264125D01*
X424492Y263750D01*
X424617Y263500D01*
X424867Y263250D01*
X425158Y263083D01*
X425450Y263000D01*
X425742D01*
X426033Y263083D01*
X426283Y263208D01*
X426492Y263375D01*
G01X428467Y263000D02*
X428550Y263542D01*
X428675Y264000D01*
X428842Y264417D01*
X429050Y264875D01*
X429383Y265500D01*
X427717D01*
G01X432000Y263433D02*
X433792D01*
X434167Y263600D01*
X434417Y263933D01*
X434500Y264350D01*
X434417Y264767D01*
X434167Y265100D01*
X433792Y265267D01*
X432000D01*
G01X434000Y266533D02*
X434292Y266783D01*
X434458Y267117D01*
X434500Y267492D01*
X434458Y267825D01*
X434250Y268158D01*
X434000Y268367D01*
X433750Y268408D01*
X433458Y268325D01*
X433250Y268033D01*
X433167Y267742D01*
Y267367D01*
G01Y267742D02*
X433042Y267992D01*
X432833Y268200D01*
X432583Y268283D01*
X432333Y268200D01*
X432125Y267992D01*
X432000Y267617D01*
X432042Y267242D01*
X432208Y266867D01*
G01X421000Y265967D02*
X418500D01*
Y266967D01*
X418625Y267300D01*
X418917Y267550D01*
X419250Y267633D01*
X419583Y267550D01*
X419833Y267342D01*
X419958Y266967D01*
Y265967D01*
G01X421000Y269067D02*
X418500D01*
Y270108D01*
X418625Y270442D01*
X418792Y270650D01*
X419125Y270733D01*
X419458Y270650D01*
X419667Y270400D01*
X419792Y270108D01*
Y269067D01*
G01Y270108D02*
X421000Y270733D01*
G01Y273000D02*
X418500D01*
X419000Y272500D01*
G01X421000D02*
Y273500D01*
G01X420708Y275392D02*
X420917Y275683D01*
X421000Y276017D01*
X420917Y276350D01*
X420667Y276642D01*
X420292Y276850D01*
X419917Y276933D01*
X419458D01*
X419083Y276850D01*
X418750Y276642D01*
X418583Y276392D01*
X418500Y276100D01*
X418583Y275767D01*
X418750Y275517D01*
X419000Y275350D01*
X419333Y275267D01*
X419625Y275350D01*
X419917Y275558D01*
X420083Y275808D01*
X420125Y276100D01*
X420042Y276433D01*
X419833Y276683D01*
X419458Y276933D01*
G01X419958Y278408D02*
X419667Y278700D01*
X419500Y278950D01*
X419417Y279283D01*
X419500Y279575D01*
X419667Y279783D01*
X419917Y279950D01*
X420208Y279992D01*
X420458Y279950D01*
X420708Y279783D01*
X420917Y279533D01*
X421000Y279242D01*
X420917Y278908D01*
X420667Y278617D01*
X420292Y278450D01*
X419875Y278408D01*
X419333Y278492D01*
X419042Y278617D01*
X418750Y278825D01*
X418542Y279117D01*
X418500Y279408D01*
X418583Y279700D01*
X418792Y279908D01*
G01X429067Y273000D02*
Y275500D01*
X430108D01*
X430442Y275375D01*
X430650Y275208D01*
X430733Y274875D01*
X430650Y274542D01*
X430400Y274333D01*
X430108Y274208D01*
X429067D01*
G01X430108D02*
X430733Y273000D01*
G01X433000D02*
Y275500D01*
X432500Y275000D01*
G01Y273000D02*
X433500D01*
G01X435392Y273292D02*
X435683Y273083D01*
X436017Y273000D01*
X436350Y273083D01*
X436642Y273333D01*
X436850Y273708D01*
X436933Y274083D01*
Y274542D01*
X436850Y274917D01*
X436642Y275250D01*
X436392Y275417D01*
X436100Y275500D01*
X435767Y275417D01*
X435517Y275250D01*
X435350Y275000D01*
X435267Y274667D01*
X435350Y274375D01*
X435558Y274083D01*
X435808Y273917D01*
X436100Y273875D01*
X436433Y273958D01*
X436683Y274167D01*
X436933Y274542D01*
G01X438983Y6500D02*
Y4708D01*
X439150Y4333D01*
X439483Y4083D01*
X439900Y4000D01*
X440317Y4083D01*
X440650Y4333D01*
X440817Y4708D01*
Y6500D01*
G01X442208Y6083D02*
X442458Y6333D01*
X442750Y6458D01*
X443083Y6500D01*
X443500Y6417D01*
X443792Y6208D01*
X443875Y5958D01*
X443833Y5708D01*
X443667Y5500D01*
X442833Y5083D01*
X442458Y4792D01*
X442208Y4375D01*
X442125Y4000D01*
X443875D01*
G01X446100D02*
Y6500D01*
X445600Y6000D01*
G01Y4000D02*
X446600D01*
G01X439600Y8017D02*
X437100D01*
Y9058D01*
X437225Y9392D01*
X437392Y9600D01*
X437725Y9683D01*
X438058Y9600D01*
X438267Y9350D01*
X438392Y9058D01*
Y8017D01*
G01Y9058D02*
X439600Y9683D01*
G01Y12450D02*
X437100D01*
X438892Y10908D01*
Y12992D01*
G01X439600Y15550D02*
X437100D01*
X438892Y14008D01*
Y16092D01*
G01X437100Y18150D02*
X437183Y17817D01*
X437392Y17567D01*
X437642Y17400D01*
X437975Y17275D01*
X438350Y17233D01*
X438725Y17275D01*
X439058Y17400D01*
X439308Y17567D01*
X439517Y17817D01*
X439600Y18150D01*
X439517Y18483D01*
X439308Y18733D01*
X439058Y18900D01*
X438725Y19025D01*
X438350Y19067D01*
X437975Y19025D01*
X437642Y18900D01*
X437392Y18733D01*
X437183Y18483D01*
X437100Y18150D01*
G01X443600Y8517D02*
X441100D01*
Y9558D01*
X441225Y9892D01*
X441392Y10100D01*
X441725Y10183D01*
X442058Y10100D01*
X442267Y9850D01*
X442392Y9558D01*
Y8517D01*
G01Y9558D02*
X443600Y10183D01*
G01Y12950D02*
X441100D01*
X442892Y11408D01*
Y13492D01*
G01X443600Y16050D02*
X441100D01*
X442892Y14508D01*
Y16592D01*
G01X443600Y18650D02*
X441100D01*
X441600Y18150D01*
G01X443600D02*
Y19150D01*
G01X447500Y8517D02*
X445000D01*
Y9558D01*
X445125Y9892D01*
X445292Y10100D01*
X445625Y10183D01*
X445958Y10100D01*
X446167Y9850D01*
X446292Y9558D01*
Y8517D01*
G01Y9558D02*
X447500Y10183D01*
G01Y12950D02*
X445000D01*
X446792Y11408D01*
Y13492D01*
G01X447500Y16050D02*
X445000D01*
X446792Y14508D01*
Y16592D01*
G01X447500Y18650D02*
X447458Y18942D01*
X447333Y19275D01*
X447125Y19483D01*
X446833Y19567D01*
X446542Y19483D01*
X446292Y19233D01*
X446167Y18858D01*
Y18442D01*
X446083Y18192D01*
X445875Y17983D01*
X445583Y17900D01*
X445292Y18025D01*
X445083Y18317D01*
X445000Y18650D01*
X445083Y18983D01*
X445292Y19275D01*
X445583Y19400D01*
X445875Y19317D01*
X446083Y19108D01*
X446167Y18858D01*
Y18442D01*
X446292Y18067D01*
X446542Y17817D01*
X446833Y17733D01*
X447125Y17817D01*
X447333Y18025D01*
X447458Y18358D01*
X447500Y18650D01*
G01X434208Y23767D02*
X434083Y23517D01*
X434000Y23225D01*
Y22892D01*
X434125Y22517D01*
X434333Y22225D01*
X434583Y22017D01*
X435000Y21850D01*
X435375Y21808D01*
X435750Y21892D01*
X436000Y22017D01*
X436250Y22267D01*
X436417Y22558D01*
X436500Y22850D01*
Y23142D01*
X436417Y23433D01*
X436292Y23683D01*
X436125Y23892D01*
G01X434417Y25158D02*
X434167Y25408D01*
X434042Y25700D01*
X434000Y26033D01*
X434083Y26450D01*
X434292Y26742D01*
X434542Y26825D01*
X434792Y26783D01*
X435000Y26617D01*
X435417Y25783D01*
X435708Y25408D01*
X436125Y25158D01*
X436500Y25075D01*
Y26825D01*
G01X434000Y29050D02*
X434083Y28717D01*
X434292Y28467D01*
X434542Y28300D01*
X434875Y28175D01*
X435250Y28133D01*
X435625Y28175D01*
X435958Y28300D01*
X436208Y28467D01*
X436417Y28717D01*
X436500Y29050D01*
X436417Y29383D01*
X436208Y29633D01*
X435958Y29800D01*
X435625Y29925D01*
X435250Y29967D01*
X434875Y29925D01*
X434542Y29800D01*
X434292Y29633D01*
X434083Y29383D01*
X434000Y29050D01*
G01X436500Y32067D02*
X435958Y32150D01*
X435500Y32275D01*
X435083Y32442D01*
X434625Y32650D01*
X434000Y32983D01*
Y31317D01*
G01X449167Y21975D02*
X449375Y22308D01*
X449500Y22683D01*
Y23017D01*
X449375Y23350D01*
X449167Y23600D01*
X448875Y23725D01*
X448583Y23642D01*
X448333Y23433D01*
X448167Y23058D01*
X448083Y22558D01*
X447917Y22267D01*
X447625Y22142D01*
X447333Y22225D01*
X447125Y22433D01*
X447000Y22725D01*
Y23017D01*
X447083Y23308D01*
X447292Y23558D01*
G01X449500Y25033D02*
X447000D01*
G01Y26617D02*
X448542Y25033D01*
G01X449500Y26867D02*
X447833Y25742D01*
G01X447000Y29050D02*
X449500D01*
G01X447000Y28092D02*
Y30008D01*
G01X449500Y32150D02*
X447000D01*
X447500Y31650D01*
G01X449500D02*
Y32650D01*
G01X445500Y25517D02*
X443000D01*
Y26558D01*
X443125Y26892D01*
X443292Y27100D01*
X443625Y27183D01*
X443958Y27100D01*
X444167Y26850D01*
X444292Y26558D01*
Y25517D01*
G01Y26558D02*
X445500Y27183D01*
G01Y29450D02*
X443000D01*
X443500Y28950D01*
G01X445500D02*
Y29950D01*
G01X444458Y31758D02*
X444167Y32050D01*
X444000Y32300D01*
X443917Y32633D01*
X444000Y32925D01*
X444167Y33133D01*
X444417Y33300D01*
X444708Y33342D01*
X444958Y33300D01*
X445208Y33133D01*
X445417Y32883D01*
X445500Y32592D01*
X445417Y32258D01*
X445167Y31967D01*
X444792Y31800D01*
X444375Y31758D01*
X443833Y31842D01*
X443542Y31967D01*
X443250Y32175D01*
X443042Y32467D01*
X443000Y32758D01*
X443083Y33050D01*
X443292Y33258D01*
G01X445208Y34942D02*
X445417Y35233D01*
X445500Y35567D01*
X445417Y35900D01*
X445167Y36192D01*
X444792Y36400D01*
X444417Y36483D01*
X443958D01*
X443583Y36400D01*
X443250Y36192D01*
X443083Y35942D01*
X443000Y35650D01*
X443083Y35317D01*
X443250Y35067D01*
X443500Y34900D01*
X443833Y34817D01*
X444125Y34900D01*
X444417Y35108D01*
X444583Y35358D01*
X444625Y35650D01*
X444542Y35983D01*
X444333Y36233D01*
X443958Y36483D01*
G01X440500Y22017D02*
X438000D01*
Y23058D01*
X438125Y23392D01*
X438292Y23600D01*
X438625Y23683D01*
X438958Y23600D01*
X439167Y23350D01*
X439292Y23058D01*
Y22017D01*
G01Y23058D02*
X440500Y23683D01*
G01Y26450D02*
X438000D01*
X439792Y24908D01*
Y26992D01*
G01X440500Y29050D02*
X440458Y29342D01*
X440333Y29675D01*
X440125Y29883D01*
X439833Y29967D01*
X439542Y29883D01*
X439292Y29633D01*
X439167Y29258D01*
Y28842D01*
X439083Y28592D01*
X438875Y28383D01*
X438583Y28300D01*
X438292Y28425D01*
X438083Y28717D01*
X438000Y29050D01*
X438083Y29383D01*
X438292Y29675D01*
X438583Y29800D01*
X438875Y29717D01*
X439083Y29508D01*
X439167Y29258D01*
Y28842D01*
X439292Y28467D01*
X439542Y28217D01*
X439833Y28133D01*
X440125Y28217D01*
X440333Y28425D01*
X440458Y28758D01*
X440500Y29050D01*
G01X438000Y32150D02*
X438083Y31817D01*
X438292Y31567D01*
X438542Y31400D01*
X438875Y31275D01*
X439250Y31233D01*
X439625Y31275D01*
X439958Y31400D01*
X440208Y31567D01*
X440417Y31817D01*
X440500Y32150D01*
X440417Y32483D01*
X440208Y32733D01*
X439958Y32900D01*
X439625Y33025D01*
X439250Y33067D01*
X438875Y33025D01*
X438542Y32900D01*
X438292Y32733D01*
X438083Y32483D01*
X438000Y32150D01*
G01X444500Y73000D02*
X448000D01*
Y34500D01*
X470000D01*
Y5500D01*
X450500D01*
G01X434500Y35983D02*
X436292D01*
X436667Y36150D01*
X436917Y36483D01*
X437000Y36900D01*
X436917Y37317D01*
X436667Y37650D01*
X436292Y37817D01*
X434500D01*
G01X437000Y40000D02*
X434500D01*
X435000Y39500D01*
G01X437000D02*
Y40500D01*
G01Y43100D02*
X436958Y43392D01*
X436833Y43725D01*
X436625Y43933D01*
X436333Y44017D01*
X436042Y43933D01*
X435792Y43683D01*
X435667Y43308D01*
Y42892D01*
X435583Y42642D01*
X435375Y42433D01*
X435083Y42350D01*
X434792Y42475D01*
X434583Y42767D01*
X434500Y43100D01*
X434583Y43433D01*
X434792Y43725D01*
X435083Y43850D01*
X435375Y43767D01*
X435583Y43558D01*
X435667Y43308D01*
Y42892D01*
X435792Y42517D01*
X436042Y42267D01*
X436333Y42183D01*
X436625Y42267D01*
X436833Y42475D01*
X436958Y42808D01*
X437000Y43100D01*
G01X447000Y52017D02*
X444500D01*
Y53058D01*
X444625Y53392D01*
X444792Y53600D01*
X445125Y53683D01*
X445458Y53600D01*
X445667Y53350D01*
X445792Y53058D01*
Y52017D01*
G01Y53058D02*
X447000Y53683D01*
G01Y55950D02*
X444500D01*
X445000Y55450D01*
G01X447000D02*
Y56450D01*
G01X444500Y59050D02*
X444583Y58717D01*
X444792Y58467D01*
X445042Y58300D01*
X445375Y58175D01*
X445750Y58133D01*
X446125Y58175D01*
X446458Y58300D01*
X446708Y58467D01*
X446917Y58717D01*
X447000Y59050D01*
X446917Y59383D01*
X446708Y59633D01*
X446458Y59800D01*
X446125Y59925D01*
X445750Y59967D01*
X445375Y59925D01*
X445042Y59800D01*
X444792Y59633D01*
X444583Y59383D01*
X444500Y59050D01*
G01X446625Y61233D02*
X446833Y61483D01*
X446958Y61775D01*
X447000Y62150D01*
X446917Y62525D01*
X446750Y62817D01*
X446458Y63025D01*
X446125Y63067D01*
X445792Y62983D01*
X445583Y62775D01*
X445417Y62483D01*
X445375Y62192D01*
X445417Y61900D01*
X445583Y61525D01*
X444500Y61650D01*
Y62775D01*
G01X439000Y52017D02*
X436500D01*
Y53058D01*
X436625Y53392D01*
X436792Y53600D01*
X437125Y53683D01*
X437458Y53600D01*
X437667Y53350D01*
X437792Y53058D01*
Y52017D01*
G01Y53058D02*
X439000Y53683D01*
G01Y55950D02*
X436500D01*
X437000Y55450D01*
G01X439000D02*
Y56450D01*
G01Y59050D02*
X436500D01*
X437000Y58550D01*
G01X439000D02*
Y59550D01*
G01X438625Y61233D02*
X438833Y61483D01*
X438958Y61775D01*
X439000Y62150D01*
X438917Y62525D01*
X438750Y62817D01*
X438458Y63025D01*
X438125Y63067D01*
X437792Y62983D01*
X437583Y62775D01*
X437417Y62483D01*
X437375Y62192D01*
X437417Y61900D01*
X437583Y61525D01*
X436500Y61650D01*
Y62775D01*
G01X443000Y52017D02*
X440500D01*
Y53058D01*
X440625Y53392D01*
X440792Y53600D01*
X441125Y53683D01*
X441458Y53600D01*
X441667Y53350D01*
X441792Y53058D01*
Y52017D01*
G01Y53058D02*
X443000Y53683D01*
G01Y55950D02*
X440500D01*
X441000Y55450D01*
G01X443000D02*
Y56450D01*
G01X440500Y59050D02*
X440583Y58717D01*
X440792Y58467D01*
X441042Y58300D01*
X441375Y58175D01*
X441750Y58133D01*
X442125Y58175D01*
X442458Y58300D01*
X442708Y58467D01*
X442917Y58717D01*
X443000Y59050D01*
X442917Y59383D01*
X442708Y59633D01*
X442458Y59800D01*
X442125Y59925D01*
X441750Y59967D01*
X441375Y59925D01*
X441042Y59800D01*
X440792Y59633D01*
X440583Y59383D01*
X440500Y59050D01*
G01X442708Y61442D02*
X442917Y61733D01*
X443000Y62067D01*
X442917Y62400D01*
X442667Y62692D01*
X442292Y62900D01*
X441917Y62983D01*
X441458D01*
X441083Y62900D01*
X440750Y62692D01*
X440583Y62442D01*
X440500Y62150D01*
X440583Y61817D01*
X440750Y61567D01*
X441000Y61400D01*
X441333Y61317D01*
X441625Y61400D01*
X441917Y61608D01*
X442083Y61858D01*
X442125Y62150D01*
X442042Y62483D01*
X441833Y62733D01*
X441458Y62983D01*
G01X446500Y125500D02*
Y116000D01*
X452000D01*
Y90000D01*
X448500D01*
Y73000D01*
X472000D01*
Y85000D01*
G01X446500Y66450D02*
X446458Y66117D01*
X446292Y65825D01*
X446042Y65575D01*
X445750Y65408D01*
X445417Y65325D01*
X445083D01*
X444750Y65408D01*
X444458Y65575D01*
X444208Y65825D01*
X444042Y66117D01*
X444000Y66450D01*
X444042Y66783D01*
X444208Y67075D01*
X444458Y67325D01*
X444750Y67492D01*
X445083Y67575D01*
X445417D01*
X445750Y67492D01*
X446042Y67325D01*
X446292Y67075D01*
X446458Y66783D01*
X446500Y66450D01*
G01X445833Y66783D02*
X446500Y67283D01*
G01Y70050D02*
X444000D01*
X445792Y68508D01*
Y70592D01*
G01X444412Y105661D02*
Y100981D01*
G01X442562Y99131D02*
X437842D01*
G01X446262D02*
G03I-1850J0D01*
G01X437842D02*
G03I-1850J0D01*
G01X444412Y199301D02*
Y109361D01*
G01X446262Y107511D02*
G03I-1850J0D01*
G01X455500Y139500D02*
X446000D01*
Y134500D01*
G01X446067Y126500D02*
Y129000D01*
X447067D01*
X447400Y128875D01*
X447650Y128583D01*
X447733Y128250D01*
X447650Y127917D01*
X447442Y127667D01*
X447067Y127542D01*
X446067D01*
G01X450250Y127750D02*
X451083D01*
Y127000D01*
X450833Y126750D01*
X450542Y126583D01*
X450125Y126500D01*
X449708Y126583D01*
X449417Y126750D01*
X449167Y127000D01*
X449000Y127292D01*
X448917Y127625D01*
Y127917D01*
X449000Y128167D01*
X449167Y128458D01*
X449417Y128708D01*
X449667Y128875D01*
X450000Y129000D01*
X450292D01*
X450625Y128917D01*
X450875Y128750D01*
G01X453600Y126500D02*
Y129000D01*
X452058Y127208D01*
X454142D01*
G01X446017Y130500D02*
Y133000D01*
X447017D01*
X447350Y132875D01*
X447600Y132583D01*
X447683Y132250D01*
X447600Y131917D01*
X447392Y131667D01*
X447017Y131542D01*
X446017D01*
G01X449117Y130500D02*
Y133000D01*
X450158D01*
X450492Y132875D01*
X450700Y132708D01*
X450783Y132375D01*
X450700Y132042D01*
X450450Y131833D01*
X450158Y131708D01*
X449117D01*
G01X450158D02*
X450783Y130500D01*
G01X453050Y133000D02*
Y130500D01*
G01X452092Y133000D02*
X454008D01*
G01X456150Y130500D02*
Y133000D01*
X455650Y132500D01*
G01Y130500D02*
X456650D01*
G01X448967Y167400D02*
Y169900D01*
X449967D01*
X450300Y169775D01*
X450550Y169483D01*
X450633Y169150D01*
X450550Y168817D01*
X450342Y168567D01*
X449967Y168442D01*
X448967D01*
G01X452067Y167400D02*
Y169900D01*
X453108D01*
X453442Y169775D01*
X453650Y169608D01*
X453733Y169275D01*
X453650Y168942D01*
X453400Y168733D01*
X453108Y168608D01*
X452067D01*
G01X453108D02*
X453733Y167400D01*
G01X456000D02*
Y169900D01*
X455500Y169400D01*
G01Y167400D02*
X456500D01*
G01X459100D02*
Y169900D01*
X458600Y169400D01*
G01Y167400D02*
X459600D01*
G01X461283Y167900D02*
X461533Y167608D01*
X461867Y167442D01*
X462242Y167400D01*
X462575Y167442D01*
X462908Y167650D01*
X463117Y167900D01*
X463158Y168150D01*
X463075Y168442D01*
X462783Y168650D01*
X462492Y168733D01*
X462117D01*
G01X462492D02*
X462742Y168858D01*
X462950Y169067D01*
X463033Y169317D01*
X462950Y169567D01*
X462742Y169775D01*
X462367Y169900D01*
X461992Y169858D01*
X461617Y169692D01*
G01X450267Y182392D02*
X450017Y182517D01*
X449725Y182600D01*
X449392D01*
X449017Y182475D01*
X448725Y182267D01*
X448517Y182017D01*
X448350Y181600D01*
X448308Y181225D01*
X448392Y180850D01*
X448517Y180600D01*
X448767Y180350D01*
X449058Y180183D01*
X449350Y180100D01*
X449642D01*
X449933Y180183D01*
X450183Y180308D01*
X450392Y180475D01*
G01X452450Y180100D02*
Y182600D01*
X451950Y182100D01*
G01Y180100D02*
X452950D01*
G01X454758Y181142D02*
X455050Y181433D01*
X455300Y181600D01*
X455633Y181683D01*
X455925Y181600D01*
X456133Y181433D01*
X456300Y181183D01*
X456342Y180892D01*
X456300Y180642D01*
X456133Y180392D01*
X455883Y180183D01*
X455592Y180100D01*
X455258Y180183D01*
X454967Y180433D01*
X454800Y180808D01*
X454758Y181225D01*
X454842Y181767D01*
X454967Y182058D01*
X455175Y182350D01*
X455467Y182558D01*
X455758Y182600D01*
X456050Y182517D01*
X456258Y182308D01*
G01X458650Y180100D02*
Y182600D01*
X458150Y182100D01*
G01Y180100D02*
X459150D01*
G01X450267Y178292D02*
X450017Y178417D01*
X449725Y178500D01*
X449392D01*
X449017Y178375D01*
X448725Y178167D01*
X448517Y177917D01*
X448350Y177500D01*
X448308Y177125D01*
X448392Y176750D01*
X448517Y176500D01*
X448767Y176250D01*
X449058Y176083D01*
X449350Y176000D01*
X449642D01*
X449933Y176083D01*
X450183Y176208D01*
X450392Y176375D01*
G01X452450Y176000D02*
Y178500D01*
X451950Y178000D01*
G01Y176000D02*
X452950D01*
G01X454758Y177042D02*
X455050Y177333D01*
X455300Y177500D01*
X455633Y177583D01*
X455925Y177500D01*
X456133Y177333D01*
X456300Y177083D01*
X456342Y176792D01*
X456300Y176542D01*
X456133Y176292D01*
X455883Y176083D01*
X455592Y176000D01*
X455258Y176083D01*
X454967Y176333D01*
X454800Y176708D01*
X454758Y177125D01*
X454842Y177667D01*
X454967Y177958D01*
X455175Y178250D01*
X455467Y178458D01*
X455758Y178500D01*
X456050Y178417D01*
X456258Y178208D01*
G01X458650Y176000D02*
X458942Y176042D01*
X459275Y176167D01*
X459483Y176375D01*
X459567Y176667D01*
X459483Y176958D01*
X459233Y177208D01*
X458858Y177333D01*
X458442D01*
X458192Y177417D01*
X457983Y177625D01*
X457900Y177917D01*
X458025Y178208D01*
X458317Y178417D01*
X458650Y178500D01*
X458983Y178417D01*
X459275Y178208D01*
X459400Y177917D01*
X459317Y177625D01*
X459108Y177417D01*
X458858Y177333D01*
X458442D01*
X458067Y177208D01*
X457817Y176958D01*
X457733Y176667D01*
X457817Y176375D01*
X458025Y176167D01*
X458358Y176042D01*
X458650Y176000D01*
G01X448967Y171400D02*
Y173900D01*
X449967D01*
X450300Y173775D01*
X450550Y173483D01*
X450633Y173150D01*
X450550Y172817D01*
X450342Y172567D01*
X449967Y172442D01*
X448967D01*
G01X452067Y171400D02*
Y173900D01*
X453108D01*
X453442Y173775D01*
X453650Y173608D01*
X453733Y173275D01*
X453650Y172942D01*
X453400Y172733D01*
X453108Y172608D01*
X452067D01*
G01X453108D02*
X453733Y171400D01*
G01X456000D02*
Y173900D01*
X455500Y173400D01*
G01Y171400D02*
X456500D01*
G01X459100Y173900D02*
X458767Y173817D01*
X458517Y173608D01*
X458350Y173358D01*
X458225Y173025D01*
X458183Y172650D01*
X458225Y172275D01*
X458350Y171942D01*
X458517Y171692D01*
X458767Y171483D01*
X459100Y171400D01*
X459433Y171483D01*
X459683Y171692D01*
X459850Y171942D01*
X459975Y172275D01*
X460017Y172650D01*
X459975Y173025D01*
X459850Y173358D01*
X459683Y173608D01*
X459433Y173817D01*
X459100Y173900D01*
G01X462200Y171400D02*
X462492Y171442D01*
X462825Y171567D01*
X463033Y171775D01*
X463117Y172067D01*
X463033Y172358D01*
X462783Y172608D01*
X462408Y172733D01*
X461992D01*
X461742Y172817D01*
X461533Y173025D01*
X461450Y173317D01*
X461575Y173608D01*
X461867Y173817D01*
X462200Y173900D01*
X462533Y173817D01*
X462825Y173608D01*
X462950Y173317D01*
X462867Y173025D01*
X462658Y172817D01*
X462408Y172733D01*
X461992D01*
X461617Y172608D01*
X461367Y172358D01*
X461283Y172067D01*
X461367Y171775D01*
X461575Y171567D01*
X461908Y171442D01*
X462200Y171400D01*
G01X469500Y186000D02*
X447500D01*
Y205500D01*
G01X449017Y192000D02*
Y194500D01*
X450058D01*
X450392Y194375D01*
X450600Y194208D01*
X450683Y193875D01*
X450600Y193542D01*
X450350Y193333D01*
X450058Y193208D01*
X449017D01*
G01X450058D02*
X450683Y192000D01*
G01X453450D02*
Y194500D01*
X451908Y192708D01*
X453992D01*
G01X456050Y192000D02*
Y194500D01*
X455550Y194000D01*
G01Y192000D02*
X456550D01*
G01X458233Y192375D02*
X458483Y192167D01*
X458775Y192042D01*
X459150Y192000D01*
X459525Y192083D01*
X459817Y192250D01*
X460025Y192542D01*
X460067Y192875D01*
X459983Y193208D01*
X459775Y193417D01*
X459483Y193583D01*
X459192Y193625D01*
X458900Y193583D01*
X458525Y193417D01*
X458650Y194500D01*
X459775D01*
G01X449017Y187500D02*
Y190000D01*
X450058D01*
X450392Y189875D01*
X450600Y189708D01*
X450683Y189375D01*
X450600Y189042D01*
X450350Y188833D01*
X450058Y188708D01*
X449017D01*
G01X450058D02*
X450683Y187500D01*
G01X452950D02*
Y190000D01*
X452450Y189500D01*
G01Y187500D02*
X453450D01*
G01X456050Y190000D02*
X455717Y189917D01*
X455467Y189708D01*
X455300Y189458D01*
X455175Y189125D01*
X455133Y188750D01*
X455175Y188375D01*
X455300Y188042D01*
X455467Y187792D01*
X455717Y187583D01*
X456050Y187500D01*
X456383Y187583D01*
X456633Y187792D01*
X456800Y188042D01*
X456925Y188375D01*
X456967Y188750D01*
X456925Y189125D01*
X456800Y189458D01*
X456633Y189708D01*
X456383Y189917D01*
X456050Y190000D01*
G01X458233Y188000D02*
X458483Y187708D01*
X458817Y187542D01*
X459192Y187500D01*
X459525Y187542D01*
X459858Y187750D01*
X460067Y188000D01*
X460108Y188250D01*
X460025Y188542D01*
X459733Y188750D01*
X459442Y188833D01*
X459067D01*
G01X459442D02*
X459692Y188958D01*
X459900Y189167D01*
X459983Y189417D01*
X459900Y189667D01*
X459692Y189875D01*
X459317Y190000D01*
X458942Y189958D01*
X458567Y189792D01*
G01X441967Y214500D02*
Y221500D01*
X447033D01*
G01X445167Y218117D02*
X441967D01*
G01X446000Y212500D02*
X440000D01*
Y220000D01*
G01X437842Y209531D02*
X442562D01*
G01X444412Y207681D02*
Y203001D01*
G01X446262Y201151D02*
G03I-1850J0D01*
G01Y209531D02*
G03I-1850J0D01*
G01X437842D02*
G03I-1850J0D01*
G01X440000Y226000D02*
X466000D01*
Y201000D01*
X469500D01*
Y186000D01*
G01X445467Y228100D02*
Y230600D01*
X446508D01*
X446842Y230475D01*
X447050Y230308D01*
X447133Y229975D01*
X447050Y229642D01*
X446800Y229433D01*
X446508Y229308D01*
X445467D01*
G01X446508D02*
X447133Y228100D01*
G01X448608Y230183D02*
X448858Y230433D01*
X449150Y230558D01*
X449483Y230600D01*
X449900Y230517D01*
X450192Y230308D01*
X450275Y230058D01*
X450233Y229808D01*
X450067Y229600D01*
X449233Y229183D01*
X448858Y228892D01*
X448608Y228475D01*
X448525Y228100D01*
X450275D01*
G01X451583Y228600D02*
X451833Y228308D01*
X452167Y228142D01*
X452542Y228100D01*
X452875Y228142D01*
X453208Y228350D01*
X453417Y228600D01*
X453458Y228850D01*
X453375Y229142D01*
X453083Y229350D01*
X452792Y229433D01*
X452417D01*
G01X452792D02*
X453042Y229558D01*
X453250Y229767D01*
X453333Y230017D01*
X453250Y230267D01*
X453042Y230475D01*
X452667Y230600D01*
X452292Y230558D01*
X451917Y230392D01*
G01X451000Y214567D02*
X448500D01*
Y215608D01*
X448625Y215942D01*
X448792Y216150D01*
X449125Y216233D01*
X449458Y216150D01*
X449667Y215900D01*
X449792Y215608D01*
Y214567D01*
G01Y215608D02*
X451000Y216233D01*
G01X450625Y217583D02*
X450833Y217833D01*
X450958Y218125D01*
X451000Y218500D01*
X450917Y218875D01*
X450750Y219167D01*
X450458Y219375D01*
X450125Y219417D01*
X449792Y219333D01*
X449583Y219125D01*
X449417Y218833D01*
X449375Y218542D01*
X449417Y218250D01*
X449583Y217875D01*
X448500Y218000D01*
Y219125D01*
G01X450625Y220683D02*
X450833Y220933D01*
X450958Y221225D01*
X451000Y221600D01*
X450917Y221975D01*
X450750Y222267D01*
X450458Y222475D01*
X450125Y222517D01*
X449792Y222433D01*
X449583Y222225D01*
X449417Y221933D01*
X449375Y221642D01*
X449417Y221350D01*
X449583Y220975D01*
X448500Y221100D01*
Y222225D01*
G01X445463Y232163D02*
Y234663D01*
X446504D01*
X446838Y234538D01*
X447046Y234371D01*
X447129Y234038D01*
X447046Y233705D01*
X446796Y233496D01*
X446504Y233371D01*
X445463D01*
G01X446504D02*
X447129Y232163D01*
G01X448604Y234246D02*
X448854Y234496D01*
X449146Y234621D01*
X449479Y234663D01*
X449896Y234580D01*
X450188Y234371D01*
X450271Y234121D01*
X450229Y233871D01*
X450063Y233663D01*
X449229Y233246D01*
X448854Y232955D01*
X448604Y232538D01*
X448521Y232163D01*
X450271D01*
G01X452496D02*
Y234663D01*
X451996Y234163D01*
G01Y232163D02*
X452996D01*
G01X447508Y242067D02*
X447383Y241817D01*
X447300Y241525D01*
Y241192D01*
X447425Y240817D01*
X447633Y240525D01*
X447883Y240317D01*
X448300Y240150D01*
X448675Y240108D01*
X449050Y240192D01*
X449300Y240317D01*
X449550Y240567D01*
X449717Y240858D01*
X449800Y241150D01*
Y241442D01*
X449717Y241733D01*
X449592Y241983D01*
X449425Y242192D01*
G01Y243333D02*
X449633Y243583D01*
X449758Y243875D01*
X449800Y244250D01*
X449717Y244625D01*
X449550Y244917D01*
X449258Y245125D01*
X448925Y245167D01*
X448592Y245083D01*
X448383Y244875D01*
X448217Y244583D01*
X448175Y244292D01*
X448217Y244000D01*
X448383Y243625D01*
X447300Y243750D01*
Y244875D01*
G01X445500Y240067D02*
X443000D01*
Y241108D01*
X443125Y241442D01*
X443292Y241650D01*
X443625Y241733D01*
X443958Y241650D01*
X444167Y241400D01*
X444292Y241108D01*
Y240067D01*
G01Y241108D02*
X445500Y241733D01*
G01Y244000D02*
X443000D01*
X443500Y243500D01*
G01X445500D02*
Y244500D01*
G01Y247100D02*
X445458Y247392D01*
X445333Y247725D01*
X445125Y247933D01*
X444833Y248017D01*
X444542Y247933D01*
X444292Y247683D01*
X444167Y247308D01*
Y246892D01*
X444083Y246642D01*
X443875Y246433D01*
X443583Y246350D01*
X443292Y246475D01*
X443083Y246767D01*
X443000Y247100D01*
X443083Y247433D01*
X443292Y247725D01*
X443583Y247850D01*
X443875Y247767D01*
X444083Y247558D01*
X444167Y247308D01*
Y246892D01*
X444292Y246517D01*
X444542Y246267D01*
X444833Y246183D01*
X445125Y246267D01*
X445333Y246475D01*
X445458Y246808D01*
X445500Y247100D01*
G01X441500Y240067D02*
X439000D01*
Y241108D01*
X439125Y241442D01*
X439292Y241650D01*
X439625Y241733D01*
X439958Y241650D01*
X440167Y241400D01*
X440292Y241108D01*
Y240067D01*
G01Y241108D02*
X441500Y241733D01*
G01Y244000D02*
X439000D01*
X439500Y243500D01*
G01X441500D02*
Y244500D01*
G01Y247017D02*
X440958Y247100D01*
X440500Y247225D01*
X440083Y247392D01*
X439625Y247600D01*
X439000Y247933D01*
Y246267D01*
G01X448533Y275800D02*
Y274008D01*
X448700Y273633D01*
X449033Y273383D01*
X449450Y273300D01*
X449867Y273383D01*
X450200Y273633D01*
X450367Y274008D01*
Y275800D01*
G01X451758Y275383D02*
X452008Y275633D01*
X452300Y275758D01*
X452633Y275800D01*
X453050Y275717D01*
X453342Y275508D01*
X453425Y275258D01*
X453383Y275008D01*
X453217Y274800D01*
X452383Y274383D01*
X452008Y274092D01*
X451758Y273675D01*
X451675Y273300D01*
X453425D01*
G01X446550Y267800D02*
X454450D01*
G01X446550Y265200D02*
Y267800D01*
G01X454450Y265200D02*
X446550D01*
G01X439367Y287292D02*
X439117Y287417D01*
X438825Y287500D01*
X438492D01*
X438117Y287375D01*
X437825Y287167D01*
X437617Y286917D01*
X437450Y286500D01*
X437408Y286125D01*
X437492Y285750D01*
X437617Y285500D01*
X437867Y285250D01*
X438158Y285083D01*
X438450Y285000D01*
X438742D01*
X439033Y285083D01*
X439283Y285208D01*
X439492Y285375D01*
G01X440758Y286042D02*
X441050Y286333D01*
X441300Y286500D01*
X441633Y286583D01*
X441925Y286500D01*
X442133Y286333D01*
X442300Y286083D01*
X442342Y285792D01*
X442300Y285542D01*
X442133Y285292D01*
X441883Y285083D01*
X441592Y285000D01*
X441258Y285083D01*
X440967Y285333D01*
X440800Y285708D01*
X440758Y286125D01*
X440842Y286667D01*
X440967Y286958D01*
X441175Y287250D01*
X441467Y287458D01*
X441758Y287500D01*
X442050Y287417D01*
X442258Y287208D01*
G01X457208Y11317D02*
X457083Y11067D01*
X457000Y10775D01*
Y10442D01*
X457125Y10067D01*
X457333Y9775D01*
X457583Y9567D01*
X458000Y9400D01*
X458375Y9358D01*
X458750Y9442D01*
X459000Y9567D01*
X459250Y9817D01*
X459417Y10108D01*
X459500Y10400D01*
Y10692D01*
X459417Y10983D01*
X459292Y11233D01*
X459125Y11442D01*
G01X459500Y13417D02*
X458958Y13500D01*
X458500Y13625D01*
X458083Y13792D01*
X457625Y14000D01*
X457000Y14333D01*
Y12667D01*
G01X458458Y15808D02*
X458167Y16100D01*
X458000Y16350D01*
X457917Y16683D01*
X458000Y16975D01*
X458167Y17183D01*
X458417Y17350D01*
X458708Y17392D01*
X458958Y17350D01*
X459208Y17183D01*
X459417Y16933D01*
X459500Y16642D01*
X459417Y16308D01*
X459167Y16017D01*
X458792Y15850D01*
X458375Y15808D01*
X457833Y15892D01*
X457542Y16017D01*
X457250Y16225D01*
X457042Y16517D01*
X457000Y16808D01*
X457083Y17100D01*
X457292Y17308D01*
G01X451500Y9017D02*
X449000D01*
Y10058D01*
X449125Y10392D01*
X449292Y10600D01*
X449625Y10683D01*
X449958Y10600D01*
X450167Y10350D01*
X450292Y10058D01*
Y9017D01*
G01Y10058D02*
X451500Y10683D01*
G01Y13450D02*
X449000D01*
X450792Y11908D01*
Y13992D01*
G01X451125Y15133D02*
X451333Y15383D01*
X451458Y15675D01*
X451500Y16050D01*
X451417Y16425D01*
X451250Y16717D01*
X450958Y16925D01*
X450625Y16967D01*
X450292Y16883D01*
X450083Y16675D01*
X449917Y16383D01*
X449875Y16092D01*
X449917Y15800D01*
X450083Y15425D01*
X449000Y15550D01*
Y16675D01*
G01X451125Y18233D02*
X451333Y18483D01*
X451458Y18775D01*
X451500Y19150D01*
X451417Y19525D01*
X451250Y19817D01*
X450958Y20025D01*
X450625Y20067D01*
X450292Y19983D01*
X450083Y19775D01*
X449917Y19483D01*
X449875Y19192D01*
X449917Y18900D01*
X450083Y18525D01*
X449000Y18650D01*
Y19775D01*
G01X455000Y9017D02*
X452500D01*
Y10058D01*
X452625Y10392D01*
X452792Y10600D01*
X453125Y10683D01*
X453458Y10600D01*
X453667Y10350D01*
X453792Y10058D01*
Y9017D01*
G01Y10058D02*
X455000Y10683D01*
G01Y12950D02*
X452500D01*
X453000Y12450D01*
G01X455000D02*
Y13450D01*
G01Y16550D02*
X452500D01*
X454292Y15008D01*
Y17092D01*
G01X454625Y18233D02*
X454833Y18483D01*
X454958Y18775D01*
X455000Y19150D01*
X454917Y19525D01*
X454750Y19817D01*
X454458Y20025D01*
X454125Y20067D01*
X453792Y19983D01*
X453583Y19775D01*
X453417Y19483D01*
X453375Y19192D01*
X453417Y18900D01*
X453583Y18525D01*
X452500Y18650D01*
Y19775D01*
G01X455667Y24500D02*
X459000Y31500D01*
X462333Y24500D01*
G01X461133Y26950D02*
X456867D01*
G01X452413Y39376D02*
Y51176D01*
X483413D01*
Y39376D01*
X452413D01*
G01X458817Y57292D02*
X458567Y57417D01*
X458275Y57500D01*
X457942D01*
X457567Y57375D01*
X457275Y57167D01*
X457067Y56917D01*
X456900Y56500D01*
X456858Y56125D01*
X456942Y55750D01*
X457067Y55500D01*
X457317Y55250D01*
X457608Y55083D01*
X457900Y55000D01*
X458192D01*
X458483Y55083D01*
X458733Y55208D01*
X458942Y55375D01*
G01X460042Y55000D02*
Y57500D01*
X461958Y55000D01*
Y57500D01*
G01X463308Y57083D02*
X463558Y57333D01*
X463850Y57458D01*
X464183Y57500D01*
X464600Y57417D01*
X464892Y57208D01*
X464975Y56958D01*
X464933Y56708D01*
X464767Y56500D01*
X463933Y56083D01*
X463558Y55792D01*
X463308Y55375D01*
X463225Y55000D01*
X464975D01*
G01X456383Y61507D02*
Y64007D01*
X457217D01*
X457550Y63882D01*
X457800Y63715D01*
X458008Y63465D01*
X458175Y63174D01*
X458217Y62757D01*
X458175Y62340D01*
X458008Y62049D01*
X457800Y61799D01*
X457550Y61632D01*
X457217Y61507D01*
X456383D01*
G01X459900Y64007D02*
X460900D01*
G01X460400D02*
Y61507D01*
G01X459900D02*
X460900D01*
G01X462417D02*
Y64007D01*
X463500Y61924D01*
X464583Y64007D01*
Y61507D01*
G01X465517D02*
Y64007D01*
X466600Y61924D01*
X467683Y64007D01*
Y61507D01*
G01X470200D02*
Y64007D01*
X468658Y62215D01*
X470742D01*
G01X458208Y81317D02*
X458083Y81067D01*
X458000Y80775D01*
Y80442D01*
X458125Y80067D01*
X458333Y79775D01*
X458583Y79567D01*
X459000Y79400D01*
X459375Y79358D01*
X459750Y79442D01*
X460000Y79567D01*
X460250Y79817D01*
X460417Y80108D01*
X460500Y80400D01*
Y80692D01*
X460417Y80983D01*
X460292Y81233D01*
X460125Y81442D01*
G01X460500Y83500D02*
X458000D01*
X458500Y83000D01*
G01X460500D02*
Y84000D01*
G01X459458Y85808D02*
X459167Y86100D01*
X459000Y86350D01*
X458917Y86683D01*
X459000Y86975D01*
X459167Y87183D01*
X459417Y87350D01*
X459708Y87392D01*
X459958Y87350D01*
X460208Y87183D01*
X460417Y86933D01*
X460500Y86642D01*
X460417Y86308D01*
X460167Y86017D01*
X459792Y85850D01*
X459375Y85808D01*
X458833Y85892D01*
X458542Y86017D01*
X458250Y86225D01*
X458042Y86517D01*
X458000Y86808D01*
X458083Y87100D01*
X458292Y87308D01*
G01X454000Y81033D02*
X455792D01*
X456167Y81200D01*
X456417Y81533D01*
X456500Y81950D01*
X456417Y82367D01*
X456167Y82700D01*
X455792Y82867D01*
X454000D01*
G01X456500Y85050D02*
X456458Y85342D01*
X456333Y85675D01*
X456125Y85883D01*
X455833Y85967D01*
X455542Y85883D01*
X455292Y85633D01*
X455167Y85258D01*
Y84842D01*
X455083Y84592D01*
X454875Y84383D01*
X454583Y84300D01*
X454292Y84425D01*
X454083Y84717D01*
X454000Y85050D01*
X454083Y85383D01*
X454292Y85675D01*
X454583Y85800D01*
X454875Y85717D01*
X455083Y85508D01*
X455167Y85258D01*
Y84842D01*
X455292Y84467D01*
X455542Y84217D01*
X455833Y84133D01*
X456125Y84217D01*
X456333Y84425D01*
X456458Y84758D01*
X456500Y85050D01*
G01X452500Y80067D02*
X450000D01*
Y81108D01*
X450125Y81442D01*
X450292Y81650D01*
X450625Y81733D01*
X450958Y81650D01*
X451167Y81400D01*
X451292Y81108D01*
Y80067D01*
G01Y81108D02*
X452500Y81733D01*
G01X452125Y83083D02*
X452333Y83333D01*
X452458Y83625D01*
X452500Y84000D01*
X452417Y84375D01*
X452250Y84667D01*
X451958Y84875D01*
X451625Y84917D01*
X451292Y84833D01*
X451083Y84625D01*
X450917Y84333D01*
X450875Y84042D01*
X450917Y83750D01*
X451083Y83375D01*
X450000Y83500D01*
Y84625D01*
G01X451458Y86308D02*
X451167Y86600D01*
X451000Y86850D01*
X450917Y87183D01*
X451000Y87475D01*
X451167Y87683D01*
X451417Y87850D01*
X451708Y87892D01*
X451958Y87850D01*
X452208Y87683D01*
X452417Y87433D01*
X452500Y87142D01*
X452417Y86808D01*
X452167Y86517D01*
X451792Y86350D01*
X451375Y86308D01*
X450833Y86392D01*
X450542Y86517D01*
X450250Y86725D01*
X450042Y87017D01*
X450000Y87308D01*
X450083Y87600D01*
X450292Y87808D01*
G01X465000Y76567D02*
X462500D01*
Y77608D01*
X462625Y77942D01*
X462792Y78150D01*
X463125Y78233D01*
X463458Y78150D01*
X463667Y77900D01*
X463792Y77608D01*
Y76567D01*
G01Y77608D02*
X465000Y78233D01*
G01X464625Y79583D02*
X464833Y79833D01*
X464958Y80125D01*
X465000Y80500D01*
X464917Y80875D01*
X464750Y81167D01*
X464458Y81375D01*
X464125Y81417D01*
X463792Y81333D01*
X463583Y81125D01*
X463417Y80833D01*
X463375Y80542D01*
X463417Y80250D01*
X463583Y79875D01*
X462500Y80000D01*
Y81125D01*
G01X464500Y82683D02*
X464792Y82933D01*
X464958Y83267D01*
X465000Y83642D01*
X464958Y83975D01*
X464750Y84308D01*
X464500Y84517D01*
X464250Y84558D01*
X463958Y84475D01*
X463750Y84183D01*
X463667Y83892D01*
Y83517D01*
G01Y83892D02*
X463542Y84142D01*
X463333Y84350D01*
X463083Y84433D01*
X462833Y84350D01*
X462625Y84142D01*
X462500Y83767D01*
X462542Y83392D01*
X462708Y83017D01*
G01X462567Y86000D02*
Y88500D01*
X463608D01*
X463942Y88375D01*
X464150Y88208D01*
X464233Y87875D01*
X464150Y87542D01*
X463900Y87333D01*
X463608Y87208D01*
X462567D01*
G01X463608D02*
X464233Y86000D01*
G01X467000D02*
Y88500D01*
X465458Y86708D01*
X467542D01*
G01X468808Y87042D02*
X469100Y87333D01*
X469350Y87500D01*
X469683Y87583D01*
X469975Y87500D01*
X470183Y87333D01*
X470350Y87083D01*
X470392Y86792D01*
X470350Y86542D01*
X470183Y86292D01*
X469933Y86083D01*
X469642Y86000D01*
X469308Y86083D01*
X469017Y86333D01*
X468850Y86708D01*
X468808Y87125D01*
X468892Y87667D01*
X469017Y87958D01*
X469225Y88250D01*
X469517Y88458D01*
X469808Y88500D01*
X470100Y88417D01*
X470308Y88208D01*
G01X462567Y90000D02*
Y92500D01*
X463608D01*
X463942Y92375D01*
X464150Y92208D01*
X464233Y91875D01*
X464150Y91542D01*
X463900Y91333D01*
X463608Y91208D01*
X462567D01*
G01X463608D02*
X464233Y90000D01*
G01X467000D02*
Y92500D01*
X465458Y90708D01*
X467542D01*
G01X469600Y90000D02*
Y92500D01*
X469100Y92000D01*
G01Y90000D02*
X470100D01*
G01X461700Y93967D02*
X459200D01*
Y94967D01*
X459325Y95300D01*
X459617Y95550D01*
X459950Y95633D01*
X460283Y95550D01*
X460533Y95342D01*
X460658Y94967D01*
Y93967D01*
G01X459408Y98817D02*
X459283Y98567D01*
X459200Y98275D01*
Y97942D01*
X459325Y97567D01*
X459533Y97275D01*
X459783Y97067D01*
X460200Y96900D01*
X460575Y96858D01*
X460950Y96942D01*
X461200Y97067D01*
X461450Y97317D01*
X461617Y97608D01*
X461700Y97900D01*
Y98192D01*
X461617Y98483D01*
X461492Y98733D01*
X461325Y98942D01*
G01X461700Y101000D02*
X459200D01*
X459700Y100500D01*
G01X461700D02*
Y101500D01*
G01X459200Y104100D02*
X459283Y103767D01*
X459492Y103517D01*
X459742Y103350D01*
X460075Y103225D01*
X460450Y103183D01*
X460825Y103225D01*
X461158Y103350D01*
X461408Y103517D01*
X461617Y103767D01*
X461700Y104100D01*
X461617Y104433D01*
X461408Y104683D01*
X461158Y104850D01*
X460825Y104975D01*
X460450Y105017D01*
X460075Y104975D01*
X459742Y104850D01*
X459492Y104683D01*
X459283Y104433D01*
X459200Y104100D01*
G01X461700Y107200D02*
X459200D01*
X459700Y106700D01*
G01X461700D02*
Y107700D01*
G01X457500Y100467D02*
X455000D01*
Y101467D01*
X455125Y101800D01*
X455417Y102050D01*
X455750Y102133D01*
X456083Y102050D01*
X456333Y101842D01*
X456458Y101467D01*
Y100467D01*
G01X457500Y103567D02*
X455000D01*
Y104608D01*
X455125Y104942D01*
X455292Y105150D01*
X455625Y105233D01*
X455958Y105150D01*
X456167Y104900D01*
X456292Y104608D01*
Y103567D01*
G01Y104608D02*
X457500Y105233D01*
G01Y107500D02*
X455000D01*
X455500Y107000D01*
G01X457500D02*
Y108000D01*
G01X457125Y109683D02*
X457333Y109933D01*
X457458Y110225D01*
X457500Y110600D01*
X457417Y110975D01*
X457250Y111267D01*
X456958Y111475D01*
X456625Y111517D01*
X456292Y111433D01*
X456083Y111225D01*
X455917Y110933D01*
X455875Y110642D01*
X455917Y110350D01*
X456083Y109975D01*
X455000Y110100D01*
Y111225D01*
G01X457208Y112992D02*
X457417Y113283D01*
X457500Y113617D01*
X457417Y113950D01*
X457167Y114242D01*
X456792Y114450D01*
X456417Y114533D01*
X455958D01*
X455583Y114450D01*
X455250Y114242D01*
X455083Y113992D01*
X455000Y113700D01*
X455083Y113367D01*
X455250Y113117D01*
X455500Y112950D01*
X455833Y112867D01*
X456125Y112950D01*
X456417Y113158D01*
X456583Y113408D01*
X456625Y113700D01*
X456542Y114033D01*
X456333Y114283D01*
X455958Y114533D01*
G01X463500Y110017D02*
X461000D01*
Y111017D01*
X461125Y111350D01*
X461417Y111600D01*
X461750Y111683D01*
X462083Y111600D01*
X462333Y111392D01*
X462458Y111017D01*
Y110017D01*
G01X461000Y113033D02*
X462792D01*
X463167Y113200D01*
X463417Y113533D01*
X463500Y113950D01*
X463417Y114367D01*
X463167Y114700D01*
X462792Y114867D01*
X461000D01*
G01X463500Y117050D02*
X461000D01*
X461500Y116550D01*
G01X463500D02*
Y117550D01*
G01Y120150D02*
X461000D01*
X461500Y119650D01*
G01X463500D02*
Y120650D01*
G01X465500Y122967D02*
X463000D01*
Y123967D01*
X463125Y124300D01*
X463417Y124550D01*
X463750Y124633D01*
X464083Y124550D01*
X464333Y124342D01*
X464458Y123967D01*
Y122967D01*
G01X463208Y127817D02*
X463083Y127567D01*
X463000Y127275D01*
Y126942D01*
X463125Y126567D01*
X463333Y126275D01*
X463583Y126067D01*
X464000Y125900D01*
X464375Y125858D01*
X464750Y125942D01*
X465000Y126067D01*
X465250Y126317D01*
X465417Y126608D01*
X465500Y126900D01*
Y127192D01*
X465417Y127483D01*
X465292Y127733D01*
X465125Y127942D01*
G01X465500Y130000D02*
X463000D01*
X463500Y129500D01*
G01X465500D02*
Y130500D01*
G01X463000Y133100D02*
X463083Y132767D01*
X463292Y132517D01*
X463542Y132350D01*
X463875Y132225D01*
X464250Y132183D01*
X464625Y132225D01*
X464958Y132350D01*
X465208Y132517D01*
X465417Y132767D01*
X465500Y133100D01*
X465417Y133433D01*
X465208Y133683D01*
X464958Y133850D01*
X464625Y133975D01*
X464250Y134017D01*
X463875Y133975D01*
X463542Y133850D01*
X463292Y133683D01*
X463083Y133433D01*
X463000Y133100D01*
G01X465500Y136700D02*
X463000D01*
X464792Y135158D01*
Y137242D01*
G01X460800Y122667D02*
X458300D01*
Y123667D01*
X458425Y124000D01*
X458717Y124250D01*
X459050Y124333D01*
X459383Y124250D01*
X459633Y124042D01*
X459758Y123667D01*
Y122667D01*
G01X460800Y125767D02*
X458300D01*
Y126808D01*
X458425Y127142D01*
X458592Y127350D01*
X458925Y127433D01*
X459258Y127350D01*
X459467Y127100D01*
X459592Y126808D01*
Y125767D01*
G01Y126808D02*
X460800Y127433D01*
G01Y129700D02*
X458300D01*
X458800Y129200D01*
G01X460800D02*
Y130200D01*
G01Y133300D02*
X458300D01*
X460092Y131758D01*
Y133842D01*
G01X460800Y135817D02*
X460258Y135900D01*
X459800Y136025D01*
X459383Y136192D01*
X458925Y136400D01*
X458300Y136733D01*
Y135067D01*
G01X456017Y196500D02*
Y199000D01*
X457058D01*
X457392Y198875D01*
X457600Y198708D01*
X457683Y198375D01*
X457600Y198042D01*
X457350Y197833D01*
X457058Y197708D01*
X456017D01*
G01X457058D02*
X457683Y196500D01*
G01X460450D02*
Y199000D01*
X458908Y197208D01*
X460992D01*
G01X463050Y196500D02*
X463342Y196542D01*
X463675Y196667D01*
X463883Y196875D01*
X463967Y197167D01*
X463883Y197458D01*
X463633Y197708D01*
X463258Y197833D01*
X462842D01*
X462592Y197917D01*
X462383Y198125D01*
X462300Y198417D01*
X462425Y198708D01*
X462717Y198917D01*
X463050Y199000D01*
X463383Y198917D01*
X463675Y198708D01*
X463800Y198417D01*
X463717Y198125D01*
X463508Y197917D01*
X463258Y197833D01*
X462842D01*
X462467Y197708D01*
X462217Y197458D01*
X462133Y197167D01*
X462217Y196875D01*
X462425Y196667D01*
X462758Y196542D01*
X463050Y196500D01*
G01X466067D02*
X466150Y197042D01*
X466275Y197500D01*
X466442Y197917D01*
X466650Y198375D01*
X466983Y199000D01*
X465317D01*
G01X453500Y200567D02*
X451000D01*
Y201608D01*
X451125Y201942D01*
X451292Y202150D01*
X451625Y202233D01*
X451958Y202150D01*
X452167Y201900D01*
X452292Y201608D01*
Y200567D01*
G01Y201608D02*
X453500Y202233D01*
G01X453208Y203792D02*
X453417Y204083D01*
X453500Y204417D01*
X453417Y204750D01*
X453167Y205042D01*
X452792Y205250D01*
X452417Y205333D01*
X451958D01*
X451583Y205250D01*
X451250Y205042D01*
X451083Y204792D01*
X451000Y204500D01*
X451083Y204167D01*
X451250Y203917D01*
X451500Y203750D01*
X451833Y203667D01*
X452125Y203750D01*
X452417Y203958D01*
X452583Y204208D01*
X452625Y204500D01*
X452542Y204833D01*
X452333Y205083D01*
X451958Y205333D01*
G01X451417Y206808D02*
X451167Y207058D01*
X451042Y207350D01*
X451000Y207683D01*
X451083Y208100D01*
X451292Y208392D01*
X451542Y208475D01*
X451792Y208433D01*
X452000Y208267D01*
X452417Y207433D01*
X452708Y207058D01*
X453125Y206808D01*
X453500Y206725D01*
Y208475D01*
G01X458317Y203292D02*
X458067Y203417D01*
X457775Y203500D01*
X457442D01*
X457067Y203375D01*
X456775Y203167D01*
X456567Y202917D01*
X456400Y202500D01*
X456358Y202125D01*
X456442Y201750D01*
X456567Y201500D01*
X456817Y201250D01*
X457108Y201083D01*
X457400Y201000D01*
X457692D01*
X457983Y201083D01*
X458233Y201208D01*
X458442Y201375D01*
G01X459583Y201500D02*
X459833Y201208D01*
X460167Y201042D01*
X460542Y201000D01*
X460875Y201042D01*
X461208Y201250D01*
X461417Y201500D01*
X461458Y201750D01*
X461375Y202042D01*
X461083Y202250D01*
X460792Y202333D01*
X460417D01*
G01X460792D02*
X461042Y202458D01*
X461250Y202667D01*
X461333Y202917D01*
X461250Y203167D01*
X461042Y203375D01*
X460667Y203500D01*
X460292Y203458D01*
X459917Y203292D01*
G01X462683Y201500D02*
X462933Y201208D01*
X463267Y201042D01*
X463642Y201000D01*
X463975Y201042D01*
X464308Y201250D01*
X464517Y201500D01*
X464558Y201750D01*
X464475Y202042D01*
X464183Y202250D01*
X463892Y202333D01*
X463517D01*
G01X463892D02*
X464142Y202458D01*
X464350Y202667D01*
X464433Y202917D01*
X464350Y203167D01*
X464142Y203375D01*
X463767Y203500D01*
X463392Y203458D01*
X463017Y203292D01*
G01X458317Y207792D02*
X458067Y207917D01*
X457775Y208000D01*
X457442D01*
X457067Y207875D01*
X456775Y207667D01*
X456567Y207417D01*
X456400Y207000D01*
X456358Y206625D01*
X456442Y206250D01*
X456567Y206000D01*
X456817Y205750D01*
X457108Y205583D01*
X457400Y205500D01*
X457692D01*
X457983Y205583D01*
X458233Y205708D01*
X458442Y205875D01*
G01X459708Y207583D02*
X459958Y207833D01*
X460250Y207958D01*
X460583Y208000D01*
X461000Y207917D01*
X461292Y207708D01*
X461375Y207458D01*
X461333Y207208D01*
X461167Y207000D01*
X460333Y206583D01*
X459958Y206292D01*
X459708Y205875D01*
X459625Y205500D01*
X461375D01*
G01X462808Y206542D02*
X463100Y206833D01*
X463350Y207000D01*
X463683Y207083D01*
X463975Y207000D01*
X464183Y206833D01*
X464350Y206583D01*
X464392Y206292D01*
X464350Y206042D01*
X464183Y205792D01*
X463933Y205583D01*
X463642Y205500D01*
X463308Y205583D01*
X463017Y205833D01*
X462850Y206208D01*
X462808Y206625D01*
X462892Y207167D01*
X463017Y207458D01*
X463225Y207750D01*
X463517Y207958D01*
X463808Y208000D01*
X464100Y207917D01*
X464308Y207708D01*
G01X449517Y210000D02*
Y212500D01*
X450558D01*
X450892Y212375D01*
X451100Y212208D01*
X451183Y211875D01*
X451100Y211542D01*
X450850Y211333D01*
X450558Y211208D01*
X449517D01*
G01X450558D02*
X451183Y210000D01*
G01X452533Y210500D02*
X452783Y210208D01*
X453117Y210042D01*
X453492Y210000D01*
X453825Y210042D01*
X454158Y210250D01*
X454367Y210500D01*
X454408Y210750D01*
X454325Y211042D01*
X454033Y211250D01*
X453742Y211333D01*
X453367D01*
G01X453742D02*
X453992Y211458D01*
X454200Y211667D01*
X454283Y211917D01*
X454200Y212167D01*
X453992Y212375D01*
X453617Y212500D01*
X453242Y212458D01*
X452867Y212292D01*
G01X456550Y212500D02*
X456217Y212417D01*
X455967Y212208D01*
X455800Y211958D01*
X455675Y211625D01*
X455633Y211250D01*
X455675Y210875D01*
X455800Y210542D01*
X455967Y210292D01*
X456217Y210083D01*
X456550Y210000D01*
X456883Y210083D01*
X457133Y210292D01*
X457300Y210542D01*
X457425Y210875D01*
X457467Y211250D01*
X457425Y211625D01*
X457300Y211958D01*
X457133Y212208D01*
X456883Y212417D01*
X456550Y212500D01*
G01X458858Y211042D02*
X459150Y211333D01*
X459400Y211500D01*
X459733Y211583D01*
X460025Y211500D01*
X460233Y211333D01*
X460400Y211083D01*
X460442Y210792D01*
X460400Y210542D01*
X460233Y210292D01*
X459983Y210083D01*
X459692Y210000D01*
X459358Y210083D01*
X459067Y210333D01*
X458900Y210708D01*
X458858Y211125D01*
X458942Y211667D01*
X459067Y211958D01*
X459275Y212250D01*
X459567Y212458D01*
X459858Y212500D01*
X460150Y212417D01*
X460358Y212208D01*
G01X453567Y214000D02*
Y216500D01*
X454608D01*
X454942Y216375D01*
X455150Y216208D01*
X455233Y215875D01*
X455150Y215542D01*
X454900Y215333D01*
X454608Y215208D01*
X453567D01*
G01X454608D02*
X455233Y214000D01*
G01X457417D02*
X457500Y214542D01*
X457625Y215000D01*
X457792Y215417D01*
X458000Y215875D01*
X458333Y216500D01*
X456667D01*
G01X459808Y216083D02*
X460058Y216333D01*
X460350Y216458D01*
X460683Y216500D01*
X461100Y216417D01*
X461392Y216208D01*
X461475Y215958D01*
X461433Y215708D01*
X461267Y215500D01*
X460433Y215083D01*
X460058Y214792D01*
X459808Y214375D01*
X459725Y214000D01*
X461475D01*
G01X455467Y227600D02*
Y230100D01*
X456508D01*
X456842Y229975D01*
X457050Y229808D01*
X457133Y229475D01*
X457050Y229142D01*
X456800Y228933D01*
X456508Y228808D01*
X455467D01*
G01X456508D02*
X457133Y227600D01*
G01X458608Y229683D02*
X458858Y229933D01*
X459150Y230058D01*
X459483Y230100D01*
X459900Y230017D01*
X460192Y229808D01*
X460275Y229558D01*
X460233Y229308D01*
X460067Y229100D01*
X459233Y228683D01*
X458858Y228392D01*
X458608Y227975D01*
X458525Y227600D01*
X460275D01*
G01X463000D02*
Y230100D01*
X461458Y228308D01*
X463542D01*
G01X453517Y222000D02*
Y224500D01*
X454558D01*
X454892Y224375D01*
X455100Y224208D01*
X455183Y223875D01*
X455100Y223542D01*
X454850Y223333D01*
X454558Y223208D01*
X453517D01*
G01X454558D02*
X455183Y222000D01*
G01X457950D02*
Y224500D01*
X456408Y222708D01*
X458492D01*
G01X460550Y222000D02*
Y224500D01*
X460050Y224000D01*
G01Y222000D02*
X461050D01*
G01X462858Y223042D02*
X463150Y223333D01*
X463400Y223500D01*
X463733Y223583D01*
X464025Y223500D01*
X464233Y223333D01*
X464400Y223083D01*
X464442Y222792D01*
X464400Y222542D01*
X464233Y222292D01*
X463983Y222083D01*
X463692Y222000D01*
X463358Y222083D01*
X463067Y222333D01*
X462900Y222708D01*
X462858Y223125D01*
X462942Y223667D01*
X463067Y223958D01*
X463275Y224250D01*
X463567Y224458D01*
X463858Y224500D01*
X464150Y224417D01*
X464358Y224208D01*
G01X453567Y218000D02*
Y220500D01*
X454608D01*
X454942Y220375D01*
X455150Y220208D01*
X455233Y219875D01*
X455150Y219542D01*
X454900Y219333D01*
X454608Y219208D01*
X453567D01*
G01X454608D02*
X455233Y218000D01*
G01X457417D02*
X457500Y218542D01*
X457625Y219000D01*
X457792Y219417D01*
X458000Y219875D01*
X458333Y220500D01*
X456667D01*
G01X459683Y218500D02*
X459933Y218208D01*
X460267Y218042D01*
X460642Y218000D01*
X460975Y218042D01*
X461308Y218250D01*
X461517Y218500D01*
X461558Y218750D01*
X461475Y219042D01*
X461183Y219250D01*
X460892Y219333D01*
X460517D01*
G01X460892D02*
X461142Y219458D01*
X461350Y219667D01*
X461433Y219917D01*
X461350Y220167D01*
X461142Y220375D01*
X460767Y220500D01*
X460392Y220458D01*
X460017Y220292D01*
G01X455467Y232100D02*
Y234600D01*
X456508D01*
X456842Y234475D01*
X457050Y234308D01*
X457133Y233975D01*
X457050Y233642D01*
X456800Y233433D01*
X456508Y233308D01*
X455467D01*
G01X456508D02*
X457133Y232100D01*
G01X458608Y234183D02*
X458858Y234433D01*
X459150Y234558D01*
X459483Y234600D01*
X459900Y234517D01*
X460192Y234308D01*
X460275Y234058D01*
X460233Y233808D01*
X460067Y233600D01*
X459233Y233183D01*
X458858Y232892D01*
X458608Y232475D01*
X458525Y232100D01*
X460275D01*
G01X461708Y234183D02*
X461958Y234433D01*
X462250Y234558D01*
X462583Y234600D01*
X463000Y234517D01*
X463292Y234308D01*
X463375Y234058D01*
X463333Y233808D01*
X463167Y233600D01*
X462333Y233183D01*
X461958Y232892D01*
X461708Y232475D01*
X461625Y232100D01*
X463375D01*
G01X466267Y242792D02*
X466017Y242917D01*
X465725Y243000D01*
X465392D01*
X465017Y242875D01*
X464725Y242667D01*
X464517Y242417D01*
X464350Y242000D01*
X464308Y241625D01*
X464392Y241250D01*
X464517Y241000D01*
X464767Y240750D01*
X465058Y240583D01*
X465350Y240500D01*
X465642D01*
X465933Y240583D01*
X466183Y240708D01*
X466392Y240875D01*
G01X468450Y240500D02*
Y243000D01*
X467950Y242500D01*
G01Y240500D02*
X468950D01*
G01X471550D02*
Y243000D01*
X471050Y242500D01*
G01Y240500D02*
X472050D01*
G01X474650Y243000D02*
X474317Y242917D01*
X474067Y242708D01*
X473900Y242458D01*
X473775Y242125D01*
X473733Y241750D01*
X473775Y241375D01*
X473900Y241042D01*
X474067Y240792D01*
X474317Y240583D01*
X474650Y240500D01*
X474983Y240583D01*
X475233Y240792D01*
X475400Y241042D01*
X475525Y241375D01*
X475567Y241750D01*
X475525Y242125D01*
X475400Y242458D01*
X475233Y242708D01*
X474983Y242917D01*
X474650Y243000D01*
G01X466267Y261292D02*
X466017Y261417D01*
X465725Y261500D01*
X465392D01*
X465017Y261375D01*
X464725Y261167D01*
X464517Y260917D01*
X464350Y260500D01*
X464308Y260125D01*
X464392Y259750D01*
X464517Y259500D01*
X464767Y259250D01*
X465058Y259083D01*
X465350Y259000D01*
X465642D01*
X465933Y259083D01*
X466183Y259208D01*
X466392Y259375D01*
G01X468450Y259000D02*
Y261500D01*
X467950Y261000D01*
G01Y259000D02*
X468950D01*
G01X471550Y261500D02*
X471217Y261417D01*
X470967Y261208D01*
X470800Y260958D01*
X470675Y260625D01*
X470633Y260250D01*
X470675Y259875D01*
X470800Y259542D01*
X470967Y259292D01*
X471217Y259083D01*
X471550Y259000D01*
X471883Y259083D01*
X472133Y259292D01*
X472300Y259542D01*
X472425Y259875D01*
X472467Y260250D01*
X472425Y260625D01*
X472300Y260958D01*
X472133Y261208D01*
X471883Y261417D01*
X471550Y261500D01*
G01X473733Y259500D02*
X473983Y259208D01*
X474317Y259042D01*
X474692Y259000D01*
X475025Y259042D01*
X475358Y259250D01*
X475567Y259500D01*
X475608Y259750D01*
X475525Y260042D01*
X475233Y260250D01*
X474942Y260333D01*
X474567D01*
G01X474942D02*
X475192Y260458D01*
X475400Y260667D01*
X475483Y260917D01*
X475400Y261167D01*
X475192Y261375D01*
X474817Y261500D01*
X474442Y261458D01*
X474067Y261292D01*
G01X455500Y248517D02*
X453000D01*
Y249558D01*
X453125Y249892D01*
X453292Y250100D01*
X453625Y250183D01*
X453958Y250100D01*
X454167Y249850D01*
X454292Y249558D01*
Y248517D01*
G01Y249558D02*
X455500Y250183D01*
G01X453417Y251658D02*
X453167Y251908D01*
X453042Y252200D01*
X453000Y252533D01*
X453083Y252950D01*
X453292Y253242D01*
X453542Y253325D01*
X453792Y253283D01*
X454000Y253117D01*
X454417Y252283D01*
X454708Y251908D01*
X455125Y251658D01*
X455500Y251575D01*
Y253325D01*
G01X453417Y254758D02*
X453167Y255008D01*
X453042Y255300D01*
X453000Y255633D01*
X453083Y256050D01*
X453292Y256342D01*
X453542Y256425D01*
X453792Y256383D01*
X454000Y256217D01*
X454417Y255383D01*
X454708Y255008D01*
X455125Y254758D01*
X455500Y254675D01*
Y256425D01*
G01X455125Y257733D02*
X455333Y257983D01*
X455458Y258275D01*
X455500Y258650D01*
X455417Y259025D01*
X455250Y259317D01*
X454958Y259525D01*
X454625Y259567D01*
X454292Y259483D01*
X454083Y259275D01*
X453917Y258983D01*
X453875Y258692D01*
X453917Y258400D01*
X454083Y258025D01*
X453000Y258150D01*
Y259275D01*
G01X460000Y248517D02*
X457500D01*
Y249558D01*
X457625Y249892D01*
X457792Y250100D01*
X458125Y250183D01*
X458458Y250100D01*
X458667Y249850D01*
X458792Y249558D01*
Y248517D01*
G01Y249558D02*
X460000Y250183D01*
G01X457917Y251658D02*
X457667Y251908D01*
X457542Y252200D01*
X457500Y252533D01*
X457583Y252950D01*
X457792Y253242D01*
X458042Y253325D01*
X458292Y253283D01*
X458500Y253117D01*
X458917Y252283D01*
X459208Y251908D01*
X459625Y251658D01*
X460000Y251575D01*
Y253325D01*
G01X457917Y254758D02*
X457667Y255008D01*
X457542Y255300D01*
X457500Y255633D01*
X457583Y256050D01*
X457792Y256342D01*
X458042Y256425D01*
X458292Y256383D01*
X458500Y256217D01*
X458917Y255383D01*
X459208Y255008D01*
X459625Y254758D01*
X460000Y254675D01*
Y256425D01*
G01X458958Y257858D02*
X458667Y258150D01*
X458500Y258400D01*
X458417Y258733D01*
X458500Y259025D01*
X458667Y259233D01*
X458917Y259400D01*
X459208Y259442D01*
X459458Y259400D01*
X459708Y259233D01*
X459917Y258983D01*
X460000Y258692D01*
X459917Y258358D01*
X459667Y258067D01*
X459292Y257900D01*
X458875Y257858D01*
X458333Y257942D01*
X458042Y258067D01*
X457750Y258275D01*
X457542Y258567D01*
X457500Y258858D01*
X457583Y259150D01*
X457792Y259358D01*
G01X454450Y267800D02*
Y265200D01*
G01X464067Y267500D02*
Y270000D01*
X465108D01*
X465442Y269875D01*
X465650Y269708D01*
X465733Y269375D01*
X465650Y269042D01*
X465400Y268833D01*
X465108Y268708D01*
X464067D01*
G01X465108D02*
X465733Y267500D01*
G01X468000D02*
Y270000D01*
X467500Y269500D01*
G01Y267500D02*
X468500D01*
G01X470308Y268542D02*
X470600Y268833D01*
X470850Y269000D01*
X471183Y269083D01*
X471475Y269000D01*
X471683Y268833D01*
X471850Y268583D01*
X471892Y268292D01*
X471850Y268042D01*
X471683Y267792D01*
X471433Y267583D01*
X471142Y267500D01*
X470808Y267583D01*
X470517Y267833D01*
X470350Y268208D01*
X470308Y268625D01*
X470392Y269167D01*
X470517Y269458D01*
X470725Y269750D01*
X471017Y269958D01*
X471308Y270000D01*
X471600Y269917D01*
X471808Y269708D01*
G01X465200Y274417D02*
X462700D01*
Y275458D01*
X462825Y275792D01*
X462992Y276000D01*
X463325Y276083D01*
X463658Y276000D01*
X463867Y275750D01*
X463992Y275458D01*
Y274417D01*
G01Y275458D02*
X465200Y276083D01*
G01X463117Y277558D02*
X462867Y277808D01*
X462742Y278100D01*
X462700Y278433D01*
X462783Y278850D01*
X462992Y279142D01*
X463242Y279225D01*
X463492Y279183D01*
X463700Y279017D01*
X464117Y278183D01*
X464408Y277808D01*
X464825Y277558D01*
X465200Y277475D01*
Y279225D01*
G01X464700Y280533D02*
X464992Y280783D01*
X465158Y281117D01*
X465200Y281492D01*
X465158Y281825D01*
X464950Y282158D01*
X464700Y282367D01*
X464450Y282408D01*
X464158Y282325D01*
X463950Y282033D01*
X463867Y281742D01*
Y281367D01*
G01Y281742D02*
X463742Y281992D01*
X463533Y282200D01*
X463283Y282283D01*
X463033Y282200D01*
X462825Y281992D01*
X462700Y281617D01*
X462742Y281242D01*
X462908Y280867D01*
G01X465200Y285050D02*
X462700D01*
X464492Y283508D01*
Y285592D01*
G01X461200Y274417D02*
X458700D01*
Y275458D01*
X458825Y275792D01*
X458992Y276000D01*
X459325Y276083D01*
X459658Y276000D01*
X459867Y275750D01*
X459992Y275458D01*
Y274417D01*
G01Y275458D02*
X461200Y276083D01*
G01X459117Y277558D02*
X458867Y277808D01*
X458742Y278100D01*
X458700Y278433D01*
X458783Y278850D01*
X458992Y279142D01*
X459242Y279225D01*
X459492Y279183D01*
X459700Y279017D01*
X460117Y278183D01*
X460408Y277808D01*
X460825Y277558D01*
X461200Y277475D01*
Y279225D01*
G01X460700Y280533D02*
X460992Y280783D01*
X461158Y281117D01*
X461200Y281492D01*
X461158Y281825D01*
X460950Y282158D01*
X460700Y282367D01*
X460450Y282408D01*
X460158Y282325D01*
X459950Y282033D01*
X459867Y281742D01*
Y281367D01*
G01Y281742D02*
X459742Y281992D01*
X459533Y282200D01*
X459283Y282283D01*
X459033Y282200D01*
X458825Y281992D01*
X458700Y281617D01*
X458742Y281242D01*
X458908Y280867D01*
G01X460825Y283633D02*
X461033Y283883D01*
X461158Y284175D01*
X461200Y284550D01*
X461117Y284925D01*
X460950Y285217D01*
X460658Y285425D01*
X460325Y285467D01*
X459992Y285383D01*
X459783Y285175D01*
X459617Y284883D01*
X459575Y284592D01*
X459617Y284300D01*
X459783Y283925D01*
X458700Y284050D01*
Y285175D01*
G01X487171Y2098D02*
Y21798D01*
X483271D01*
Y52848D01*
X472621D01*
Y81698D01*
X479321D01*
Y116298D01*
X504721D01*
Y106698D01*
X506521D01*
Y80098D01*
X508671D01*
Y59998D01*
X506521D01*
Y43498D01*
X753321D01*
Y59998D01*
X751171D01*
Y80098D01*
X753321D01*
Y106698D01*
X755121D01*
Y116298D01*
X780521D01*
Y81698D01*
X787221D01*
Y52848D01*
X776571D01*
Y21798D01*
X772671D01*
Y2098D01*
X487171D01*
G01X500500Y131500D02*
Y121000D01*
X478000D01*
Y95500D01*
X472000D01*
Y85000D01*
G01X469000Y76567D02*
X466500D01*
Y77608D01*
X466625Y77942D01*
X466792Y78150D01*
X467125Y78233D01*
X467458Y78150D01*
X467667Y77900D01*
X467792Y77608D01*
Y76567D01*
G01Y77608D02*
X469000Y78233D01*
G01X468625Y79583D02*
X468833Y79833D01*
X468958Y80125D01*
X469000Y80500D01*
X468917Y80875D01*
X468750Y81167D01*
X468458Y81375D01*
X468125Y81417D01*
X467792Y81333D01*
X467583Y81125D01*
X467417Y80833D01*
X467375Y80542D01*
X467417Y80250D01*
X467583Y79875D01*
X466500Y80000D01*
Y81125D01*
G01X469000Y84100D02*
X466500D01*
X468292Y82558D01*
Y84642D01*
G01X476167Y99500D02*
X470833D01*
Y106500D01*
X476167D01*
G01X474033Y103117D02*
X470833D01*
G01X467500Y94967D02*
X465000D01*
Y95967D01*
X465125Y96300D01*
X465417Y96550D01*
X465750Y96633D01*
X466083Y96550D01*
X466333Y96342D01*
X466458Y95967D01*
Y94967D01*
G01X465208Y99817D02*
X465083Y99567D01*
X465000Y99275D01*
Y98942D01*
X465125Y98567D01*
X465333Y98275D01*
X465583Y98067D01*
X466000Y97900D01*
X466375Y97858D01*
X466750Y97942D01*
X467000Y98067D01*
X467250Y98317D01*
X467417Y98608D01*
X467500Y98900D01*
Y99192D01*
X467417Y99483D01*
X467292Y99733D01*
X467125Y99942D01*
G01X467500Y102000D02*
X465000D01*
X465500Y101500D01*
G01X467500D02*
Y102500D01*
G01X465000Y105100D02*
X465083Y104767D01*
X465292Y104517D01*
X465542Y104350D01*
X465875Y104225D01*
X466250Y104183D01*
X466625Y104225D01*
X466958Y104350D01*
X467208Y104517D01*
X467417Y104767D01*
X467500Y105100D01*
X467417Y105433D01*
X467208Y105683D01*
X466958Y105850D01*
X466625Y105975D01*
X466250Y106017D01*
X465875Y105975D01*
X465542Y105850D01*
X465292Y105683D01*
X465083Y105433D01*
X465000Y105100D01*
G01Y108200D02*
X465083Y107867D01*
X465292Y107617D01*
X465542Y107450D01*
X465875Y107325D01*
X466250Y107283D01*
X466625Y107325D01*
X466958Y107450D01*
X467208Y107617D01*
X467417Y107867D01*
X467500Y108200D01*
X467417Y108533D01*
X467208Y108783D01*
X466958Y108950D01*
X466625Y109075D01*
X466250Y109117D01*
X465875Y109075D01*
X465542Y108950D01*
X465292Y108783D01*
X465083Y108533D01*
X465000Y108200D01*
G01X477000Y110967D02*
X474500D01*
Y111967D01*
X474625Y112300D01*
X474917Y112550D01*
X475250Y112633D01*
X475583Y112550D01*
X475833Y112342D01*
X475958Y111967D01*
Y110967D01*
G01X477000Y114067D02*
X474500D01*
Y115108D01*
X474625Y115442D01*
X474792Y115650D01*
X475125Y115733D01*
X475458Y115650D01*
X475667Y115400D01*
X475792Y115108D01*
Y114067D01*
G01Y115108D02*
X477000Y115733D01*
G01Y118000D02*
X474500D01*
X475000Y117500D01*
G01X477000D02*
Y118500D01*
G01X475958Y120308D02*
X475667Y120600D01*
X475500Y120850D01*
X475417Y121183D01*
X475500Y121475D01*
X475667Y121683D01*
X475917Y121850D01*
X476208Y121892D01*
X476458Y121850D01*
X476708Y121683D01*
X476917Y121433D01*
X477000Y121142D01*
X476917Y120808D01*
X476667Y120517D01*
X476292Y120350D01*
X475875Y120308D01*
X475333Y120392D01*
X475042Y120517D01*
X474750Y120725D01*
X474542Y121017D01*
X474500Y121308D01*
X474583Y121600D01*
X474792Y121808D01*
G01X476500Y123283D02*
X476792Y123533D01*
X476958Y123867D01*
X477000Y124242D01*
X476958Y124575D01*
X476750Y124908D01*
X476500Y125117D01*
X476250Y125158D01*
X475958Y125075D01*
X475750Y124783D01*
X475667Y124492D01*
Y124117D01*
G01Y124492D02*
X475542Y124742D01*
X475333Y124950D01*
X475083Y125033D01*
X474833Y124950D01*
X474625Y124742D01*
X474500Y124367D01*
X474542Y123992D01*
X474708Y123617D01*
G01X469500Y111967D02*
X467000D01*
Y112967D01*
X467125Y113300D01*
X467417Y113550D01*
X467750Y113633D01*
X468083Y113550D01*
X468333Y113342D01*
X468458Y112967D01*
Y111967D01*
G01X467208Y116817D02*
X467083Y116567D01*
X467000Y116275D01*
Y115942D01*
X467125Y115567D01*
X467333Y115275D01*
X467583Y115067D01*
X468000Y114900D01*
X468375Y114858D01*
X468750Y114942D01*
X469000Y115067D01*
X469250Y115317D01*
X469417Y115608D01*
X469500Y115900D01*
Y116192D01*
X469417Y116483D01*
X469292Y116733D01*
X469125Y116942D01*
G01X469500Y119000D02*
X467000D01*
X467500Y118500D01*
G01X469500D02*
Y119500D01*
G01Y122100D02*
X467000D01*
X467500Y121600D01*
G01X469500D02*
Y122600D01*
G01X467417Y124408D02*
X467167Y124658D01*
X467042Y124950D01*
X467000Y125283D01*
X467083Y125700D01*
X467292Y125992D01*
X467542Y126075D01*
X467792Y126033D01*
X468000Y125867D01*
X468417Y125033D01*
X468708Y124658D01*
X469125Y124408D01*
X469500Y124325D01*
Y126075D01*
G01X473500Y110967D02*
X471000D01*
Y111967D01*
X471125Y112300D01*
X471417Y112550D01*
X471750Y112633D01*
X472083Y112550D01*
X472333Y112342D01*
X472458Y111967D01*
Y110967D01*
G01X471208Y115817D02*
X471083Y115567D01*
X471000Y115275D01*
Y114942D01*
X471125Y114567D01*
X471333Y114275D01*
X471583Y114067D01*
X472000Y113900D01*
X472375Y113858D01*
X472750Y113942D01*
X473000Y114067D01*
X473250Y114317D01*
X473417Y114608D01*
X473500Y114900D01*
Y115192D01*
X473417Y115483D01*
X473292Y115733D01*
X473125Y115942D01*
G01X473500Y118000D02*
X471000D01*
X471500Y117500D01*
G01X473500D02*
Y118500D01*
G01Y121100D02*
X471000D01*
X471500Y120600D01*
G01X473500D02*
Y121600D01*
G01X473000Y123283D02*
X473292Y123533D01*
X473458Y123867D01*
X473500Y124242D01*
X473458Y124575D01*
X473250Y124908D01*
X473000Y125117D01*
X472750Y125158D01*
X472458Y125075D01*
X472250Y124783D01*
X472167Y124492D01*
Y124117D01*
G01Y124492D02*
X472042Y124742D01*
X471833Y124950D01*
X471583Y125033D01*
X471333Y124950D01*
X471125Y124742D01*
X471000Y124367D01*
X471042Y123992D01*
X471208Y123617D01*
G01X475000Y129967D02*
X472500D01*
Y130967D01*
X472625Y131300D01*
X472917Y131550D01*
X473250Y131633D01*
X473583Y131550D01*
X473833Y131342D01*
X473958Y130967D01*
Y129967D01*
G01X475000Y133067D02*
X472500D01*
Y134108D01*
X472625Y134442D01*
X472792Y134650D01*
X473125Y134733D01*
X473458Y134650D01*
X473667Y134400D01*
X473792Y134108D01*
Y133067D01*
G01Y134108D02*
X475000Y134733D01*
G01Y137000D02*
X472500D01*
X473000Y136500D01*
G01X475000D02*
Y137500D01*
G01X474625Y139183D02*
X474833Y139433D01*
X474958Y139725D01*
X475000Y140100D01*
X474917Y140475D01*
X474750Y140767D01*
X474458Y140975D01*
X474125Y141017D01*
X473792Y140933D01*
X473583Y140725D01*
X473417Y140433D01*
X473375Y140142D01*
X473417Y139850D01*
X473583Y139475D01*
X472500Y139600D01*
Y140725D01*
G01X475000Y143200D02*
X472500D01*
X473000Y142700D01*
G01X475000D02*
Y143700D01*
G01X479000Y129967D02*
X476500D01*
Y130967D01*
X476625Y131300D01*
X476917Y131550D01*
X477250Y131633D01*
X477583Y131550D01*
X477833Y131342D01*
X477958Y130967D01*
Y129967D01*
G01X479000Y133067D02*
X476500D01*
Y134108D01*
X476625Y134442D01*
X476792Y134650D01*
X477125Y134733D01*
X477458Y134650D01*
X477667Y134400D01*
X477792Y134108D01*
Y133067D01*
G01Y134108D02*
X479000Y134733D01*
G01Y137000D02*
X476500D01*
X477000Y136500D01*
G01X479000D02*
Y137500D01*
G01X478625Y139183D02*
X478833Y139433D01*
X478958Y139725D01*
X479000Y140100D01*
X478917Y140475D01*
X478750Y140767D01*
X478458Y140975D01*
X478125Y141017D01*
X477792Y140933D01*
X477583Y140725D01*
X477417Y140433D01*
X477375Y140142D01*
X477417Y139850D01*
X477583Y139475D01*
X476500Y139600D01*
Y140725D01*
G01X479000Y143117D02*
X478458Y143200D01*
X478000Y143325D01*
X477583Y143492D01*
X477125Y143700D01*
X476500Y144033D01*
Y142367D01*
G01X498000Y150000D02*
X467500D01*
Y140000D01*
G01X467467Y152200D02*
Y154700D01*
X468467D01*
X468800Y154575D01*
X469050Y154283D01*
X469133Y153950D01*
X469050Y153617D01*
X468842Y153367D01*
X468467Y153242D01*
X467467D01*
G01X470567Y152200D02*
Y154700D01*
X471608D01*
X471942Y154575D01*
X472150Y154408D01*
X472233Y154075D01*
X472150Y153742D01*
X471900Y153533D01*
X471608Y153408D01*
X470567D01*
G01X471608D02*
X472233Y152200D01*
G01X474500D02*
Y154700D01*
X474000Y154200D01*
G01Y152200D02*
X475000D01*
G01X477600D02*
Y154700D01*
X477100Y154200D01*
G01Y152200D02*
X478100D01*
G01X480617D02*
X480700Y152742D01*
X480825Y153200D01*
X480992Y153617D01*
X481200Y154075D01*
X481533Y154700D01*
X479867D01*
G01X467517Y156200D02*
Y158700D01*
X468517D01*
X468850Y158575D01*
X469100Y158283D01*
X469183Y157950D01*
X469100Y157617D01*
X468892Y157367D01*
X468517Y157242D01*
X467517D01*
G01X472367Y158492D02*
X472117Y158617D01*
X471825Y158700D01*
X471492D01*
X471117Y158575D01*
X470825Y158367D01*
X470617Y158117D01*
X470450Y157700D01*
X470408Y157325D01*
X470492Y156950D01*
X470617Y156700D01*
X470867Y156450D01*
X471158Y156283D01*
X471450Y156200D01*
X471742D01*
X472033Y156283D01*
X472283Y156408D01*
X472492Y156575D01*
G01X474467Y156200D02*
X474550Y156742D01*
X474675Y157200D01*
X474842Y157617D01*
X475050Y158075D01*
X475383Y158700D01*
X473717D01*
G01X476942Y156492D02*
X477233Y156283D01*
X477567Y156200D01*
X477900Y156283D01*
X478192Y156533D01*
X478400Y156908D01*
X478483Y157283D01*
Y157742D01*
X478400Y158117D01*
X478192Y158450D01*
X477942Y158617D01*
X477650Y158700D01*
X477317Y158617D01*
X477067Y158450D01*
X476900Y158200D01*
X476817Y157867D01*
X476900Y157575D01*
X477108Y157283D01*
X477358Y157117D01*
X477650Y157075D01*
X477983Y157158D01*
X478233Y157367D01*
X478483Y157742D01*
G01X766766Y283298D02*
Y263598D01*
X770666D01*
Y232548D01*
X781316D01*
Y203698D01*
X774616D01*
Y169098D01*
X749216D01*
Y178698D01*
X747416D01*
Y205298D01*
X745266D01*
Y225398D01*
X747416D01*
Y241898D01*
X500616D01*
Y225398D01*
X502766D01*
Y205298D01*
X500616D01*
Y178698D01*
X498816D01*
Y169098D01*
X473416D01*
Y203698D01*
X466716D01*
Y232548D01*
X477366D01*
Y263598D01*
X481266D01*
Y283298D01*
X766766D01*
G01X469317Y238792D02*
X469067Y238917D01*
X468775Y239000D01*
X468442D01*
X468067Y238875D01*
X467775Y238667D01*
X467567Y238417D01*
X467400Y238000D01*
X467358Y237625D01*
X467442Y237250D01*
X467567Y237000D01*
X467817Y236750D01*
X468108Y236583D01*
X468400Y236500D01*
X468692D01*
X468983Y236583D01*
X469233Y236708D01*
X469442Y236875D01*
G01X470792Y236792D02*
X471083Y236583D01*
X471417Y236500D01*
X471750Y236583D01*
X472042Y236833D01*
X472250Y237208D01*
X472333Y237583D01*
Y238042D01*
X472250Y238417D01*
X472042Y238750D01*
X471792Y238917D01*
X471500Y239000D01*
X471167Y238917D01*
X470917Y238750D01*
X470750Y238500D01*
X470667Y238167D01*
X470750Y237875D01*
X470958Y237583D01*
X471208Y237417D01*
X471500Y237375D01*
X471833Y237458D01*
X472083Y237667D01*
X472333Y238042D01*
G01X474600Y236500D02*
X474892Y236542D01*
X475225Y236667D01*
X475433Y236875D01*
X475517Y237167D01*
X475433Y237458D01*
X475183Y237708D01*
X474808Y237833D01*
X474392D01*
X474142Y237917D01*
X473933Y238125D01*
X473850Y238417D01*
X473975Y238708D01*
X474267Y238917D01*
X474600Y239000D01*
X474933Y238917D01*
X475225Y238708D01*
X475350Y238417D01*
X475267Y238125D01*
X475058Y237917D01*
X474808Y237833D01*
X474392D01*
X474017Y237708D01*
X473767Y237458D01*
X473683Y237167D01*
X473767Y236875D01*
X473975Y236667D01*
X474308Y236542D01*
X474600Y236500D01*
G01X469200Y274417D02*
X466700D01*
Y275458D01*
X466825Y275792D01*
X466992Y276000D01*
X467325Y276083D01*
X467658Y276000D01*
X467867Y275750D01*
X467992Y275458D01*
Y274417D01*
G01Y275458D02*
X469200Y276083D01*
G01X467117Y277558D02*
X466867Y277808D01*
X466742Y278100D01*
X466700Y278433D01*
X466783Y278850D01*
X466992Y279142D01*
X467242Y279225D01*
X467492Y279183D01*
X467700Y279017D01*
X468117Y278183D01*
X468408Y277808D01*
X468825Y277558D01*
X469200Y277475D01*
Y279225D01*
G01X468700Y280533D02*
X468992Y280783D01*
X469158Y281117D01*
X469200Y281492D01*
X469158Y281825D01*
X468950Y282158D01*
X468700Y282367D01*
X468450Y282408D01*
X468158Y282325D01*
X467950Y282033D01*
X467867Y281742D01*
Y281367D01*
G01Y281742D02*
X467742Y281992D01*
X467533Y282200D01*
X467283Y282283D01*
X467033Y282200D01*
X466825Y281992D01*
X466700Y281617D01*
X466742Y281242D01*
X466908Y280867D01*
G01X466700Y284550D02*
X466783Y284217D01*
X466992Y283967D01*
X467242Y283800D01*
X467575Y283675D01*
X467950Y283633D01*
X468325Y283675D01*
X468658Y283800D01*
X468908Y283967D01*
X469117Y284217D01*
X469200Y284550D01*
X469117Y284883D01*
X468908Y285133D01*
X468658Y285300D01*
X468325Y285425D01*
X467950Y285467D01*
X467575Y285425D01*
X467242Y285300D01*
X466992Y285133D01*
X466783Y284883D01*
X466700Y284550D01*
G01X473200Y274417D02*
X470700D01*
Y275458D01*
X470825Y275792D01*
X470992Y276000D01*
X471325Y276083D01*
X471658Y276000D01*
X471867Y275750D01*
X471992Y275458D01*
Y274417D01*
G01Y275458D02*
X473200Y276083D01*
G01X471117Y277558D02*
X470867Y277808D01*
X470742Y278100D01*
X470700Y278433D01*
X470783Y278850D01*
X470992Y279142D01*
X471242Y279225D01*
X471492Y279183D01*
X471700Y279017D01*
X472117Y278183D01*
X472408Y277808D01*
X472825Y277558D01*
X473200Y277475D01*
Y279225D01*
G01X471117Y280658D02*
X470867Y280908D01*
X470742Y281200D01*
X470700Y281533D01*
X470783Y281950D01*
X470992Y282242D01*
X471242Y282325D01*
X471492Y282283D01*
X471700Y282117D01*
X472117Y281283D01*
X472408Y280908D01*
X472825Y280658D01*
X473200Y280575D01*
Y282325D01*
G01X472908Y283842D02*
X473117Y284133D01*
X473200Y284467D01*
X473117Y284800D01*
X472867Y285092D01*
X472492Y285300D01*
X472117Y285383D01*
X471658D01*
X471283Y285300D01*
X470950Y285092D01*
X470783Y284842D01*
X470700Y284550D01*
X470783Y284217D01*
X470950Y283967D01*
X471200Y283800D01*
X471533Y283717D01*
X471825Y283800D01*
X472117Y284008D01*
X472283Y284258D01*
X472325Y284550D01*
X472242Y284883D01*
X472033Y285133D01*
X471658Y285383D01*
G01X483517Y133500D02*
Y136000D01*
X484558D01*
X484892Y135875D01*
X485100Y135708D01*
X485183Y135375D01*
X485100Y135042D01*
X484850Y134833D01*
X484558Y134708D01*
X483517D01*
G01X484558D02*
X485183Y133500D01*
G01X487950D02*
Y136000D01*
X486408Y134208D01*
X488492D01*
G01X489758Y134542D02*
X490050Y134833D01*
X490300Y135000D01*
X490633Y135083D01*
X490925Y135000D01*
X491133Y134833D01*
X491300Y134583D01*
X491342Y134292D01*
X491300Y134042D01*
X491133Y133792D01*
X490883Y133583D01*
X490592Y133500D01*
X490258Y133583D01*
X489967Y133833D01*
X489800Y134208D01*
X489758Y134625D01*
X489842Y135167D01*
X489967Y135458D01*
X490175Y135750D01*
X490467Y135958D01*
X490758Y136000D01*
X491050Y135917D01*
X491258Y135708D01*
G01X493650Y136000D02*
X493317Y135917D01*
X493067Y135708D01*
X492900Y135458D01*
X492775Y135125D01*
X492733Y134750D01*
X492775Y134375D01*
X492900Y134042D01*
X493067Y133792D01*
X493317Y133583D01*
X493650Y133500D01*
X493983Y133583D01*
X494233Y133792D01*
X494400Y134042D01*
X494525Y134375D01*
X494567Y134750D01*
X494525Y135125D01*
X494400Y135458D01*
X494233Y135708D01*
X493983Y135917D01*
X493650Y136000D01*
G01X481567Y123000D02*
Y125500D01*
X482608D01*
X482942Y125375D01*
X483150Y125208D01*
X483233Y124875D01*
X483150Y124542D01*
X482900Y124333D01*
X482608Y124208D01*
X481567D01*
G01X482608D02*
X483233Y123000D01*
G01X484708Y124042D02*
X485000Y124333D01*
X485250Y124500D01*
X485583Y124583D01*
X485875Y124500D01*
X486083Y124333D01*
X486250Y124083D01*
X486292Y123792D01*
X486250Y123542D01*
X486083Y123292D01*
X485833Y123083D01*
X485542Y123000D01*
X485208Y123083D01*
X484917Y123333D01*
X484750Y123708D01*
X484708Y124125D01*
X484792Y124667D01*
X484917Y124958D01*
X485125Y125250D01*
X485417Y125458D01*
X485708Y125500D01*
X486000Y125417D01*
X486208Y125208D01*
G01X488600Y123000D02*
Y125500D01*
X488100Y125000D01*
G01Y123000D02*
X489100D01*
G01X486067Y128000D02*
Y130500D01*
X487108D01*
X487442Y130375D01*
X487650Y130208D01*
X487733Y129875D01*
X487650Y129542D01*
X487400Y129333D01*
X487108Y129208D01*
X486067D01*
G01X487108D02*
X487733Y128000D01*
G01X489208Y129042D02*
X489500Y129333D01*
X489750Y129500D01*
X490083Y129583D01*
X490375Y129500D01*
X490583Y129333D01*
X490750Y129083D01*
X490792Y128792D01*
X490750Y128542D01*
X490583Y128292D01*
X490333Y128083D01*
X490042Y128000D01*
X489708Y128083D01*
X489417Y128333D01*
X489250Y128708D01*
X489208Y129125D01*
X489292Y129667D01*
X489417Y129958D01*
X489625Y130250D01*
X489917Y130458D01*
X490208Y130500D01*
X490500Y130417D01*
X490708Y130208D01*
G01X492308Y130083D02*
X492558Y130333D01*
X492850Y130458D01*
X493183Y130500D01*
X493600Y130417D01*
X493892Y130208D01*
X493975Y129958D01*
X493933Y129708D01*
X493767Y129500D01*
X492933Y129083D01*
X492558Y128792D01*
X492308Y128375D01*
X492225Y128000D01*
X493975D01*
G01X490667Y123000D02*
Y125500D01*
X491708D01*
X492042Y125375D01*
X492250Y125208D01*
X492333Y124875D01*
X492250Y124542D01*
X492000Y124333D01*
X491708Y124208D01*
X490667D01*
G01X491708D02*
X492333Y123000D01*
G01X493808Y124042D02*
X494100Y124333D01*
X494350Y124500D01*
X494683Y124583D01*
X494975Y124500D01*
X495183Y124333D01*
X495350Y124083D01*
X495392Y123792D01*
X495350Y123542D01*
X495183Y123292D01*
X494933Y123083D01*
X494642Y123000D01*
X494308Y123083D01*
X494017Y123333D01*
X493850Y123708D01*
X493808Y124125D01*
X493892Y124667D01*
X494017Y124958D01*
X494225Y125250D01*
X494517Y125458D01*
X494808Y125500D01*
X495100Y125417D01*
X495308Y125208D01*
G01X497617Y123000D02*
X497700Y123542D01*
X497825Y124000D01*
X497992Y124417D01*
X498200Y124875D01*
X498533Y125500D01*
X496867D01*
G01X483017Y138500D02*
Y141000D01*
X484058D01*
X484392Y140875D01*
X484600Y140708D01*
X484683Y140375D01*
X484600Y140042D01*
X484350Y139833D01*
X484058Y139708D01*
X483017D01*
G01X484058D02*
X484683Y138500D01*
G01X487450D02*
Y141000D01*
X485908Y139208D01*
X487992D01*
G01X489258Y139542D02*
X489550Y139833D01*
X489800Y140000D01*
X490133Y140083D01*
X490425Y140000D01*
X490633Y139833D01*
X490800Y139583D01*
X490842Y139292D01*
X490800Y139042D01*
X490633Y138792D01*
X490383Y138583D01*
X490092Y138500D01*
X489758Y138583D01*
X489467Y138833D01*
X489300Y139208D01*
X489258Y139625D01*
X489342Y140167D01*
X489467Y140458D01*
X489675Y140750D01*
X489967Y140958D01*
X490258Y141000D01*
X490550Y140917D01*
X490758Y140708D01*
G01X492233Y138875D02*
X492483Y138667D01*
X492775Y138542D01*
X493150Y138500D01*
X493525Y138583D01*
X493817Y138750D01*
X494025Y139042D01*
X494067Y139375D01*
X493983Y139708D01*
X493775Y139917D01*
X493483Y140083D01*
X493192Y140125D01*
X492900Y140083D01*
X492525Y139917D01*
X492650Y141000D01*
X493775D01*
G01X483017Y144500D02*
Y147000D01*
X484058D01*
X484392Y146875D01*
X484600Y146708D01*
X484683Y146375D01*
X484600Y146042D01*
X484350Y145833D01*
X484058Y145708D01*
X483017D01*
G01X484058D02*
X484683Y144500D01*
G01X486950D02*
Y147000D01*
X486450Y146500D01*
G01Y144500D02*
X487450D01*
G01X489258Y145542D02*
X489550Y145833D01*
X489800Y146000D01*
X490133Y146083D01*
X490425Y146000D01*
X490633Y145833D01*
X490800Y145583D01*
X490842Y145292D01*
X490800Y145042D01*
X490633Y144792D01*
X490383Y144583D01*
X490092Y144500D01*
X489758Y144583D01*
X489467Y144833D01*
X489300Y145208D01*
X489258Y145625D01*
X489342Y146167D01*
X489467Y146458D01*
X489675Y146750D01*
X489967Y146958D01*
X490258Y147000D01*
X490550Y146917D01*
X490758Y146708D01*
G01X492358Y145542D02*
X492650Y145833D01*
X492900Y146000D01*
X493233Y146083D01*
X493525Y146000D01*
X493733Y145833D01*
X493900Y145583D01*
X493942Y145292D01*
X493900Y145042D01*
X493733Y144792D01*
X493483Y144583D01*
X493192Y144500D01*
X492858Y144583D01*
X492567Y144833D01*
X492400Y145208D01*
X492358Y145625D01*
X492442Y146167D01*
X492567Y146458D01*
X492775Y146750D01*
X493067Y146958D01*
X493358Y147000D01*
X493650Y146917D01*
X493858Y146708D01*
G01X502250Y4000D02*
Y6500D01*
X501750Y6000D01*
G01Y4000D02*
X502750D01*
G01X505321Y1998D02*
Y1948D01*
X503371Y-2D01*
X503471Y-102D01*
X507271D01*
Y98D01*
X505321Y2048D01*
Y-2202D01*
G01X513000Y69017D02*
X510500D01*
Y70058D01*
X510625Y70392D01*
X510792Y70600D01*
X511125Y70683D01*
X511458Y70600D01*
X511667Y70350D01*
X511792Y70058D01*
Y69017D01*
G01Y70058D02*
X513000Y70683D01*
G01X512625Y72033D02*
X512833Y72283D01*
X512958Y72575D01*
X513000Y72950D01*
X512917Y73325D01*
X512750Y73617D01*
X512458Y73825D01*
X512125Y73867D01*
X511792Y73783D01*
X511583Y73575D01*
X511417Y73283D01*
X511375Y72992D01*
X511417Y72700D01*
X511583Y72325D01*
X510500Y72450D01*
Y73575D01*
G01Y76050D02*
X510583Y75717D01*
X510792Y75467D01*
X511042Y75300D01*
X511375Y75175D01*
X511750Y75133D01*
X512125Y75175D01*
X512458Y75300D01*
X512708Y75467D01*
X512917Y75717D01*
X513000Y76050D01*
X512917Y76383D01*
X512708Y76633D01*
X512458Y76800D01*
X512125Y76925D01*
X511750Y76967D01*
X511375Y76925D01*
X511042Y76800D01*
X510792Y76633D01*
X510583Y76383D01*
X510500Y76050D01*
G01X511958Y78358D02*
X511667Y78650D01*
X511500Y78900D01*
X511417Y79233D01*
X511500Y79525D01*
X511667Y79733D01*
X511917Y79900D01*
X512208Y79942D01*
X512458Y79900D01*
X512708Y79733D01*
X512917Y79483D01*
X513000Y79192D01*
X512917Y78858D01*
X512667Y78567D01*
X512292Y78400D01*
X511875Y78358D01*
X511333Y78442D01*
X511042Y78567D01*
X510750Y78775D01*
X510542Y79067D01*
X510500Y79358D01*
X510583Y79650D01*
X510792Y79858D01*
G01X508067Y118500D02*
Y121000D01*
X509108D01*
X509442Y120875D01*
X509650Y120708D01*
X509733Y120375D01*
X509650Y120042D01*
X509400Y119833D01*
X509108Y119708D01*
X508067D01*
G01X509108D02*
X509733Y118500D01*
G01X511208Y120583D02*
X511458Y120833D01*
X511750Y120958D01*
X512083Y121000D01*
X512500Y120917D01*
X512792Y120708D01*
X512875Y120458D01*
X512833Y120208D01*
X512667Y120000D01*
X511833Y119583D01*
X511458Y119292D01*
X511208Y118875D01*
X511125Y118500D01*
X512875D01*
G01X514392Y118792D02*
X514683Y118583D01*
X515017Y118500D01*
X515350Y118583D01*
X515642Y118833D01*
X515850Y119208D01*
X515933Y119583D01*
Y120042D01*
X515850Y120417D01*
X515642Y120750D01*
X515392Y120917D01*
X515100Y121000D01*
X514767Y120917D01*
X514517Y120750D01*
X514350Y120500D01*
X514267Y120167D01*
X514350Y119875D01*
X514558Y119583D01*
X514808Y119417D01*
X515100Y119375D01*
X515433Y119458D01*
X515683Y119667D01*
X515933Y120042D01*
G01X508067Y114500D02*
Y117000D01*
X509108D01*
X509442Y116875D01*
X509650Y116708D01*
X509733Y116375D01*
X509650Y116042D01*
X509400Y115833D01*
X509108Y115708D01*
X508067D01*
G01X509108D02*
X509733Y114500D01*
G01X511208Y116583D02*
X511458Y116833D01*
X511750Y116958D01*
X512083Y117000D01*
X512500Y116917D01*
X512792Y116708D01*
X512875Y116458D01*
X512833Y116208D01*
X512667Y116000D01*
X511833Y115583D01*
X511458Y115292D01*
X511208Y114875D01*
X511125Y114500D01*
X512875D01*
G01X515100D02*
X515392Y114542D01*
X515725Y114667D01*
X515933Y114875D01*
X516017Y115167D01*
X515933Y115458D01*
X515683Y115708D01*
X515308Y115833D01*
X514892D01*
X514642Y115917D01*
X514433Y116125D01*
X514350Y116417D01*
X514475Y116708D01*
X514767Y116917D01*
X515100Y117000D01*
X515433Y116917D01*
X515725Y116708D01*
X515850Y116417D01*
X515767Y116125D01*
X515558Y115917D01*
X515308Y115833D01*
X514892D01*
X514517Y115708D01*
X514267Y115458D01*
X514183Y115167D01*
X514267Y114875D01*
X514475Y114667D01*
X514808Y114542D01*
X515100Y114500D01*
G01X508067Y107000D02*
Y109500D01*
X509108D01*
X509442Y109375D01*
X509650Y109208D01*
X509733Y108875D01*
X509650Y108542D01*
X509400Y108333D01*
X509108Y108208D01*
X508067D01*
G01X509108D02*
X509733Y107000D01*
G01X511208Y109083D02*
X511458Y109333D01*
X511750Y109458D01*
X512083Y109500D01*
X512500Y109417D01*
X512792Y109208D01*
X512875Y108958D01*
X512833Y108708D01*
X512667Y108500D01*
X511833Y108083D01*
X511458Y107792D01*
X511208Y107375D01*
X511125Y107000D01*
X512875D01*
G01X514308Y108042D02*
X514600Y108333D01*
X514850Y108500D01*
X515183Y108583D01*
X515475Y108500D01*
X515683Y108333D01*
X515850Y108083D01*
X515892Y107792D01*
X515850Y107542D01*
X515683Y107292D01*
X515433Y107083D01*
X515142Y107000D01*
X514808Y107083D01*
X514517Y107333D01*
X514350Y107708D01*
X514308Y108125D01*
X514392Y108667D01*
X514517Y108958D01*
X514725Y109250D01*
X515017Y109458D01*
X515308Y109500D01*
X515600Y109417D01*
X515808Y109208D01*
G01X508167Y110700D02*
Y113200D01*
X509208D01*
X509542Y113075D01*
X509750Y112908D01*
X509833Y112575D01*
X509750Y112242D01*
X509500Y112033D01*
X509208Y111908D01*
X508167D01*
G01X509208D02*
X509833Y110700D01*
G01X511308Y112783D02*
X511558Y113033D01*
X511850Y113158D01*
X512183Y113200D01*
X512600Y113117D01*
X512892Y112908D01*
X512975Y112658D01*
X512933Y112408D01*
X512767Y112200D01*
X511933Y111783D01*
X511558Y111492D01*
X511308Y111075D01*
X511225Y110700D01*
X512975D01*
G01X515117D02*
X515200Y111242D01*
X515325Y111700D01*
X515492Y112117D01*
X515700Y112575D01*
X516033Y113200D01*
X514367D01*
G01X499000Y130450D02*
X498958Y130117D01*
X498792Y129825D01*
X498542Y129575D01*
X498250Y129408D01*
X497917Y129325D01*
X497583D01*
X497250Y129408D01*
X496958Y129575D01*
X496708Y129825D01*
X496542Y130117D01*
X496500Y130450D01*
X496542Y130783D01*
X496708Y131075D01*
X496958Y131325D01*
X497250Y131492D01*
X497583Y131575D01*
X497917D01*
X498250Y131492D01*
X498542Y131325D01*
X498792Y131075D01*
X498958Y130783D01*
X499000Y130450D01*
G01X498333Y130783D02*
X499000Y131283D01*
G01X498625Y132633D02*
X498833Y132883D01*
X498958Y133175D01*
X499000Y133550D01*
X498917Y133925D01*
X498750Y134217D01*
X498458Y134425D01*
X498125Y134467D01*
X497792Y134383D01*
X497583Y134175D01*
X497417Y133883D01*
X497375Y133592D01*
X497417Y133300D01*
X497583Y132925D01*
X496500Y133050D01*
Y134175D01*
G01X508067Y122500D02*
Y125000D01*
X509108D01*
X509442Y124875D01*
X509650Y124708D01*
X509733Y124375D01*
X509650Y124042D01*
X509400Y123833D01*
X509108Y123708D01*
X508067D01*
G01X509108D02*
X509733Y122500D01*
G01X511083Y123000D02*
X511333Y122708D01*
X511667Y122542D01*
X512042Y122500D01*
X512375Y122542D01*
X512708Y122750D01*
X512917Y123000D01*
X512958Y123250D01*
X512875Y123542D01*
X512583Y123750D01*
X512292Y123833D01*
X511917D01*
G01X512292D02*
X512542Y123958D01*
X512750Y124167D01*
X512833Y124417D01*
X512750Y124667D01*
X512542Y124875D01*
X512167Y125000D01*
X511792Y124958D01*
X511417Y124792D01*
G01X515100Y125000D02*
X514767Y124917D01*
X514517Y124708D01*
X514350Y124458D01*
X514225Y124125D01*
X514183Y123750D01*
X514225Y123375D01*
X514350Y123042D01*
X514517Y122792D01*
X514767Y122583D01*
X515100Y122500D01*
X515433Y122583D01*
X515683Y122792D01*
X515850Y123042D01*
X515975Y123375D01*
X516017Y123750D01*
X515975Y124125D01*
X515850Y124458D01*
X515683Y124708D01*
X515433Y124917D01*
X515100Y125000D01*
G01X508067Y126500D02*
Y129000D01*
X509108D01*
X509442Y128875D01*
X509650Y128708D01*
X509733Y128375D01*
X509650Y128042D01*
X509400Y127833D01*
X509108Y127708D01*
X508067D01*
G01X509108D02*
X509733Y126500D01*
G01X511083Y127000D02*
X511333Y126708D01*
X511667Y126542D01*
X512042Y126500D01*
X512375Y126542D01*
X512708Y126750D01*
X512917Y127000D01*
X512958Y127250D01*
X512875Y127542D01*
X512583Y127750D01*
X512292Y127833D01*
X511917D01*
G01X512292D02*
X512542Y127958D01*
X512750Y128167D01*
X512833Y128417D01*
X512750Y128667D01*
X512542Y128875D01*
X512167Y129000D01*
X511792Y128958D01*
X511417Y128792D01*
G01X515100Y126500D02*
Y129000D01*
X514600Y128500D01*
G01Y126500D02*
X515600D01*
G01X500500Y146500D02*
Y150000D01*
X498000D01*
G01X499000Y139900D02*
X498958Y139567D01*
X498792Y139275D01*
X498542Y139025D01*
X498250Y138858D01*
X497917Y138775D01*
X497583D01*
X497250Y138858D01*
X496958Y139025D01*
X496708Y139275D01*
X496542Y139567D01*
X496500Y139900D01*
X496542Y140233D01*
X496708Y140525D01*
X496958Y140775D01*
X497250Y140942D01*
X497583Y141025D01*
X497917D01*
X498250Y140942D01*
X498542Y140775D01*
X498792Y140525D01*
X498958Y140233D01*
X499000Y139900D01*
G01X498333Y140233D02*
X499000Y140733D01*
G01Y143000D02*
X496500D01*
X497000Y142500D01*
G01X499000D02*
Y143500D01*
G01X497958Y145308D02*
X497667Y145600D01*
X497500Y145850D01*
X497417Y146183D01*
X497500Y146475D01*
X497667Y146683D01*
X497917Y146850D01*
X498208Y146892D01*
X498458Y146850D01*
X498708Y146683D01*
X498917Y146433D01*
X499000Y146142D01*
X498917Y145808D01*
X498667Y145517D01*
X498292Y145350D01*
X497875Y145308D01*
X497333Y145392D01*
X497042Y145517D01*
X496750Y145725D01*
X496542Y146017D01*
X496500Y146308D01*
X496583Y146600D01*
X496792Y146808D01*
G01X501817Y163792D02*
X501567Y163917D01*
X501275Y164000D01*
X500942D01*
X500567Y163875D01*
X500275Y163667D01*
X500067Y163417D01*
X499900Y163000D01*
X499858Y162625D01*
X499942Y162250D01*
X500067Y162000D01*
X500317Y161750D01*
X500608Y161583D01*
X500900Y161500D01*
X501192D01*
X501483Y161583D01*
X501733Y161708D01*
X501942Y161875D01*
G01X504000Y161500D02*
Y164000D01*
X503500Y163500D01*
G01Y161500D02*
X504500D01*
G01X506308Y163583D02*
X506558Y163833D01*
X506850Y163958D01*
X507183Y164000D01*
X507600Y163917D01*
X507892Y163708D01*
X507975Y163458D01*
X507933Y163208D01*
X507767Y163000D01*
X506933Y162583D01*
X506558Y162292D01*
X506308Y161875D01*
X506225Y161500D01*
X507975D01*
G01X501817Y167792D02*
X501567Y167917D01*
X501275Y168000D01*
X500942D01*
X500567Y167875D01*
X500275Y167667D01*
X500067Y167417D01*
X499900Y167000D01*
X499858Y166625D01*
X499942Y166250D01*
X500067Y166000D01*
X500317Y165750D01*
X500608Y165583D01*
X500900Y165500D01*
X501192D01*
X501483Y165583D01*
X501733Y165708D01*
X501942Y165875D01*
G01X504000Y165500D02*
Y168000D01*
X503500Y167500D01*
G01Y165500D02*
X504500D01*
G01X507100D02*
Y168000D01*
X506600Y167500D01*
G01Y165500D02*
X507600D01*
G01X501767Y159792D02*
X501517Y159917D01*
X501225Y160000D01*
X500892D01*
X500517Y159875D01*
X500225Y159667D01*
X500017Y159417D01*
X499850Y159000D01*
X499808Y158625D01*
X499892Y158250D01*
X500017Y158000D01*
X500267Y157750D01*
X500558Y157583D01*
X500850Y157500D01*
X501142D01*
X501433Y157583D01*
X501683Y157708D01*
X501892Y157875D01*
G01X503950Y157500D02*
Y160000D01*
X503450Y159500D01*
G01Y157500D02*
X504450D01*
G01X506133Y158000D02*
X506383Y157708D01*
X506717Y157542D01*
X507092Y157500D01*
X507425Y157542D01*
X507758Y157750D01*
X507967Y158000D01*
X508008Y158250D01*
X507925Y158542D01*
X507633Y158750D01*
X507342Y158833D01*
X506967D01*
G01X507342D02*
X507592Y158958D01*
X507800Y159167D01*
X507883Y159417D01*
X507800Y159667D01*
X507592Y159875D01*
X507217Y160000D01*
X506842Y159958D01*
X506467Y159792D01*
G01X510650Y157500D02*
Y160000D01*
X509108Y158208D01*
X511192D01*
G01X503000Y169567D02*
X500500D01*
Y170608D01*
X500625Y170942D01*
X500792Y171150D01*
X501125Y171233D01*
X501458Y171150D01*
X501667Y170900D01*
X501792Y170608D01*
Y169567D01*
G01Y170608D02*
X503000Y171233D01*
G01Y173500D02*
X500500D01*
X501000Y173000D01*
G01X503000D02*
Y174000D01*
G01X500500Y176600D02*
X500583Y176267D01*
X500792Y176017D01*
X501042Y175850D01*
X501375Y175725D01*
X501750Y175683D01*
X502125Y175725D01*
X502458Y175850D01*
X502708Y176017D01*
X502917Y176267D01*
X503000Y176600D01*
X502917Y176933D01*
X502708Y177183D01*
X502458Y177350D01*
X502125Y177475D01*
X501750Y177517D01*
X501375Y177475D01*
X501042Y177350D01*
X500792Y177183D01*
X500583Y176933D01*
X500500Y176600D01*
G01X507000Y170450D02*
X506958Y170117D01*
X506792Y169825D01*
X506542Y169575D01*
X506250Y169408D01*
X505917Y169325D01*
X505583D01*
X505250Y169408D01*
X504958Y169575D01*
X504708Y169825D01*
X504542Y170117D01*
X504500Y170450D01*
X504542Y170783D01*
X504708Y171075D01*
X504958Y171325D01*
X505250Y171492D01*
X505583Y171575D01*
X505917D01*
X506250Y171492D01*
X506542Y171325D01*
X506792Y171075D01*
X506958Y170783D01*
X507000Y170450D01*
G01X506333Y170783D02*
X507000Y171283D01*
G01Y173550D02*
X504500D01*
X505000Y173050D01*
G01X507000D02*
Y174050D01*
G01X509517Y181500D02*
Y184000D01*
X510558D01*
X510892Y183875D01*
X511100Y183708D01*
X511183Y183375D01*
X511100Y183042D01*
X510850Y182833D01*
X510558Y182708D01*
X509517D01*
G01X510558D02*
X511183Y181500D01*
G01X513450D02*
Y184000D01*
X512950Y183500D01*
G01Y181500D02*
X513950D01*
G01X516550D02*
Y184000D01*
X516050Y183500D01*
G01Y181500D02*
X517050D01*
G01X519650D02*
X519942Y181542D01*
X520275Y181667D01*
X520483Y181875D01*
X520567Y182167D01*
X520483Y182458D01*
X520233Y182708D01*
X519858Y182833D01*
X519442D01*
X519192Y182917D01*
X518983Y183125D01*
X518900Y183417D01*
X519025Y183708D01*
X519317Y183917D01*
X519650Y184000D01*
X519983Y183917D01*
X520275Y183708D01*
X520400Y183417D01*
X520317Y183125D01*
X520108Y182917D01*
X519858Y182833D01*
X519442D01*
X519067Y182708D01*
X518817Y182458D01*
X518733Y182167D01*
X518817Y181875D01*
X519025Y181667D01*
X519358Y181542D01*
X519650Y181500D01*
G01X509000Y187067D02*
X506500D01*
Y188108D01*
X506625Y188442D01*
X506792Y188650D01*
X507125Y188733D01*
X507458Y188650D01*
X507667Y188400D01*
X507792Y188108D01*
Y187067D01*
G01Y188108D02*
X509000Y188733D01*
G01Y191000D02*
X506500D01*
X507000Y190500D01*
G01X509000D02*
Y191500D01*
G01X508500Y193183D02*
X508792Y193433D01*
X508958Y193767D01*
X509000Y194142D01*
X508958Y194475D01*
X508750Y194808D01*
X508500Y195017D01*
X508250Y195058D01*
X507958Y194975D01*
X507750Y194683D01*
X507667Y194392D01*
Y194017D01*
G01Y194392D02*
X507542Y194642D01*
X507333Y194850D01*
X507083Y194933D01*
X506833Y194850D01*
X506625Y194642D01*
X506500Y194267D01*
X506542Y193892D01*
X506708Y193517D01*
G01X505000Y187067D02*
X502500D01*
Y188108D01*
X502625Y188442D01*
X502792Y188650D01*
X503125Y188733D01*
X503458Y188650D01*
X503667Y188400D01*
X503792Y188108D01*
Y187067D01*
G01Y188108D02*
X505000Y188733D01*
G01Y191000D02*
X502500D01*
X503000Y190500D01*
G01X505000D02*
Y191500D01*
G01X504625Y193183D02*
X504833Y193433D01*
X504958Y193725D01*
X505000Y194100D01*
X504917Y194475D01*
X504750Y194767D01*
X504458Y194975D01*
X504125Y195017D01*
X503792Y194933D01*
X503583Y194725D01*
X503417Y194433D01*
X503375Y194142D01*
X503417Y193850D01*
X503583Y193475D01*
X502500Y193600D01*
Y194725D01*
G01X510800Y205517D02*
X508300D01*
Y206517D01*
X508425Y206850D01*
X508717Y207100D01*
X509050Y207183D01*
X509383Y207100D01*
X509633Y206892D01*
X509758Y206517D01*
Y205517D01*
G01X508508Y210367D02*
X508383Y210117D01*
X508300Y209825D01*
Y209492D01*
X508425Y209117D01*
X508633Y208825D01*
X508883Y208617D01*
X509300Y208450D01*
X509675Y208408D01*
X510050Y208492D01*
X510300Y208617D01*
X510550Y208867D01*
X510717Y209158D01*
X510800Y209450D01*
Y209742D01*
X510717Y210033D01*
X510592Y210283D01*
X510425Y210492D01*
G01Y211633D02*
X510633Y211883D01*
X510758Y212175D01*
X510800Y212550D01*
X510717Y212925D01*
X510550Y213217D01*
X510258Y213425D01*
X509925Y213467D01*
X509592Y213383D01*
X509383Y213175D01*
X509217Y212883D01*
X509175Y212592D01*
X509217Y212300D01*
X509383Y211925D01*
X508300Y212050D01*
Y213175D01*
G01X508717Y214858D02*
X508467Y215108D01*
X508342Y215400D01*
X508300Y215733D01*
X508383Y216150D01*
X508592Y216442D01*
X508842Y216525D01*
X509092Y216483D01*
X509300Y216317D01*
X509717Y215483D01*
X510008Y215108D01*
X510425Y214858D01*
X510800Y214775D01*
Y216525D01*
G01X505017Y200000D02*
Y202500D01*
X506017D01*
X506350Y202375D01*
X506600Y202083D01*
X506683Y201750D01*
X506600Y201417D01*
X506392Y201167D01*
X506017Y201042D01*
X505017D01*
G01X509867Y202292D02*
X509617Y202417D01*
X509325Y202500D01*
X508992D01*
X508617Y202375D01*
X508325Y202167D01*
X508117Y201917D01*
X507950Y201500D01*
X507908Y201125D01*
X507992Y200750D01*
X508117Y200500D01*
X508367Y200250D01*
X508658Y200083D01*
X508950Y200000D01*
X509242D01*
X509533Y200083D01*
X509783Y200208D01*
X509992Y200375D01*
G01X512550Y200000D02*
Y202500D01*
X511008Y200708D01*
X513092D01*
G01X514442Y200292D02*
X514733Y200083D01*
X515067Y200000D01*
X515400Y200083D01*
X515692Y200333D01*
X515900Y200708D01*
X515983Y201083D01*
Y201542D01*
X515900Y201917D01*
X515692Y202250D01*
X515442Y202417D01*
X515150Y202500D01*
X514817Y202417D01*
X514567Y202250D01*
X514400Y202000D01*
X514317Y201667D01*
X514400Y201375D01*
X514608Y201083D01*
X514858Y200917D01*
X515150Y200875D01*
X515483Y200958D01*
X515733Y201167D01*
X515983Y201542D01*
G01X504508Y207267D02*
X504383Y207017D01*
X504300Y206725D01*
Y206392D01*
X504425Y206017D01*
X504633Y205725D01*
X504883Y205517D01*
X505300Y205350D01*
X505675Y205308D01*
X506050Y205392D01*
X506300Y205517D01*
X506550Y205767D01*
X506717Y206058D01*
X506800Y206350D01*
Y206642D01*
X506717Y206933D01*
X506592Y207183D01*
X506425Y207392D01*
G01X506800Y209450D02*
X504300D01*
X504800Y208950D01*
G01X506800D02*
Y209950D01*
G01X504300Y212550D02*
X504383Y212217D01*
X504592Y211967D01*
X504842Y211800D01*
X505175Y211675D01*
X505550Y211633D01*
X505925Y211675D01*
X506258Y211800D01*
X506508Y211967D01*
X506717Y212217D01*
X506800Y212550D01*
X506717Y212883D01*
X506508Y213133D01*
X506258Y213300D01*
X505925Y213425D01*
X505550Y213467D01*
X505175Y213425D01*
X504842Y213300D01*
X504592Y213133D01*
X504383Y212883D01*
X504300Y212550D01*
G01X505758Y214858D02*
X505467Y215150D01*
X505300Y215400D01*
X505217Y215733D01*
X505300Y216025D01*
X505467Y216233D01*
X505717Y216400D01*
X506008Y216442D01*
X506258Y216400D01*
X506508Y216233D01*
X506717Y215983D01*
X506800Y215692D01*
X506717Y215358D01*
X506467Y215067D01*
X506092Y214900D01*
X505675Y214858D01*
X505133Y214942D01*
X504842Y215067D01*
X504550Y215275D01*
X504342Y215567D01*
X504300Y215858D01*
X504383Y216150D01*
X504592Y216358D01*
G01X502967Y228000D02*
Y230500D01*
X503967D01*
X504300Y230375D01*
X504550Y230083D01*
X504633Y229750D01*
X504550Y229417D01*
X504342Y229167D01*
X503967Y229042D01*
X502967D01*
G01X507817Y230292D02*
X507567Y230417D01*
X507275Y230500D01*
X506942D01*
X506567Y230375D01*
X506275Y230167D01*
X506067Y229917D01*
X505900Y229500D01*
X505858Y229125D01*
X505942Y228750D01*
X506067Y228500D01*
X506317Y228250D01*
X506608Y228083D01*
X506900Y228000D01*
X507192D01*
X507483Y228083D01*
X507733Y228208D01*
X507942Y228375D01*
G01X510000Y228000D02*
Y230500D01*
X509500Y230000D01*
G01Y228000D02*
X510500D01*
G01X513600D02*
Y230500D01*
X512058Y228708D01*
X514142D01*
G01X516200Y230500D02*
X515867Y230417D01*
X515617Y230208D01*
X515450Y229958D01*
X515325Y229625D01*
X515283Y229250D01*
X515325Y228875D01*
X515450Y228542D01*
X515617Y228292D01*
X515867Y228083D01*
X516200Y228000D01*
X516533Y228083D01*
X516783Y228292D01*
X516950Y228542D01*
X517075Y228875D01*
X517117Y229250D01*
X517075Y229625D01*
X516950Y229958D01*
X516783Y230208D01*
X516533Y230417D01*
X516200Y230500D01*
G01X503017Y232000D02*
Y234500D01*
X504017D01*
X504350Y234375D01*
X504600Y234083D01*
X504683Y233750D01*
X504600Y233417D01*
X504392Y233167D01*
X504017Y233042D01*
X503017D01*
G01X507867Y234292D02*
X507617Y234417D01*
X507325Y234500D01*
X506992D01*
X506617Y234375D01*
X506325Y234167D01*
X506117Y233917D01*
X505950Y233500D01*
X505908Y233125D01*
X505992Y232750D01*
X506117Y232500D01*
X506367Y232250D01*
X506658Y232083D01*
X506950Y232000D01*
X507242D01*
X507533Y232083D01*
X507783Y232208D01*
X507992Y232375D01*
G01X510550Y232000D02*
Y234500D01*
X509008Y232708D01*
X511092D01*
G01X512233Y232375D02*
X512483Y232167D01*
X512775Y232042D01*
X513150Y232000D01*
X513525Y232083D01*
X513817Y232250D01*
X514025Y232542D01*
X514067Y232875D01*
X513983Y233208D01*
X513775Y233417D01*
X513483Y233583D01*
X513192Y233625D01*
X512900Y233583D01*
X512525Y233417D01*
X512650Y234500D01*
X513775D01*
G01X510542Y236917D02*
X510292Y236667D01*
X510000Y236542D01*
X509667Y236500D01*
X509250Y236583D01*
X508958Y236792D01*
X508875Y237042D01*
X508917Y237292D01*
X509083Y237500D01*
X509917Y237917D01*
X510292Y238208D01*
X510542Y238625D01*
X510625Y239000D01*
X508875D01*
G01X506650Y236500D02*
X506983Y236583D01*
X507233Y236792D01*
X507400Y237042D01*
X507525Y237375D01*
X507567Y237750D01*
X507525Y238125D01*
X507400Y238458D01*
X507233Y238708D01*
X506983Y238917D01*
X506650Y239000D01*
X506317Y238917D01*
X506067Y238708D01*
X505900Y238458D01*
X505775Y238125D01*
X505733Y237750D01*
X505775Y237375D01*
X505900Y237042D01*
X506067Y236792D01*
X506317Y236583D01*
X506650Y236500D01*
G01X503050Y239000D02*
Y236500D01*
X504592Y238292D01*
X502508D01*
G01X499416Y241748D02*
X497516Y239848D01*
X501316D01*
Y239948D01*
X499466Y241798D01*
Y237398D01*
G01X515000Y59567D02*
X512500D01*
Y60608D01*
X512625Y60942D01*
X512792Y61150D01*
X513125Y61233D01*
X513458Y61150D01*
X513667Y60900D01*
X513792Y60608D01*
Y59567D01*
G01Y60608D02*
X515000Y61233D01*
G01X514625Y62583D02*
X514833Y62833D01*
X514958Y63125D01*
X515000Y63500D01*
X514917Y63875D01*
X514750Y64167D01*
X514458Y64375D01*
X514125Y64417D01*
X513792Y64333D01*
X513583Y64125D01*
X513417Y63833D01*
X513375Y63542D01*
X513417Y63250D01*
X513583Y62875D01*
X512500Y63000D01*
Y64125D01*
G01X515000Y66600D02*
X512500D01*
X513000Y66100D01*
G01X515000D02*
Y67100D01*
G01X519000Y59567D02*
X516500D01*
Y60608D01*
X516625Y60942D01*
X516792Y61150D01*
X517125Y61233D01*
X517458Y61150D01*
X517667Y60900D01*
X517792Y60608D01*
Y59567D01*
G01Y60608D02*
X519000Y61233D01*
G01X518625Y62583D02*
X518833Y62833D01*
X518958Y63125D01*
X519000Y63500D01*
X518917Y63875D01*
X518750Y64167D01*
X518458Y64375D01*
X518125Y64417D01*
X517792Y64333D01*
X517583Y64125D01*
X517417Y63833D01*
X517375Y63542D01*
X517417Y63250D01*
X517583Y62875D01*
X516500Y63000D01*
Y64125D01*
G01X516917Y65808D02*
X516667Y66058D01*
X516542Y66350D01*
X516500Y66683D01*
X516583Y67100D01*
X516792Y67392D01*
X517042Y67475D01*
X517292Y67433D01*
X517500Y67267D01*
X517917Y66433D01*
X518208Y66058D01*
X518625Y65808D01*
X519000Y65725D01*
Y67475D01*
G01X522500Y59567D02*
X520000D01*
Y60608D01*
X520125Y60942D01*
X520292Y61150D01*
X520625Y61233D01*
X520958Y61150D01*
X521167Y60900D01*
X521292Y60608D01*
Y59567D01*
G01Y60608D02*
X522500Y61233D01*
G01X522125Y62583D02*
X522333Y62833D01*
X522458Y63125D01*
X522500Y63500D01*
X522417Y63875D01*
X522250Y64167D01*
X521958Y64375D01*
X521625Y64417D01*
X521292Y64333D01*
X521083Y64125D01*
X520917Y63833D01*
X520875Y63542D01*
X520917Y63250D01*
X521083Y62875D01*
X520000Y63000D01*
Y64125D01*
G01X522500Y66600D02*
X522458Y66892D01*
X522333Y67225D01*
X522125Y67433D01*
X521833Y67517D01*
X521542Y67433D01*
X521292Y67183D01*
X521167Y66808D01*
Y66392D01*
X521083Y66142D01*
X520875Y65933D01*
X520583Y65850D01*
X520292Y65975D01*
X520083Y66267D01*
X520000Y66600D01*
X520083Y66933D01*
X520292Y67225D01*
X520583Y67350D01*
X520875Y67267D01*
X521083Y67058D01*
X521167Y66808D01*
Y66392D01*
X521292Y66017D01*
X521542Y65767D01*
X521833Y65683D01*
X522125Y65767D01*
X522333Y65975D01*
X522458Y66308D01*
X522500Y66600D01*
G01X516983Y55000D02*
Y53208D01*
X517150Y52833D01*
X517483Y52583D01*
X517900Y52500D01*
X518317Y52583D01*
X518650Y52833D01*
X518817Y53208D01*
Y55000D01*
G01X520083Y53000D02*
X520333Y52708D01*
X520667Y52542D01*
X521042Y52500D01*
X521375Y52542D01*
X521708Y52750D01*
X521917Y53000D01*
X521958Y53250D01*
X521875Y53542D01*
X521583Y53750D01*
X521292Y53833D01*
X520917D01*
G01X521292D02*
X521542Y53958D01*
X521750Y54167D01*
X521833Y54417D01*
X521750Y54667D01*
X521542Y54875D01*
X521167Y55000D01*
X520792Y54958D01*
X520417Y54792D01*
G01X524100Y55000D02*
X523767Y54917D01*
X523517Y54708D01*
X523350Y54458D01*
X523225Y54125D01*
X523183Y53750D01*
X523225Y53375D01*
X523350Y53042D01*
X523517Y52792D01*
X523767Y52583D01*
X524100Y52500D01*
X524433Y52583D01*
X524683Y52792D01*
X524850Y53042D01*
X524975Y53375D01*
X525017Y53750D01*
X524975Y54125D01*
X524850Y54458D01*
X524683Y54708D01*
X524433Y54917D01*
X524100Y55000D01*
G01X516500Y69017D02*
X514000D01*
Y70058D01*
X514125Y70392D01*
X514292Y70600D01*
X514625Y70683D01*
X514958Y70600D01*
X515167Y70350D01*
X515292Y70058D01*
Y69017D01*
G01Y70058D02*
X516500Y70683D01*
G01X516000Y72033D02*
X516292Y72283D01*
X516458Y72617D01*
X516500Y72992D01*
X516458Y73325D01*
X516250Y73658D01*
X516000Y73867D01*
X515750Y73908D01*
X515458Y73825D01*
X515250Y73533D01*
X515167Y73242D01*
Y72867D01*
G01Y73242D02*
X515042Y73492D01*
X514833Y73700D01*
X514583Y73783D01*
X514333Y73700D01*
X514125Y73492D01*
X514000Y73117D01*
X514042Y72742D01*
X514208Y72367D01*
G01X516208Y75342D02*
X516417Y75633D01*
X516500Y75967D01*
X516417Y76300D01*
X516167Y76592D01*
X515792Y76800D01*
X515417Y76883D01*
X514958D01*
X514583Y76800D01*
X514250Y76592D01*
X514083Y76342D01*
X514000Y76050D01*
X514083Y75717D01*
X514250Y75467D01*
X514500Y75300D01*
X514833Y75217D01*
X515125Y75300D01*
X515417Y75508D01*
X515583Y75758D01*
X515625Y76050D01*
X515542Y76383D01*
X515333Y76633D01*
X514958Y76883D01*
G01X516125Y78233D02*
X516333Y78483D01*
X516458Y78775D01*
X516500Y79150D01*
X516417Y79525D01*
X516250Y79817D01*
X515958Y80025D01*
X515625Y80067D01*
X515292Y79983D01*
X515083Y79775D01*
X514917Y79483D01*
X514875Y79192D01*
X514917Y78900D01*
X515083Y78525D01*
X514000Y78650D01*
Y79775D01*
G01X515700Y89517D02*
X513200D01*
Y90558D01*
X513325Y90892D01*
X513492Y91100D01*
X513825Y91183D01*
X514158Y91100D01*
X514367Y90850D01*
X514492Y90558D01*
Y89517D01*
G01Y90558D02*
X515700Y91183D01*
G01Y93950D02*
X513200D01*
X514992Y92408D01*
Y94492D01*
G01X515700Y96550D02*
X515658Y96842D01*
X515533Y97175D01*
X515325Y97383D01*
X515033Y97467D01*
X514742Y97383D01*
X514492Y97133D01*
X514367Y96758D01*
Y96342D01*
X514283Y96092D01*
X514075Y95883D01*
X513783Y95800D01*
X513492Y95925D01*
X513283Y96217D01*
X513200Y96550D01*
X513283Y96883D01*
X513492Y97175D01*
X513783Y97300D01*
X514075Y97217D01*
X514283Y97008D01*
X514367Y96758D01*
Y96342D01*
X514492Y95967D01*
X514742Y95717D01*
X515033Y95633D01*
X515325Y95717D01*
X515533Y95925D01*
X515658Y96258D01*
X515700Y96550D01*
G01X515200Y98733D02*
X515492Y98983D01*
X515658Y99317D01*
X515700Y99692D01*
X515658Y100025D01*
X515450Y100358D01*
X515200Y100567D01*
X514950Y100608D01*
X514658Y100525D01*
X514450Y100233D01*
X514367Y99942D01*
Y99567D01*
G01Y99942D02*
X514242Y100192D01*
X514033Y100400D01*
X513783Y100483D01*
X513533Y100400D01*
X513325Y100192D01*
X513200Y99817D01*
X513242Y99442D01*
X513408Y99067D01*
G01X512708Y150817D02*
X512583Y150567D01*
X512500Y150275D01*
Y149942D01*
X512625Y149567D01*
X512833Y149275D01*
X513083Y149067D01*
X513500Y148900D01*
X513875Y148858D01*
X514250Y148942D01*
X514500Y149067D01*
X514750Y149317D01*
X514917Y149608D01*
X515000Y149900D01*
Y150192D01*
X514917Y150483D01*
X514792Y150733D01*
X514625Y150942D01*
G01X515000Y153000D02*
X512500D01*
X513000Y152500D01*
G01X515000D02*
Y153500D01*
G01X514500Y155183D02*
X514792Y155433D01*
X514958Y155767D01*
X515000Y156142D01*
X514958Y156475D01*
X514750Y156808D01*
X514500Y157017D01*
X514250Y157058D01*
X513958Y156975D01*
X513750Y156683D01*
X513667Y156392D01*
Y156017D01*
G01Y156392D02*
X513542Y156642D01*
X513333Y156850D01*
X513083Y156933D01*
X512833Y156850D01*
X512625Y156642D01*
X512500Y156267D01*
X512542Y155892D01*
X512708Y155517D01*
G01X528000Y181958D02*
X525500D01*
Y183542D01*
G01X526708Y182958D02*
Y181958D01*
G01X525500Y184600D02*
X528000Y185183D01*
X525500Y185850D01*
X528000Y186517D01*
X525500Y187100D01*
G01X528000Y191217D02*
X525500D01*
Y192258D01*
X525625Y192592D01*
X525792Y192800D01*
X526125Y192883D01*
X526458Y192800D01*
X526667Y192550D01*
X526792Y192258D01*
Y191217D01*
G01Y192258D02*
X528000Y192883D01*
G01X526875Y194525D02*
Y195858D01*
X526583Y195733D01*
X526417Y195525D01*
X526333Y195233D01*
X526375Y194942D01*
X526500Y194692D01*
X526792Y194525D01*
X527042Y194442D01*
X527292D01*
X527542Y194525D01*
X527792Y194733D01*
X527958Y194983D01*
X528000Y195275D01*
X527917Y195567D01*
X527667Y195858D01*
G01X527708Y197625D02*
X527875Y197833D01*
X528000Y198125D01*
Y198375D01*
X527917Y198625D01*
X527792Y198792D01*
X527625Y198875D01*
X527375Y198833D01*
X527250Y198667D01*
X527000Y197917D01*
X526708Y197750D01*
X526500Y197833D01*
X526375Y198000D01*
X526333Y198250D01*
X526375Y198500D01*
X526500Y198750D01*
G01X526875Y200725D02*
Y202058D01*
X526583Y201933D01*
X526417Y201725D01*
X526333Y201433D01*
X526375Y201142D01*
X526500Y200892D01*
X526792Y200725D01*
X527042Y200642D01*
X527292D01*
X527542Y200725D01*
X527792Y200933D01*
X527958Y201183D01*
X528000Y201475D01*
X527917Y201767D01*
X527667Y202058D01*
G01X525500Y204450D02*
X528000D01*
G01X526333Y203867D02*
Y205033D01*
G01X517017Y211000D02*
Y213500D01*
X518017D01*
X518350Y213375D01*
X518600Y213083D01*
X518683Y212750D01*
X518600Y212417D01*
X518392Y212167D01*
X518017Y212042D01*
X517017D01*
G01X520117Y211000D02*
Y213500D01*
X521158D01*
X521492Y213375D01*
X521700Y213208D01*
X521783Y212875D01*
X521700Y212542D01*
X521450Y212333D01*
X521158Y212208D01*
X520117D01*
G01X521158D02*
X521783Y211000D01*
G01X524050D02*
X524342Y211042D01*
X524675Y211167D01*
X524883Y211375D01*
X524967Y211667D01*
X524883Y211958D01*
X524633Y212208D01*
X524258Y212333D01*
X523842D01*
X523592Y212417D01*
X523383Y212625D01*
X523300Y212917D01*
X523425Y213208D01*
X523717Y213417D01*
X524050Y213500D01*
X524383Y213417D01*
X524675Y213208D01*
X524800Y212917D01*
X524717Y212625D01*
X524508Y212417D01*
X524258Y212333D01*
X523842D01*
X523467Y212208D01*
X523217Y211958D01*
X523133Y211667D01*
X523217Y211375D01*
X523425Y211167D01*
X523758Y211042D01*
X524050Y211000D01*
G01X527150Y213500D02*
X526817Y213417D01*
X526567Y213208D01*
X526400Y212958D01*
X526275Y212625D01*
X526233Y212250D01*
X526275Y211875D01*
X526400Y211542D01*
X526567Y211292D01*
X526817Y211083D01*
X527150Y211000D01*
X527483Y211083D01*
X527733Y211292D01*
X527900Y211542D01*
X528025Y211875D01*
X528067Y212250D01*
X528025Y212625D01*
X527900Y212958D01*
X527733Y213208D01*
X527483Y213417D01*
X527150Y213500D01*
G01X517017Y207500D02*
Y210000D01*
X518017D01*
X518350Y209875D01*
X518600Y209583D01*
X518683Y209250D01*
X518600Y208917D01*
X518392Y208667D01*
X518017Y208542D01*
X517017D01*
G01X521867Y209792D02*
X521617Y209917D01*
X521325Y210000D01*
X520992D01*
X520617Y209875D01*
X520325Y209667D01*
X520117Y209417D01*
X519950Y209000D01*
X519908Y208625D01*
X519992Y208250D01*
X520117Y208000D01*
X520367Y207750D01*
X520658Y207583D01*
X520950Y207500D01*
X521242D01*
X521533Y207583D01*
X521783Y207708D01*
X521992Y207875D01*
G01X523258Y208542D02*
X523550Y208833D01*
X523800Y209000D01*
X524133Y209083D01*
X524425Y209000D01*
X524633Y208833D01*
X524800Y208583D01*
X524842Y208292D01*
X524800Y208042D01*
X524633Y207792D01*
X524383Y207583D01*
X524092Y207500D01*
X523758Y207583D01*
X523467Y207833D01*
X523300Y208208D01*
X523258Y208625D01*
X523342Y209167D01*
X523467Y209458D01*
X523675Y209750D01*
X523967Y209958D01*
X524258Y210000D01*
X524550Y209917D01*
X524758Y209708D01*
G01X526358Y208542D02*
X526650Y208833D01*
X526900Y209000D01*
X527233Y209083D01*
X527525Y209000D01*
X527733Y208833D01*
X527900Y208583D01*
X527942Y208292D01*
X527900Y208042D01*
X527733Y207792D01*
X527483Y207583D01*
X527192Y207500D01*
X526858Y207583D01*
X526567Y207833D01*
X526400Y208208D01*
X526358Y208625D01*
X526442Y209167D01*
X526567Y209458D01*
X526775Y209750D01*
X527067Y209958D01*
X527358Y210000D01*
X527650Y209917D01*
X527858Y209708D01*
G01X517517Y238500D02*
Y241000D01*
X518517D01*
X518850Y240875D01*
X519100Y240583D01*
X519183Y240250D01*
X519100Y239917D01*
X518892Y239667D01*
X518517Y239542D01*
X517517D01*
G01X520617Y238500D02*
Y241000D01*
X521658D01*
X521992Y240875D01*
X522200Y240708D01*
X522283Y240375D01*
X522200Y240042D01*
X521950Y239833D01*
X521658Y239708D01*
X520617D01*
G01X521658D02*
X522283Y238500D01*
G01X523633Y238875D02*
X523883Y238667D01*
X524175Y238542D01*
X524550Y238500D01*
X524925Y238583D01*
X525217Y238750D01*
X525425Y239042D01*
X525467Y239375D01*
X525383Y239708D01*
X525175Y239917D01*
X524883Y240083D01*
X524592Y240125D01*
X524300Y240083D01*
X523925Y239917D01*
X524050Y241000D01*
X525175D01*
G01X526942Y238792D02*
X527233Y238583D01*
X527567Y238500D01*
X527900Y238583D01*
X528192Y238833D01*
X528400Y239208D01*
X528483Y239583D01*
Y240042D01*
X528400Y240417D01*
X528192Y240750D01*
X527942Y240917D01*
X527650Y241000D01*
X527317Y240917D01*
X527067Y240750D01*
X526900Y240500D01*
X526817Y240167D01*
X526900Y239875D01*
X527108Y239583D01*
X527358Y239417D01*
X527650Y239375D01*
X527983Y239458D01*
X528233Y239667D01*
X528483Y240042D01*
G01X541417Y57500D02*
Y55000D01*
X543083D01*
G01X546183D02*
X544517D01*
Y57500D01*
X546183D01*
G01X545517Y56292D02*
X544517D01*
G01X547533Y55000D02*
Y57500D01*
X548367D01*
X548700Y57375D01*
X548950Y57208D01*
X549158Y56958D01*
X549325Y56667D01*
X549367Y56250D01*
X549325Y55833D01*
X549158Y55542D01*
X548950Y55292D01*
X548700Y55125D01*
X548367Y55000D01*
X547533D01*
G01X552050D02*
Y57500D01*
X550508Y55708D01*
X552592D01*
G01X554650Y54917D02*
X554567Y54958D01*
Y55042D01*
X554650Y55083D01*
X554733Y55042D01*
Y54958D01*
X554650Y54917D01*
G01Y56042D02*
X554567Y56083D01*
Y56167D01*
X554650Y56208D01*
X554733Y56167D01*
Y56083D01*
X554650Y56042D01*
G01X560058Y55000D02*
Y57500D01*
X561642D01*
G01X561058Y56292D02*
X560058D01*
G01X563117Y55000D02*
Y57500D01*
X564117D01*
X564450Y57375D01*
X564700Y57083D01*
X564783Y56750D01*
X564700Y56417D01*
X564492Y56167D01*
X564117Y56042D01*
X563117D01*
G01X567300Y56250D02*
X568133D01*
Y55500D01*
X567883Y55250D01*
X567592Y55083D01*
X567175Y55000D01*
X566758Y55083D01*
X566467Y55250D01*
X566217Y55500D01*
X566050Y55792D01*
X565967Y56125D01*
Y56417D01*
X566050Y56667D01*
X566217Y56958D01*
X566467Y57208D01*
X566717Y57375D01*
X567050Y57500D01*
X567342D01*
X567675Y57417D01*
X567925Y57250D01*
G01X569108Y55000D02*
X570150Y57500D01*
X571192Y55000D01*
G01X570817Y55875D02*
X569483D01*
G01X572000Y54167D02*
X574500D01*
G01X575475Y55000D02*
Y57500D01*
G01X577225D02*
Y55000D01*
G01Y56250D02*
X575475D01*
G01X579783Y56333D02*
X579950Y56458D01*
X580075Y56667D01*
X580158Y56958D01*
X580075Y57208D01*
X579908Y57375D01*
X579617Y57500D01*
X578492D01*
Y55000D01*
X579867D01*
X580158Y55167D01*
X580325Y55417D01*
X580408Y55708D01*
X580325Y56000D01*
X580075Y56250D01*
X579783Y56333D01*
X578492D01*
G01X541417Y53000D02*
Y50500D01*
X543083D01*
G01X546183D02*
X544517D01*
Y53000D01*
X546183D01*
G01X545517Y51792D02*
X544517D01*
G01X547533Y50500D02*
Y53000D01*
X548367D01*
X548700Y52875D01*
X548950Y52708D01*
X549158Y52458D01*
X549325Y52167D01*
X549367Y51750D01*
X549325Y51333D01*
X549158Y51042D01*
X548950Y50792D01*
X548700Y50625D01*
X548367Y50500D01*
X547533D01*
G01X550633Y51000D02*
X550883Y50708D01*
X551217Y50542D01*
X551592Y50500D01*
X551925Y50542D01*
X552258Y50750D01*
X552467Y51000D01*
X552508Y51250D01*
X552425Y51542D01*
X552133Y51750D01*
X551842Y51833D01*
X551467D01*
G01X551842D02*
X552092Y51958D01*
X552300Y52167D01*
X552383Y52417D01*
X552300Y52667D01*
X552092Y52875D01*
X551717Y53000D01*
X551342Y52958D01*
X550967Y52792D01*
G01X554650Y50417D02*
X554567Y50458D01*
Y50542D01*
X554650Y50583D01*
X554733Y50542D01*
Y50458D01*
X554650Y50417D01*
G01Y51542D02*
X554567Y51583D01*
Y51667D01*
X554650Y51708D01*
X554733Y51667D01*
Y51583D01*
X554650Y51542D01*
G01X560058Y50500D02*
Y53000D01*
X561642D01*
G01X561058Y51792D02*
X560058D01*
G01X563117Y50500D02*
Y53000D01*
X564117D01*
X564450Y52875D01*
X564700Y52583D01*
X564783Y52250D01*
X564700Y51917D01*
X564492Y51667D01*
X564117Y51542D01*
X563117D01*
G01X567300Y51750D02*
X568133D01*
Y51000D01*
X567883Y50750D01*
X567592Y50583D01*
X567175Y50500D01*
X566758Y50583D01*
X566467Y50750D01*
X566217Y51000D01*
X566050Y51292D01*
X565967Y51625D01*
Y51917D01*
X566050Y52167D01*
X566217Y52458D01*
X566467Y52708D01*
X566717Y52875D01*
X567050Y53000D01*
X567342D01*
X567675Y52917D01*
X567925Y52750D01*
G01X569108Y50500D02*
X570150Y53000D01*
X571192Y50500D01*
G01X570817Y51375D02*
X569483D01*
G01X572000Y49667D02*
X574500D01*
G01X575475Y50833D02*
X575808Y50625D01*
X576183Y50500D01*
X576517D01*
X576850Y50625D01*
X577100Y50833D01*
X577225Y51125D01*
X577142Y51417D01*
X576933Y51667D01*
X576558Y51833D01*
X576058Y51917D01*
X575767Y52083D01*
X575642Y52375D01*
X575725Y52667D01*
X575933Y52875D01*
X576225Y53000D01*
X576517D01*
X576808Y52917D01*
X577058Y52708D01*
G01X579450Y53000D02*
Y50500D01*
G01X578492Y53000D02*
X580408D01*
G01X581508Y50500D02*
X582550Y53000D01*
X583592Y50500D01*
G01X583217Y51375D02*
X581883D01*
G01X585650Y53000D02*
Y50500D01*
G01X584692Y53000D02*
X586608D01*
G01X587833D02*
Y51208D01*
X588000Y50833D01*
X588333Y50583D01*
X588750Y50500D01*
X589167Y50583D01*
X589500Y50833D01*
X589667Y51208D01*
Y53000D01*
G01X590975Y50833D02*
X591308Y50625D01*
X591683Y50500D01*
X592017D01*
X592350Y50625D01*
X592600Y50833D01*
X592725Y51125D01*
X592642Y51417D01*
X592433Y51667D01*
X592058Y51833D01*
X591558Y51917D01*
X591267Y52083D01*
X591142Y52375D01*
X591225Y52667D01*
X591433Y52875D01*
X591725Y53000D01*
X592017D01*
X592308Y52917D01*
X592558Y52708D01*
G01X529767Y54292D02*
X529517Y54417D01*
X529225Y54500D01*
X528892D01*
X528517Y54375D01*
X528225Y54167D01*
X528017Y53917D01*
X527850Y53500D01*
X527808Y53125D01*
X527892Y52750D01*
X528017Y52500D01*
X528267Y52250D01*
X528558Y52083D01*
X528850Y52000D01*
X529142D01*
X529433Y52083D01*
X529683Y52208D01*
X529892Y52375D01*
G01X531033Y52500D02*
X531283Y52208D01*
X531617Y52042D01*
X531992Y52000D01*
X532325Y52042D01*
X532658Y52250D01*
X532867Y52500D01*
X532908Y52750D01*
X532825Y53042D01*
X532533Y53250D01*
X532242Y53333D01*
X531867D01*
G01X532242D02*
X532492Y53458D01*
X532700Y53667D01*
X532783Y53917D01*
X532700Y54167D01*
X532492Y54375D01*
X532117Y54500D01*
X531742Y54458D01*
X531367Y54292D01*
G01X534258Y54083D02*
X534508Y54333D01*
X534800Y54458D01*
X535133Y54500D01*
X535550Y54417D01*
X535842Y54208D01*
X535925Y53958D01*
X535883Y53708D01*
X535717Y53500D01*
X534883Y53083D01*
X534508Y52792D01*
X534258Y52375D01*
X534175Y52000D01*
X535925D01*
G01X537233Y52500D02*
X537483Y52208D01*
X537817Y52042D01*
X538192Y52000D01*
X538525Y52042D01*
X538858Y52250D01*
X539067Y52500D01*
X539108Y52750D01*
X539025Y53042D01*
X538733Y53250D01*
X538442Y53333D01*
X538067D01*
G01X538442D02*
X538692Y53458D01*
X538900Y53667D01*
X538983Y53917D01*
X538900Y54167D01*
X538692Y54375D01*
X538317Y54500D01*
X537942Y54458D01*
X537567Y54292D01*
G01X538067Y67500D02*
Y70000D01*
X539108D01*
X539442Y69875D01*
X539650Y69708D01*
X539733Y69375D01*
X539650Y69042D01*
X539400Y68833D01*
X539108Y68708D01*
X538067D01*
G01X539108D02*
X539733Y67500D01*
G01X541083Y67875D02*
X541333Y67667D01*
X541625Y67542D01*
X542000Y67500D01*
X542375Y67583D01*
X542667Y67750D01*
X542875Y68042D01*
X542917Y68375D01*
X542833Y68708D01*
X542625Y68917D01*
X542333Y69083D01*
X542042Y69125D01*
X541750Y69083D01*
X541375Y68917D01*
X541500Y70000D01*
X542625D01*
G01X545017Y67500D02*
X545100Y68042D01*
X545225Y68500D01*
X545392Y68917D01*
X545600Y69375D01*
X545933Y70000D01*
X544267D01*
G01X536817Y89792D02*
X536567Y89917D01*
X536275Y90000D01*
X535942D01*
X535567Y89875D01*
X535275Y89667D01*
X535067Y89417D01*
X534900Y89000D01*
X534858Y88625D01*
X534942Y88250D01*
X535067Y88000D01*
X535317Y87750D01*
X535608Y87583D01*
X535900Y87500D01*
X536192D01*
X536483Y87583D01*
X536733Y87708D01*
X536942Y87875D01*
G01X539000Y87500D02*
Y90000D01*
X538500Y89500D01*
G01Y87500D02*
X539500D01*
G01X542100D02*
X542392Y87542D01*
X542725Y87667D01*
X542933Y87875D01*
X543017Y88167D01*
X542933Y88458D01*
X542683Y88708D01*
X542308Y88833D01*
X541892D01*
X541642Y88917D01*
X541433Y89125D01*
X541350Y89417D01*
X541475Y89708D01*
X541767Y89917D01*
X542100Y90000D01*
X542433Y89917D01*
X542725Y89708D01*
X542850Y89417D01*
X542767Y89125D01*
X542558Y88917D01*
X542308Y88833D01*
X541892D01*
X541517Y88708D01*
X541267Y88458D01*
X541183Y88167D01*
X541267Y87875D01*
X541475Y87667D01*
X541808Y87542D01*
X542100Y87500D01*
G01X539850Y184500D02*
Y182000D01*
G01X538892Y184500D02*
X540808D01*
G01X542117Y182000D02*
Y184500D01*
X543117D01*
X543450Y184375D01*
X543700Y184083D01*
X543783Y183750D01*
X543700Y183417D01*
X543492Y183167D01*
X543117Y183042D01*
X542117D01*
G01X545133Y182500D02*
X545383Y182208D01*
X545717Y182042D01*
X546092Y182000D01*
X546425Y182042D01*
X546758Y182250D01*
X546967Y182500D01*
X547008Y182750D01*
X546925Y183042D01*
X546633Y183250D01*
X546342Y183333D01*
X545967D01*
G01X546342D02*
X546592Y183458D01*
X546800Y183667D01*
X546883Y183917D01*
X546800Y184167D01*
X546592Y184375D01*
X546217Y184500D01*
X545842Y184458D01*
X545467Y184292D01*
G01X549067Y182000D02*
X549150Y182542D01*
X549275Y183000D01*
X549442Y183417D01*
X549650Y183875D01*
X549983Y184500D01*
X548317D01*
G01X529525Y184833D02*
X529858Y184625D01*
X530233Y184500D01*
X530567D01*
X530900Y184625D01*
X531150Y184833D01*
X531275Y185125D01*
X531192Y185417D01*
X530983Y185667D01*
X530608Y185833D01*
X530108Y185917D01*
X529817Y186083D01*
X529692Y186375D01*
X529775Y186667D01*
X529983Y186875D01*
X530275Y187000D01*
X530567D01*
X530858Y186917D01*
X531108Y186708D01*
G01X532250Y187000D02*
X532833Y184500D01*
X533500Y187000D01*
X534167Y184500D01*
X534750Y187000D01*
G01X536600Y184500D02*
Y187000D01*
X536100Y186500D01*
G01Y184500D02*
X537100D01*
G01X537017Y207500D02*
Y210000D01*
X538017D01*
X538350Y209875D01*
X538600Y209583D01*
X538683Y209250D01*
X538600Y208917D01*
X538392Y208667D01*
X538017Y208542D01*
X537017D01*
G01X541867Y209792D02*
X541617Y209917D01*
X541325Y210000D01*
X540992D01*
X540617Y209875D01*
X540325Y209667D01*
X540117Y209417D01*
X539950Y209000D01*
X539908Y208625D01*
X539992Y208250D01*
X540117Y208000D01*
X540367Y207750D01*
X540658Y207583D01*
X540950Y207500D01*
X541242D01*
X541533Y207583D01*
X541783Y207708D01*
X541992Y207875D01*
G01X543133D02*
X543383Y207667D01*
X543675Y207542D01*
X544050Y207500D01*
X544425Y207583D01*
X544717Y207750D01*
X544925Y208042D01*
X544967Y208375D01*
X544883Y208708D01*
X544675Y208917D01*
X544383Y209083D01*
X544092Y209125D01*
X543800Y209083D01*
X543425Y208917D01*
X543550Y210000D01*
X544675D01*
G01X546233Y208000D02*
X546483Y207708D01*
X546817Y207542D01*
X547192Y207500D01*
X547525Y207542D01*
X547858Y207750D01*
X548067Y208000D01*
X548108Y208250D01*
X548025Y208542D01*
X547733Y208750D01*
X547442Y208833D01*
X547067D01*
G01X547442D02*
X547692Y208958D01*
X547900Y209167D01*
X547983Y209417D01*
X547900Y209667D01*
X547692Y209875D01*
X547317Y210000D01*
X546942Y209958D01*
X546567Y209792D01*
G01X531567Y212000D02*
Y214500D01*
X532567D01*
X532900Y214375D01*
X533150Y214083D01*
X533233Y213750D01*
X533150Y213417D01*
X532942Y213167D01*
X532567Y213042D01*
X531567D01*
G01X534583Y214500D02*
Y212708D01*
X534750Y212333D01*
X535083Y212083D01*
X535500Y212000D01*
X535917Y212083D01*
X536250Y212333D01*
X536417Y212708D01*
Y214500D01*
G01X539100Y212000D02*
Y214500D01*
X537558Y212708D01*
X539642D01*
G01X530017Y238500D02*
Y241000D01*
X531017D01*
X531350Y240875D01*
X531600Y240583D01*
X531683Y240250D01*
X531600Y239917D01*
X531392Y239667D01*
X531017Y239542D01*
X530017D01*
G01X533117Y238500D02*
Y241000D01*
X534158D01*
X534492Y240875D01*
X534700Y240708D01*
X534783Y240375D01*
X534700Y240042D01*
X534450Y239833D01*
X534158Y239708D01*
X533117D01*
G01X534158D02*
X534783Y238500D01*
G01X536133Y238875D02*
X536383Y238667D01*
X536675Y238542D01*
X537050Y238500D01*
X537425Y238583D01*
X537717Y238750D01*
X537925Y239042D01*
X537967Y239375D01*
X537883Y239708D01*
X537675Y239917D01*
X537383Y240083D01*
X537092Y240125D01*
X536800Y240083D01*
X536425Y239917D01*
X536550Y241000D01*
X537675D01*
G01X539233Y239000D02*
X539483Y238708D01*
X539817Y238542D01*
X540192Y238500D01*
X540525Y238542D01*
X540858Y238750D01*
X541067Y239000D01*
X541108Y239250D01*
X541025Y239542D01*
X540733Y239750D01*
X540442Y239833D01*
X540067D01*
G01X540442D02*
X540692Y239958D01*
X540900Y240167D01*
X540983Y240417D01*
X540900Y240667D01*
X540692Y240875D01*
X540317Y241000D01*
X539942Y240958D01*
X539567Y240792D01*
G01X555400Y73417D02*
X557900D01*
Y75083D01*
G01Y78183D02*
Y76517D01*
X555400D01*
Y78183D01*
G01X556608Y77517D02*
Y76517D01*
G01X557900Y79533D02*
X555400D01*
Y80367D01*
X555525Y80700D01*
X555692Y80950D01*
X555942Y81158D01*
X556233Y81325D01*
X556650Y81367D01*
X557067Y81325D01*
X557358Y81158D01*
X557608Y80950D01*
X557775Y80700D01*
X557900Y80367D01*
Y79533D01*
G01X555817Y82758D02*
X555567Y83008D01*
X555442Y83300D01*
X555400Y83633D01*
X555483Y84050D01*
X555692Y84342D01*
X555942Y84425D01*
X556192Y84383D01*
X556400Y84217D01*
X556817Y83383D01*
X557108Y83008D01*
X557525Y82758D01*
X557900Y82675D01*
Y84425D01*
G01X551000Y71850D02*
X553500D01*
G01X551000Y70892D02*
Y72808D01*
G01X553500Y74117D02*
X551000D01*
Y75117D01*
X551125Y75450D01*
X551417Y75700D01*
X551750Y75783D01*
X552083Y75700D01*
X552333Y75492D01*
X552458Y75117D01*
Y74117D01*
G01X553500Y78050D02*
X551000D01*
X551500Y77550D01*
G01X553500D02*
Y78550D01*
G01X553000Y80233D02*
X553292Y80483D01*
X553458Y80817D01*
X553500Y81192D01*
X553458Y81525D01*
X553250Y81858D01*
X553000Y82067D01*
X552750Y82108D01*
X552458Y82025D01*
X552250Y81733D01*
X552167Y81442D01*
Y81067D01*
G01Y81442D02*
X552042Y81692D01*
X551833Y81900D01*
X551583Y81983D01*
X551333Y81900D01*
X551125Y81692D01*
X551000Y81317D01*
X551042Y80942D01*
X551208Y80567D01*
G01X547000Y71850D02*
X549500D01*
G01X547000Y70892D02*
Y72808D01*
G01X549500Y74117D02*
X547000D01*
Y75117D01*
X547125Y75450D01*
X547417Y75700D01*
X547750Y75783D01*
X548083Y75700D01*
X548333Y75492D01*
X548458Y75117D01*
Y74117D01*
G01X549500Y78050D02*
X547000D01*
X547500Y77550D01*
G01X549500D02*
Y78550D01*
G01X547417Y80358D02*
X547167Y80608D01*
X547042Y80900D01*
X547000Y81233D01*
X547083Y81650D01*
X547292Y81942D01*
X547542Y82025D01*
X547792Y81983D01*
X548000Y81817D01*
X548417Y80983D01*
X548708Y80608D01*
X549125Y80358D01*
X549500Y80275D01*
Y82025D01*
G01X544017Y63000D02*
Y65500D01*
X545058D01*
X545392Y65375D01*
X545600Y65208D01*
X545683Y64875D01*
X545600Y64542D01*
X545350Y64333D01*
X545058Y64208D01*
X544017D01*
G01X545058D02*
X545683Y63000D01*
G01X548450D02*
Y65500D01*
X546908Y63708D01*
X548992D01*
G01X550967Y63000D02*
X551050Y63542D01*
X551175Y64000D01*
X551342Y64417D01*
X551550Y64875D01*
X551883Y65500D01*
X550217D01*
G01X554150D02*
X553817Y65417D01*
X553567Y65208D01*
X553400Y64958D01*
X553275Y64625D01*
X553233Y64250D01*
X553275Y63875D01*
X553400Y63542D01*
X553567Y63292D01*
X553817Y63083D01*
X554150Y63000D01*
X554483Y63083D01*
X554733Y63292D01*
X554900Y63542D01*
X555025Y63875D01*
X555067Y64250D01*
X555025Y64625D01*
X554900Y64958D01*
X554733Y65208D01*
X554483Y65417D01*
X554150Y65500D01*
G01X556350Y90000D02*
Y87500D01*
G01X555392Y90000D02*
X557308D01*
G01X558617Y87500D02*
Y90000D01*
X559617D01*
X559950Y89875D01*
X560200Y89583D01*
X560283Y89250D01*
X560200Y88917D01*
X559992Y88667D01*
X559617Y88542D01*
X558617D01*
G01X563050Y87500D02*
Y90000D01*
X561508Y88208D01*
X563592D01*
G01X564858Y89583D02*
X565108Y89833D01*
X565400Y89958D01*
X565733Y90000D01*
X566150Y89917D01*
X566442Y89708D01*
X566525Y89458D01*
X566483Y89208D01*
X566317Y89000D01*
X565483Y88583D01*
X565108Y88292D01*
X564858Y87875D01*
X564775Y87500D01*
X566525D01*
G01X552350Y184500D02*
Y182000D01*
G01X551392Y184500D02*
X553308D01*
G01X554617Y182000D02*
Y184500D01*
X555617D01*
X555950Y184375D01*
X556200Y184083D01*
X556283Y183750D01*
X556200Y183417D01*
X555992Y183167D01*
X555617Y183042D01*
X554617D01*
G01X559050Y182000D02*
Y184500D01*
X557508Y182708D01*
X559592D01*
G01X561650Y182000D02*
Y184500D01*
X561150Y184000D01*
G01Y182000D02*
X562150D01*
G01X553000Y197000D02*
X556000D01*
G01X552500Y217500D02*
Y207500D01*
X549500D01*
Y200000D01*
G01X545500Y230017D02*
X543000D01*
Y231017D01*
X543125Y231350D01*
X543417Y231600D01*
X543750Y231683D01*
X544083Y231600D01*
X544333Y231392D01*
X544458Y231017D01*
Y230017D01*
G01X543208Y234867D02*
X543083Y234617D01*
X543000Y234325D01*
Y233992D01*
X543125Y233617D01*
X543333Y233325D01*
X543583Y233117D01*
X544000Y232950D01*
X544375Y232908D01*
X544750Y232992D01*
X545000Y233117D01*
X545250Y233367D01*
X545417Y233658D01*
X545500Y233950D01*
Y234242D01*
X545417Y234533D01*
X545292Y234783D01*
X545125Y234992D01*
G01X545500Y237550D02*
X543000D01*
X544792Y236008D01*
Y238092D01*
G01X545000Y239233D02*
X545292Y239483D01*
X545458Y239817D01*
X545500Y240192D01*
X545458Y240525D01*
X545250Y240858D01*
X545000Y241067D01*
X544750Y241108D01*
X544458Y241025D01*
X544250Y240733D01*
X544167Y240442D01*
Y240067D01*
G01Y240442D02*
X544042Y240692D01*
X543833Y240900D01*
X543583Y240983D01*
X543333Y240900D01*
X543125Y240692D01*
X543000Y240317D01*
X543042Y239942D01*
X543208Y239567D01*
G01X562567Y67500D02*
Y70000D01*
X563608D01*
X563942Y69875D01*
X564150Y69708D01*
X564233Y69375D01*
X564150Y69042D01*
X563900Y68833D01*
X563608Y68708D01*
X562567D01*
G01X563608D02*
X564233Y67500D01*
G01X566500D02*
X566792Y67542D01*
X567125Y67667D01*
X567333Y67875D01*
X567417Y68167D01*
X567333Y68458D01*
X567083Y68708D01*
X566708Y68833D01*
X566292D01*
X566042Y68917D01*
X565833Y69125D01*
X565750Y69417D01*
X565875Y69708D01*
X566167Y69917D01*
X566500Y70000D01*
X566833Y69917D01*
X567125Y69708D01*
X567250Y69417D01*
X567167Y69125D01*
X566958Y68917D01*
X566708Y68833D01*
X566292D01*
X565917Y68708D01*
X565667Y68458D01*
X565583Y68167D01*
X565667Y67875D01*
X565875Y67667D01*
X566208Y67542D01*
X566500Y67500D01*
G01X568892Y67792D02*
X569183Y67583D01*
X569517Y67500D01*
X569850Y67583D01*
X570142Y67833D01*
X570350Y68208D01*
X570433Y68583D01*
Y69042D01*
X570350Y69417D01*
X570142Y69750D01*
X569892Y69917D01*
X569600Y70000D01*
X569267Y69917D01*
X569017Y69750D01*
X568850Y69500D01*
X568767Y69167D01*
X568850Y68875D01*
X569058Y68583D01*
X569308Y68417D01*
X569600Y68375D01*
X569933Y68458D01*
X570183Y68667D01*
X570433Y69042D01*
G01X562567Y63500D02*
Y66000D01*
X563608D01*
X563942Y65875D01*
X564150Y65708D01*
X564233Y65375D01*
X564150Y65042D01*
X563900Y64833D01*
X563608Y64708D01*
X562567D01*
G01X563608D02*
X564233Y63500D01*
G01X565792Y63792D02*
X566083Y63583D01*
X566417Y63500D01*
X566750Y63583D01*
X567042Y63833D01*
X567250Y64208D01*
X567333Y64583D01*
Y65042D01*
X567250Y65417D01*
X567042Y65750D01*
X566792Y65917D01*
X566500Y66000D01*
X566167Y65917D01*
X565917Y65750D01*
X565750Y65500D01*
X565667Y65167D01*
X565750Y64875D01*
X565958Y64583D01*
X566208Y64417D01*
X566500Y64375D01*
X566833Y64458D01*
X567083Y64667D01*
X567333Y65042D01*
G01X569517Y63500D02*
X569600Y64042D01*
X569725Y64500D01*
X569892Y64917D01*
X570100Y65375D01*
X570433Y66000D01*
X568767D01*
G01X568017Y181500D02*
Y184000D01*
X569058D01*
X569392Y183875D01*
X569600Y183708D01*
X569683Y183375D01*
X569600Y183042D01*
X569350Y182833D01*
X569058Y182708D01*
X568017D01*
G01X569058D02*
X569683Y181500D01*
G01X572450D02*
Y184000D01*
X570908Y182208D01*
X572992D01*
G01X574133Y182000D02*
X574383Y181708D01*
X574717Y181542D01*
X575092Y181500D01*
X575425Y181542D01*
X575758Y181750D01*
X575967Y182000D01*
X576008Y182250D01*
X575925Y182542D01*
X575633Y182750D01*
X575342Y182833D01*
X574967D01*
G01X575342D02*
X575592Y182958D01*
X575800Y183167D01*
X575883Y183417D01*
X575800Y183667D01*
X575592Y183875D01*
X575217Y184000D01*
X574842Y183958D01*
X574467Y183792D01*
G01X577233Y182000D02*
X577483Y181708D01*
X577817Y181542D01*
X578192Y181500D01*
X578525Y181542D01*
X578858Y181750D01*
X579067Y182000D01*
X579108Y182250D01*
X579025Y182542D01*
X578733Y182750D01*
X578442Y182833D01*
X578067D01*
G01X578442D02*
X578692Y182958D01*
X578900Y183167D01*
X578983Y183417D01*
X578900Y183667D01*
X578692Y183875D01*
X578317Y184000D01*
X577942Y183958D01*
X577567Y183792D01*
G01X568850Y187500D02*
Y185000D01*
G01X567892Y187500D02*
X569808D01*
G01X571117Y185000D02*
Y187500D01*
X572117D01*
X572450Y187375D01*
X572700Y187083D01*
X572783Y186750D01*
X572700Y186417D01*
X572492Y186167D01*
X572117Y186042D01*
X571117D01*
G01X575550Y185000D02*
Y187500D01*
X574008Y185708D01*
X576092D01*
G01X577233Y185500D02*
X577483Y185208D01*
X577817Y185042D01*
X578192Y185000D01*
X578525Y185042D01*
X578858Y185250D01*
X579067Y185500D01*
X579108Y185750D01*
X579025Y186042D01*
X578733Y186250D01*
X578442Y186333D01*
X578067D01*
G01X578442D02*
X578692Y186458D01*
X578900Y186667D01*
X578983Y186917D01*
X578900Y187167D01*
X578692Y187375D01*
X578317Y187500D01*
X577942Y187458D01*
X577567Y187292D01*
G01X559850Y199500D02*
Y197000D01*
G01X558892Y199500D02*
X560808D01*
G01X562117Y197000D02*
Y199500D01*
X563117D01*
X563450Y199375D01*
X563700Y199083D01*
X563783Y198750D01*
X563700Y198417D01*
X563492Y198167D01*
X563117Y198042D01*
X562117D01*
G01X565133Y197500D02*
X565383Y197208D01*
X565717Y197042D01*
X566092Y197000D01*
X566425Y197042D01*
X566758Y197250D01*
X566967Y197500D01*
X567008Y197750D01*
X566925Y198042D01*
X566633Y198250D01*
X566342Y198333D01*
X565967D01*
G01X566342D02*
X566592Y198458D01*
X566800Y198667D01*
X566883Y198917D01*
X566800Y199167D01*
X566592Y199375D01*
X566217Y199500D01*
X565842Y199458D01*
X565467Y199292D01*
G01X569150Y197000D02*
X569442Y197042D01*
X569775Y197167D01*
X569983Y197375D01*
X570067Y197667D01*
X569983Y197958D01*
X569733Y198208D01*
X569358Y198333D01*
X568942D01*
X568692Y198417D01*
X568483Y198625D01*
X568400Y198917D01*
X568525Y199208D01*
X568817Y199417D01*
X569150Y199500D01*
X569483Y199417D01*
X569775Y199208D01*
X569900Y198917D01*
X569817Y198625D01*
X569608Y198417D01*
X569358Y198333D01*
X568942D01*
X568567Y198208D01*
X568317Y197958D01*
X568233Y197667D01*
X568317Y197375D01*
X568525Y197167D01*
X568858Y197042D01*
X569150Y197000D01*
G01X566000Y183067D02*
X563500D01*
Y184108D01*
X563625Y184442D01*
X563792Y184650D01*
X564125Y184733D01*
X564458Y184650D01*
X564667Y184400D01*
X564792Y184108D01*
Y183067D01*
G01Y184108D02*
X566000Y184733D01*
G01Y186917D02*
X565458Y187000D01*
X565000Y187125D01*
X564583Y187292D01*
X564125Y187500D01*
X563500Y187833D01*
Y186167D01*
G01X566000Y190100D02*
X565958Y190392D01*
X565833Y190725D01*
X565625Y190933D01*
X565333Y191017D01*
X565042Y190933D01*
X564792Y190683D01*
X564667Y190308D01*
Y189892D01*
X564583Y189642D01*
X564375Y189433D01*
X564083Y189350D01*
X563792Y189475D01*
X563583Y189767D01*
X563500Y190100D01*
X563583Y190433D01*
X563792Y190725D01*
X564083Y190850D01*
X564375Y190767D01*
X564583Y190558D01*
X564667Y190308D01*
Y189892D01*
X564792Y189517D01*
X565042Y189267D01*
X565333Y189183D01*
X565625Y189267D01*
X565833Y189475D01*
X565958Y189808D01*
X566000Y190100D01*
G01X559583Y209500D02*
Y214500D01*
X563417Y209500D01*
Y214500D01*
G01X558000Y198500D02*
Y206500D01*
G01X566500Y215500D02*
Y209500D01*
G01X561483Y207500D02*
Y205708D01*
X561650Y205333D01*
X561983Y205083D01*
X562400Y205000D01*
X562817Y205083D01*
X563150Y205333D01*
X563317Y205708D01*
Y207500D01*
G01X566000Y205000D02*
Y207500D01*
X564458Y205708D01*
X566542D01*
G01X568600Y205000D02*
X568892Y205042D01*
X569225Y205167D01*
X569433Y205375D01*
X569517Y205667D01*
X569433Y205958D01*
X569183Y206208D01*
X568808Y206333D01*
X568392D01*
X568142Y206417D01*
X567933Y206625D01*
X567850Y206917D01*
X567975Y207208D01*
X568267Y207417D01*
X568600Y207500D01*
X568933Y207417D01*
X569225Y207208D01*
X569350Y206917D01*
X569267Y206625D01*
X569058Y206417D01*
X568808Y206333D01*
X568392D01*
X568017Y206208D01*
X567767Y205958D01*
X567683Y205667D01*
X567767Y205375D01*
X567975Y205167D01*
X568308Y205042D01*
X568600Y205000D01*
G01X557000Y218500D02*
X559500D01*
Y216500D01*
G01X560017Y223000D02*
Y225500D01*
X561017D01*
X561350Y225375D01*
X561600Y225083D01*
X561683Y224750D01*
X561600Y224417D01*
X561392Y224167D01*
X561017Y224042D01*
X560017D01*
G01X563117Y223000D02*
Y225500D01*
X564158D01*
X564492Y225375D01*
X564700Y225208D01*
X564783Y224875D01*
X564700Y224542D01*
X564450Y224333D01*
X564158Y224208D01*
X563117D01*
G01X564158D02*
X564783Y223000D01*
G01X566258Y224042D02*
X566550Y224333D01*
X566800Y224500D01*
X567133Y224583D01*
X567425Y224500D01*
X567633Y224333D01*
X567800Y224083D01*
X567842Y223792D01*
X567800Y223542D01*
X567633Y223292D01*
X567383Y223083D01*
X567092Y223000D01*
X566758Y223083D01*
X566467Y223333D01*
X566300Y223708D01*
X566258Y224125D01*
X566342Y224667D01*
X566467Y224958D01*
X566675Y225250D01*
X566967Y225458D01*
X567258Y225500D01*
X567550Y225417D01*
X567758Y225208D01*
G01X570067Y223000D02*
X570150Y223542D01*
X570275Y224000D01*
X570442Y224417D01*
X570650Y224875D01*
X570983Y225500D01*
X569317D01*
G01X560017Y219500D02*
Y222000D01*
X561017D01*
X561350Y221875D01*
X561600Y221583D01*
X561683Y221250D01*
X561600Y220917D01*
X561392Y220667D01*
X561017Y220542D01*
X560017D01*
G01X563117Y219500D02*
Y222000D01*
X564158D01*
X564492Y221875D01*
X564700Y221708D01*
X564783Y221375D01*
X564700Y221042D01*
X564450Y220833D01*
X564158Y220708D01*
X563117D01*
G01X564158D02*
X564783Y219500D01*
G01X566967D02*
X567050Y220042D01*
X567175Y220500D01*
X567342Y220917D01*
X567550Y221375D01*
X567883Y222000D01*
X566217D01*
G01X569358Y221583D02*
X569608Y221833D01*
X569900Y221958D01*
X570233Y222000D01*
X570650Y221917D01*
X570942Y221708D01*
X571025Y221458D01*
X570983Y221208D01*
X570817Y221000D01*
X569983Y220583D01*
X569608Y220292D01*
X569358Y219875D01*
X569275Y219500D01*
X571025D01*
G01X560017Y234000D02*
Y236500D01*
X561017D01*
X561350Y236375D01*
X561600Y236083D01*
X561683Y235750D01*
X561600Y235417D01*
X561392Y235167D01*
X561017Y235042D01*
X560017D01*
G01X563117Y234000D02*
Y236500D01*
X564158D01*
X564492Y236375D01*
X564700Y236208D01*
X564783Y235875D01*
X564700Y235542D01*
X564450Y235333D01*
X564158Y235208D01*
X563117D01*
G01X564158D02*
X564783Y234000D01*
G01X566258Y235042D02*
X566550Y235333D01*
X566800Y235500D01*
X567133Y235583D01*
X567425Y235500D01*
X567633Y235333D01*
X567800Y235083D01*
X567842Y234792D01*
X567800Y234542D01*
X567633Y234292D01*
X567383Y234083D01*
X567092Y234000D01*
X566758Y234083D01*
X566467Y234333D01*
X566300Y234708D01*
X566258Y235125D01*
X566342Y235667D01*
X566467Y235958D01*
X566675Y236250D01*
X566967Y236458D01*
X567258Y236500D01*
X567550Y236417D01*
X567758Y236208D01*
G01X570150Y234000D02*
Y236500D01*
X569650Y236000D01*
G01Y234000D02*
X570650D01*
G01X560017Y238000D02*
Y240500D01*
X561017D01*
X561350Y240375D01*
X561600Y240083D01*
X561683Y239750D01*
X561600Y239417D01*
X561392Y239167D01*
X561017Y239042D01*
X560017D01*
G01X564867Y240292D02*
X564617Y240417D01*
X564325Y240500D01*
X563992D01*
X563617Y240375D01*
X563325Y240167D01*
X563117Y239917D01*
X562950Y239500D01*
X562908Y239125D01*
X562992Y238750D01*
X563117Y238500D01*
X563367Y238250D01*
X563658Y238083D01*
X563950Y238000D01*
X564242D01*
X564533Y238083D01*
X564783Y238208D01*
X564992Y238375D01*
G01X567550Y238000D02*
Y240500D01*
X566008Y238708D01*
X568092D01*
G01X570150Y240500D02*
X569817Y240417D01*
X569567Y240208D01*
X569400Y239958D01*
X569275Y239625D01*
X569233Y239250D01*
X569275Y238875D01*
X569400Y238542D01*
X569567Y238292D01*
X569817Y238083D01*
X570150Y238000D01*
X570483Y238083D01*
X570733Y238292D01*
X570900Y238542D01*
X571025Y238875D01*
X571067Y239250D01*
X571025Y239625D01*
X570900Y239958D01*
X570733Y240208D01*
X570483Y240417D01*
X570150Y240500D01*
G01X560017Y230000D02*
Y232500D01*
X561017D01*
X561350Y232375D01*
X561600Y232083D01*
X561683Y231750D01*
X561600Y231417D01*
X561392Y231167D01*
X561017Y231042D01*
X560017D01*
G01X563117Y230000D02*
Y232500D01*
X564158D01*
X564492Y232375D01*
X564700Y232208D01*
X564783Y231875D01*
X564700Y231542D01*
X564450Y231333D01*
X564158Y231208D01*
X563117D01*
G01X564158D02*
X564783Y230000D01*
G01X566258Y231042D02*
X566550Y231333D01*
X566800Y231500D01*
X567133Y231583D01*
X567425Y231500D01*
X567633Y231333D01*
X567800Y231083D01*
X567842Y230792D01*
X567800Y230542D01*
X567633Y230292D01*
X567383Y230083D01*
X567092Y230000D01*
X566758Y230083D01*
X566467Y230333D01*
X566300Y230708D01*
X566258Y231125D01*
X566342Y231667D01*
X566467Y231958D01*
X566675Y232250D01*
X566967Y232458D01*
X567258Y232500D01*
X567550Y232417D01*
X567758Y232208D01*
G01X569233Y230375D02*
X569483Y230167D01*
X569775Y230042D01*
X570150Y230000D01*
X570525Y230083D01*
X570817Y230250D01*
X571025Y230542D01*
X571067Y230875D01*
X570983Y231208D01*
X570775Y231417D01*
X570483Y231583D01*
X570192Y231625D01*
X569900Y231583D01*
X569525Y231417D01*
X569650Y232500D01*
X570775D01*
G01X576267Y47292D02*
X576017Y47417D01*
X575725Y47500D01*
X575392D01*
X575017Y47375D01*
X574725Y47167D01*
X574517Y46917D01*
X574350Y46500D01*
X574308Y46125D01*
X574392Y45750D01*
X574517Y45500D01*
X574767Y45250D01*
X575058Y45083D01*
X575350Y45000D01*
X575642D01*
X575933Y45083D01*
X576183Y45208D01*
X576392Y45375D01*
G01X577658Y47083D02*
X577908Y47333D01*
X578200Y47458D01*
X578533Y47500D01*
X578950Y47417D01*
X579242Y47208D01*
X579325Y46958D01*
X579283Y46708D01*
X579117Y46500D01*
X578283Y46083D01*
X577908Y45792D01*
X577658Y45375D01*
X577575Y45000D01*
X579325D01*
G01X580842Y45292D02*
X581133Y45083D01*
X581467Y45000D01*
X581800Y45083D01*
X582092Y45333D01*
X582300Y45708D01*
X582383Y46083D01*
Y46542D01*
X582300Y46917D01*
X582092Y47250D01*
X581842Y47417D01*
X581550Y47500D01*
X581217Y47417D01*
X580967Y47250D01*
X580800Y47000D01*
X580717Y46667D01*
X580800Y46375D01*
X581008Y46083D01*
X581258Y45917D01*
X581550Y45875D01*
X581883Y45958D01*
X582133Y46167D01*
X582383Y46542D01*
G01X583733Y45375D02*
X583983Y45167D01*
X584275Y45042D01*
X584650Y45000D01*
X585025Y45083D01*
X585317Y45250D01*
X585525Y45542D01*
X585567Y45875D01*
X585483Y46208D01*
X585275Y46417D01*
X584983Y46583D01*
X584692Y46625D01*
X584400Y46583D01*
X584025Y46417D01*
X584150Y47500D01*
X585275D01*
G01X583517Y55500D02*
Y58000D01*
X584558D01*
X584892Y57875D01*
X585100Y57708D01*
X585183Y57375D01*
X585100Y57042D01*
X584850Y56833D01*
X584558Y56708D01*
X583517D01*
G01X584558D02*
X585183Y55500D01*
G01X586533Y56000D02*
X586783Y55708D01*
X587117Y55542D01*
X587492Y55500D01*
X587825Y55542D01*
X588158Y55750D01*
X588367Y56000D01*
X588408Y56250D01*
X588325Y56542D01*
X588033Y56750D01*
X587742Y56833D01*
X587367D01*
G01X587742D02*
X587992Y56958D01*
X588200Y57167D01*
X588283Y57417D01*
X588200Y57667D01*
X587992Y57875D01*
X587617Y58000D01*
X587242Y57958D01*
X586867Y57792D01*
G01X590550Y55500D02*
X590842Y55542D01*
X591175Y55667D01*
X591383Y55875D01*
X591467Y56167D01*
X591383Y56458D01*
X591133Y56708D01*
X590758Y56833D01*
X590342D01*
X590092Y56917D01*
X589883Y57125D01*
X589800Y57417D01*
X589925Y57708D01*
X590217Y57917D01*
X590550Y58000D01*
X590883Y57917D01*
X591175Y57708D01*
X591300Y57417D01*
X591217Y57125D01*
X591008Y56917D01*
X590758Y56833D01*
X590342D01*
X589967Y56708D01*
X589717Y56458D01*
X589633Y56167D01*
X589717Y55875D01*
X589925Y55667D01*
X590258Y55542D01*
X590550Y55500D01*
G01X592858Y56542D02*
X593150Y56833D01*
X593400Y57000D01*
X593733Y57083D01*
X594025Y57000D01*
X594233Y56833D01*
X594400Y56583D01*
X594442Y56292D01*
X594400Y56042D01*
X594233Y55792D01*
X593983Y55583D01*
X593692Y55500D01*
X593358Y55583D01*
X593067Y55833D01*
X592900Y56208D01*
X592858Y56625D01*
X592942Y57167D01*
X593067Y57458D01*
X593275Y57750D01*
X593567Y57958D01*
X593858Y58000D01*
X594150Y57917D01*
X594358Y57708D01*
G01X587717Y45100D02*
Y47600D01*
X588758D01*
X589092Y47475D01*
X589300Y47308D01*
X589383Y46975D01*
X589300Y46642D01*
X589050Y46433D01*
X588758Y46308D01*
X587717D01*
G01X588758D02*
X589383Y45100D01*
G01X590733Y45600D02*
X590983Y45308D01*
X591317Y45142D01*
X591692Y45100D01*
X592025Y45142D01*
X592358Y45350D01*
X592567Y45600D01*
X592608Y45850D01*
X592525Y46142D01*
X592233Y46350D01*
X591942Y46433D01*
X591567D01*
G01X591942D02*
X592192Y46558D01*
X592400Y46767D01*
X592483Y47017D01*
X592400Y47267D01*
X592192Y47475D01*
X591817Y47600D01*
X591442Y47558D01*
X591067Y47392D01*
G01X594750Y45100D02*
X595042Y45142D01*
X595375Y45267D01*
X595583Y45475D01*
X595667Y45767D01*
X595583Y46058D01*
X595333Y46308D01*
X594958Y46433D01*
X594542D01*
X594292Y46517D01*
X594083Y46725D01*
X594000Y47017D01*
X594125Y47308D01*
X594417Y47517D01*
X594750Y47600D01*
X595083Y47517D01*
X595375Y47308D01*
X595500Y47017D01*
X595417Y46725D01*
X595208Y46517D01*
X594958Y46433D01*
X594542D01*
X594167Y46308D01*
X593917Y46058D01*
X593833Y45767D01*
X593917Y45475D01*
X594125Y45267D01*
X594458Y45142D01*
X594750Y45100D01*
G01X596933Y45475D02*
X597183Y45267D01*
X597475Y45142D01*
X597850Y45100D01*
X598225Y45183D01*
X598517Y45350D01*
X598725Y45642D01*
X598767Y45975D01*
X598683Y46308D01*
X598475Y46517D01*
X598183Y46683D01*
X597892Y46725D01*
X597600Y46683D01*
X597225Y46517D01*
X597350Y47600D01*
X598475D01*
G01X584208Y65817D02*
X584083Y65567D01*
X584000Y65275D01*
Y64942D01*
X584125Y64567D01*
X584333Y64275D01*
X584583Y64067D01*
X585000Y63900D01*
X585375Y63858D01*
X585750Y63942D01*
X586000Y64067D01*
X586250Y64317D01*
X586417Y64608D01*
X586500Y64900D01*
Y65192D01*
X586417Y65483D01*
X586292Y65733D01*
X586125Y65942D01*
G01X586500Y68500D02*
X584000D01*
X585792Y66958D01*
Y69042D01*
G01X586208Y70392D02*
X586417Y70683D01*
X586500Y71017D01*
X586417Y71350D01*
X586167Y71642D01*
X585792Y71850D01*
X585417Y71933D01*
X584958D01*
X584583Y71850D01*
X584250Y71642D01*
X584083Y71392D01*
X584000Y71100D01*
X584083Y70767D01*
X584250Y70517D01*
X584500Y70350D01*
X584833Y70267D01*
X585125Y70350D01*
X585417Y70558D01*
X585583Y70808D01*
X585625Y71100D01*
X585542Y71433D01*
X585333Y71683D01*
X584958Y71933D01*
G01X579500Y61900D02*
X582000D01*
G01X579500Y60942D02*
Y62858D01*
G01X582000Y64167D02*
X579500D01*
Y65167D01*
X579625Y65500D01*
X579917Y65750D01*
X580250Y65833D01*
X580583Y65750D01*
X580833Y65542D01*
X580958Y65167D01*
Y64167D01*
G01X582000Y68100D02*
X581958Y68392D01*
X581833Y68725D01*
X581625Y68933D01*
X581333Y69017D01*
X581042Y68933D01*
X580792Y68683D01*
X580667Y68308D01*
Y67892D01*
X580583Y67642D01*
X580375Y67433D01*
X580083Y67350D01*
X579792Y67475D01*
X579583Y67767D01*
X579500Y68100D01*
X579583Y68433D01*
X579792Y68725D01*
X580083Y68850D01*
X580375Y68767D01*
X580583Y68558D01*
X580667Y68308D01*
Y67892D01*
X580792Y67517D01*
X581042Y67267D01*
X581333Y67183D01*
X581625Y67267D01*
X581833Y67475D01*
X581958Y67808D01*
X582000Y68100D01*
G01X573500Y61350D02*
X576000D01*
G01X573500Y60392D02*
Y62308D01*
G01X576000Y63617D02*
X573500D01*
Y64617D01*
X573625Y64950D01*
X573917Y65200D01*
X574250Y65283D01*
X574583Y65200D01*
X574833Y64992D01*
X574958Y64617D01*
Y63617D01*
G01X576000Y67550D02*
X573500D01*
X574000Y67050D01*
G01X576000D02*
Y68050D01*
G01Y70650D02*
X573500D01*
X574000Y70150D01*
G01X576000D02*
Y71150D01*
G01X586317Y88292D02*
X586067Y88417D01*
X585775Y88500D01*
X585442D01*
X585067Y88375D01*
X584775Y88167D01*
X584567Y87917D01*
X584400Y87500D01*
X584358Y87125D01*
X584442Y86750D01*
X584567Y86500D01*
X584817Y86250D01*
X585108Y86083D01*
X585400Y86000D01*
X585692D01*
X585983Y86083D01*
X586233Y86208D01*
X586442Y86375D01*
G01X589000Y86000D02*
Y88500D01*
X587458Y86708D01*
X589542D01*
G01X590808Y87042D02*
X591100Y87333D01*
X591350Y87500D01*
X591683Y87583D01*
X591975Y87500D01*
X592183Y87333D01*
X592350Y87083D01*
X592392Y86792D01*
X592350Y86542D01*
X592183Y86292D01*
X591933Y86083D01*
X591642Y86000D01*
X591308Y86083D01*
X591017Y86333D01*
X590850Y86708D01*
X590808Y87125D01*
X590892Y87667D01*
X591017Y87958D01*
X591225Y88250D01*
X591517Y88458D01*
X591808Y88500D01*
X592100Y88417D01*
X592308Y88208D01*
G01X582000Y78517D02*
X579500D01*
Y79558D01*
X579625Y79892D01*
X579792Y80100D01*
X580125Y80183D01*
X580458Y80100D01*
X580667Y79850D01*
X580792Y79558D01*
Y78517D01*
G01Y79558D02*
X582000Y80183D01*
G01Y82450D02*
X579500D01*
X580000Y81950D01*
G01X582000D02*
Y82950D01*
G01X579500Y85550D02*
X579583Y85217D01*
X579792Y84967D01*
X580042Y84800D01*
X580375Y84675D01*
X580750Y84633D01*
X581125Y84675D01*
X581458Y84800D01*
X581708Y84967D01*
X581917Y85217D01*
X582000Y85550D01*
X581917Y85883D01*
X581708Y86133D01*
X581458Y86300D01*
X581125Y86425D01*
X580750Y86467D01*
X580375Y86425D01*
X580042Y86300D01*
X579792Y86133D01*
X579583Y85883D01*
X579500Y85550D01*
G01Y88650D02*
X579583Y88317D01*
X579792Y88067D01*
X580042Y87900D01*
X580375Y87775D01*
X580750Y87733D01*
X581125Y87775D01*
X581458Y87900D01*
X581708Y88067D01*
X581917Y88317D01*
X582000Y88650D01*
X581917Y88983D01*
X581708Y89233D01*
X581458Y89400D01*
X581125Y89525D01*
X580750Y89567D01*
X580375Y89525D01*
X580042Y89400D01*
X579792Y89233D01*
X579583Y88983D01*
X579500Y88650D01*
G01X584483Y184000D02*
Y182208D01*
X584650Y181833D01*
X584983Y181583D01*
X585400Y181500D01*
X585817Y181583D01*
X586150Y181833D01*
X586317Y182208D01*
Y184000D01*
G01X587583Y181875D02*
X587833Y181667D01*
X588125Y181542D01*
X588500Y181500D01*
X588875Y181583D01*
X589167Y181750D01*
X589375Y182042D01*
X589417Y182375D01*
X589333Y182708D01*
X589125Y182917D01*
X588833Y183083D01*
X588542Y183125D01*
X588250Y183083D01*
X587875Y182917D01*
X588000Y184000D01*
X589125D01*
G01X591600D02*
X591267Y183917D01*
X591017Y183708D01*
X590850Y183458D01*
X590725Y183125D01*
X590683Y182750D01*
X590725Y182375D01*
X590850Y182042D01*
X591017Y181792D01*
X591267Y181583D01*
X591600Y181500D01*
X591933Y181583D01*
X592183Y181792D01*
X592350Y182042D01*
X592475Y182375D01*
X592517Y182750D01*
X592475Y183125D01*
X592350Y183458D01*
X592183Y183708D01*
X591933Y183917D01*
X591600Y184000D01*
G01X593000Y204850D02*
X579000D01*
Y224755D01*
X593000D01*
Y204850D01*
G01X586100Y206350D02*
X587600Y204850D01*
G01X584600D02*
X586100Y206350D01*
G01X575000Y201050D02*
X575550D01*
G01X575000Y204450D02*
Y201050D01*
G01X579400Y204450D02*
X575000D01*
G01X579400Y203900D02*
Y204450D01*
G01Y203900D02*
Y203350D01*
G01X575550Y203900D02*
X579400D01*
G01X575550Y201050D02*
Y203900D01*
G01X576100Y201050D02*
X575550D01*
G01X576100Y203350D02*
X579400D01*
G01X576100Y201050D02*
Y203350D01*
G01X576708Y229267D02*
X576583Y229017D01*
X576500Y228725D01*
Y228392D01*
X576625Y228017D01*
X576833Y227725D01*
X577083Y227517D01*
X577500Y227350D01*
X577875Y227308D01*
X578250Y227392D01*
X578500Y227517D01*
X578750Y227767D01*
X578917Y228058D01*
X579000Y228350D01*
Y228642D01*
X578917Y228933D01*
X578792Y229183D01*
X578625Y229392D01*
G01X578500Y230533D02*
X578792Y230783D01*
X578958Y231117D01*
X579000Y231492D01*
X578958Y231825D01*
X578750Y232158D01*
X578500Y232367D01*
X578250Y232408D01*
X577958Y232325D01*
X577750Y232033D01*
X577667Y231742D01*
Y231367D01*
G01Y231742D02*
X577542Y231992D01*
X577333Y232200D01*
X577083Y232283D01*
X576833Y232200D01*
X576625Y231992D01*
X576500Y231617D01*
X576542Y231242D01*
X576708Y230867D01*
G01X577958Y233758D02*
X577667Y234050D01*
X577500Y234300D01*
X577417Y234633D01*
X577500Y234925D01*
X577667Y235133D01*
X577917Y235300D01*
X578208Y235342D01*
X578458Y235300D01*
X578708Y235133D01*
X578917Y234883D01*
X579000Y234592D01*
X578917Y234258D01*
X578667Y233967D01*
X578292Y233800D01*
X577875Y233758D01*
X577333Y233842D01*
X577042Y233967D01*
X576750Y234175D01*
X576542Y234467D01*
X576500Y234758D01*
X576583Y235050D01*
X576792Y235258D01*
G01X578708Y236942D02*
X578917Y237233D01*
X579000Y237567D01*
X578917Y237900D01*
X578667Y238192D01*
X578292Y238400D01*
X577917Y238483D01*
X577458D01*
X577083Y238400D01*
X576750Y238192D01*
X576583Y237942D01*
X576500Y237650D01*
X576583Y237317D01*
X576750Y237067D01*
X577000Y236900D01*
X577333Y236817D01*
X577625Y236900D01*
X577917Y237108D01*
X578083Y237358D01*
X578125Y237650D01*
X578042Y237983D01*
X577833Y238233D01*
X577458Y238483D01*
G01X572708Y229317D02*
X572583Y229067D01*
X572500Y228775D01*
Y228442D01*
X572625Y228067D01*
X572833Y227775D01*
X573083Y227567D01*
X573500Y227400D01*
X573875Y227358D01*
X574250Y227442D01*
X574500Y227567D01*
X574750Y227817D01*
X574917Y228108D01*
X575000Y228400D01*
Y228692D01*
X574917Y228983D01*
X574792Y229233D01*
X574625Y229442D01*
G01X575000Y231500D02*
X572500D01*
X573000Y231000D01*
G01X575000D02*
Y232000D01*
G01X572500Y234600D02*
X572583Y234267D01*
X572792Y234017D01*
X573042Y233850D01*
X573375Y233725D01*
X573750Y233683D01*
X574125Y233725D01*
X574458Y233850D01*
X574708Y234017D01*
X574917Y234267D01*
X575000Y234600D01*
X574917Y234933D01*
X574708Y235183D01*
X574458Y235350D01*
X574125Y235475D01*
X573750Y235517D01*
X573375Y235475D01*
X573042Y235350D01*
X572792Y235183D01*
X572583Y234933D01*
X572500Y234600D01*
G01X596467Y55507D02*
Y58007D01*
X597467D01*
X597800Y57882D01*
X598050Y57590D01*
X598133Y57257D01*
X598050Y56924D01*
X597842Y56674D01*
X597467Y56549D01*
X596467D01*
G01X599567Y55507D02*
Y58007D01*
X600608D01*
X600942Y57882D01*
X601150Y57715D01*
X601233Y57382D01*
X601150Y57049D01*
X600900Y56840D01*
X600608Y56715D01*
X599567D01*
G01X600608D02*
X601233Y55507D01*
G01X602708Y57590D02*
X602958Y57840D01*
X603250Y57965D01*
X603583Y58007D01*
X604000Y57924D01*
X604292Y57715D01*
X604375Y57465D01*
X604333Y57215D01*
X604167Y57007D01*
X603333Y56590D01*
X602958Y56299D01*
X602708Y55882D01*
X602625Y55507D01*
X604375D01*
G01X606600D02*
Y58007D01*
X606100Y57507D01*
G01Y55507D02*
X607100D01*
G01X609617D02*
X609700Y56049D01*
X609825Y56507D01*
X609992Y56924D01*
X610200Y57382D01*
X610533Y58007D01*
X608867D01*
G01X596467Y59507D02*
Y62007D01*
X597467D01*
X597800Y61882D01*
X598050Y61590D01*
X598133Y61257D01*
X598050Y60924D01*
X597842Y60674D01*
X597467Y60549D01*
X596467D01*
G01X599567Y59507D02*
Y62007D01*
X600608D01*
X600942Y61882D01*
X601150Y61715D01*
X601233Y61382D01*
X601150Y61049D01*
X600900Y60840D01*
X600608Y60715D01*
X599567D01*
G01X600608D02*
X601233Y59507D01*
G01X602708Y61590D02*
X602958Y61840D01*
X603250Y61965D01*
X603583Y62007D01*
X604000Y61924D01*
X604292Y61715D01*
X604375Y61465D01*
X604333Y61215D01*
X604167Y61007D01*
X603333Y60590D01*
X602958Y60299D01*
X602708Y59882D01*
X602625Y59507D01*
X604375D01*
G01X606600Y62007D02*
X606267Y61924D01*
X606017Y61715D01*
X605850Y61465D01*
X605725Y61132D01*
X605683Y60757D01*
X605725Y60382D01*
X605850Y60049D01*
X606017Y59799D01*
X606267Y59590D01*
X606600Y59507D01*
X606933Y59590D01*
X607183Y59799D01*
X607350Y60049D01*
X607475Y60382D01*
X607517Y60757D01*
X607475Y61132D01*
X607350Y61465D01*
X607183Y61715D01*
X606933Y61924D01*
X606600Y62007D01*
G01X608783Y59882D02*
X609033Y59674D01*
X609325Y59549D01*
X609700Y59507D01*
X610075Y59590D01*
X610367Y59757D01*
X610575Y60049D01*
X610617Y60382D01*
X610533Y60715D01*
X610325Y60924D01*
X610033Y61090D01*
X609742Y61132D01*
X609450Y61090D01*
X609075Y60924D01*
X609200Y62007D01*
X610325D01*
G01X588208Y65817D02*
X588083Y65567D01*
X588000Y65275D01*
Y64942D01*
X588125Y64567D01*
X588333Y64275D01*
X588583Y64067D01*
X589000Y63900D01*
X589375Y63858D01*
X589750Y63942D01*
X590000Y64067D01*
X590250Y64317D01*
X590417Y64608D01*
X590500Y64900D01*
Y65192D01*
X590417Y65483D01*
X590292Y65733D01*
X590125Y65942D01*
G01Y67083D02*
X590333Y67333D01*
X590458Y67625D01*
X590500Y68000D01*
X590417Y68375D01*
X590250Y68667D01*
X589958Y68875D01*
X589625Y68917D01*
X589292Y68833D01*
X589083Y68625D01*
X588917Y68333D01*
X588875Y68042D01*
X588917Y67750D01*
X589083Y67375D01*
X588000Y67500D01*
Y68625D01*
G01X590500Y71600D02*
X588000D01*
X589792Y70058D01*
Y72142D01*
G01X600350Y70500D02*
Y68000D01*
G01X599392Y70500D02*
X601308D01*
G01X602617Y68000D02*
Y70500D01*
X603617D01*
X603950Y70375D01*
X604200Y70083D01*
X604283Y69750D01*
X604200Y69417D01*
X603992Y69167D01*
X603617Y69042D01*
X602617D01*
G01X606550Y68000D02*
Y70500D01*
X606050Y70000D01*
G01Y68000D02*
X607050D01*
G01X610150D02*
Y70500D01*
X608608Y68708D01*
X610692D01*
G01X600350Y74500D02*
Y72000D01*
G01X599392Y74500D02*
X601308D01*
G01X602617Y72000D02*
Y74500D01*
X603617D01*
X603950Y74375D01*
X604200Y74083D01*
X604283Y73750D01*
X604200Y73417D01*
X603992Y73167D01*
X603617Y73042D01*
X602617D01*
G01X605758Y74083D02*
X606008Y74333D01*
X606300Y74458D01*
X606633Y74500D01*
X607050Y74417D01*
X607342Y74208D01*
X607425Y73958D01*
X607383Y73708D01*
X607217Y73500D01*
X606383Y73083D01*
X606008Y72792D01*
X605758Y72375D01*
X605675Y72000D01*
X607425D01*
G01X609650D02*
Y74500D01*
X609150Y74000D01*
G01Y72000D02*
X610150D01*
G01X600350Y82500D02*
Y80000D01*
G01X599392Y82500D02*
X601308D01*
G01X602617Y80000D02*
Y82500D01*
X603617D01*
X603950Y82375D01*
X604200Y82083D01*
X604283Y81750D01*
X604200Y81417D01*
X603992Y81167D01*
X603617Y81042D01*
X602617D01*
G01X605758D02*
X606050Y81333D01*
X606300Y81500D01*
X606633Y81583D01*
X606925Y81500D01*
X607133Y81333D01*
X607300Y81083D01*
X607342Y80792D01*
X607300Y80542D01*
X607133Y80292D01*
X606883Y80083D01*
X606592Y80000D01*
X606258Y80083D01*
X605967Y80333D01*
X605800Y80708D01*
X605758Y81125D01*
X605842Y81667D01*
X605967Y81958D01*
X606175Y82250D01*
X606467Y82458D01*
X606758Y82500D01*
X607050Y82417D01*
X607258Y82208D01*
G01X608733Y80500D02*
X608983Y80208D01*
X609317Y80042D01*
X609692Y80000D01*
X610025Y80042D01*
X610358Y80250D01*
X610567Y80500D01*
X610608Y80750D01*
X610525Y81042D01*
X610233Y81250D01*
X609942Y81333D01*
X609567D01*
G01X609942D02*
X610192Y81458D01*
X610400Y81667D01*
X610483Y81917D01*
X610400Y82167D01*
X610192Y82375D01*
X609817Y82500D01*
X609442Y82458D01*
X609067Y82292D01*
G01X600350Y78500D02*
Y76000D01*
G01X599392Y78500D02*
X601308D01*
G01X602617Y76000D02*
Y78500D01*
X603617D01*
X603950Y78375D01*
X604200Y78083D01*
X604283Y77750D01*
X604200Y77417D01*
X603992Y77167D01*
X603617Y77042D01*
X602617D01*
G01X605758D02*
X606050Y77333D01*
X606300Y77500D01*
X606633Y77583D01*
X606925Y77500D01*
X607133Y77333D01*
X607300Y77083D01*
X607342Y76792D01*
X607300Y76542D01*
X607133Y76292D01*
X606883Y76083D01*
X606592Y76000D01*
X606258Y76083D01*
X605967Y76333D01*
X605800Y76708D01*
X605758Y77125D01*
X605842Y77667D01*
X605967Y77958D01*
X606175Y78250D01*
X606467Y78458D01*
X606758Y78500D01*
X607050Y78417D01*
X607258Y78208D01*
G01X608858Y78083D02*
X609108Y78333D01*
X609400Y78458D01*
X609733Y78500D01*
X610150Y78417D01*
X610442Y78208D01*
X610525Y77958D01*
X610483Y77708D01*
X610317Y77500D01*
X609483Y77083D01*
X609108Y76792D01*
X608858Y76375D01*
X608775Y76000D01*
X610525D01*
G01X600500Y182850D02*
X603000D01*
G01X600500Y181892D02*
Y183808D01*
G01X603000Y185117D02*
X600500D01*
Y186117D01*
X600625Y186450D01*
X600917Y186700D01*
X601250Y186783D01*
X601583Y186700D01*
X601833Y186492D01*
X601958Y186117D01*
Y185117D01*
G01X603000Y189550D02*
X600500D01*
X602292Y188008D01*
Y190092D01*
G01X600500Y192150D02*
X600583Y191817D01*
X600792Y191567D01*
X601042Y191400D01*
X601375Y191275D01*
X601750Y191233D01*
X602125Y191275D01*
X602458Y191400D01*
X602708Y191567D01*
X602917Y191817D01*
X603000Y192150D01*
X602917Y192483D01*
X602708Y192733D01*
X602458Y192900D01*
X602125Y193025D01*
X601750Y193067D01*
X601375Y193025D01*
X601042Y192900D01*
X600792Y192733D01*
X600583Y192483D01*
X600500Y192150D01*
G01X604500Y201017D02*
X602000D01*
Y202058D01*
X602125Y202392D01*
X602292Y202600D01*
X602625Y202683D01*
X602958Y202600D01*
X603167Y202350D01*
X603292Y202058D01*
Y201017D01*
G01Y202058D02*
X604500Y202683D01*
G01X602417Y204158D02*
X602167Y204408D01*
X602042Y204700D01*
X602000Y205033D01*
X602083Y205450D01*
X602292Y205742D01*
X602542Y205825D01*
X602792Y205783D01*
X603000Y205617D01*
X603417Y204783D01*
X603708Y204408D01*
X604125Y204158D01*
X604500Y204075D01*
Y205825D01*
G01Y208050D02*
X604458Y208342D01*
X604333Y208675D01*
X604125Y208883D01*
X603833Y208967D01*
X603542Y208883D01*
X603292Y208633D01*
X603167Y208258D01*
Y207842D01*
X603083Y207592D01*
X602875Y207383D01*
X602583Y207300D01*
X602292Y207425D01*
X602083Y207717D01*
X602000Y208050D01*
X602083Y208383D01*
X602292Y208675D01*
X602583Y208800D01*
X602875Y208717D01*
X603083Y208508D01*
X603167Y208258D01*
Y207842D01*
X603292Y207467D01*
X603542Y207217D01*
X603833Y207133D01*
X604125Y207217D01*
X604333Y207425D01*
X604458Y207758D01*
X604500Y208050D01*
G01X603458Y210358D02*
X603167Y210650D01*
X603000Y210900D01*
X602917Y211233D01*
X603000Y211525D01*
X603167Y211733D01*
X603417Y211900D01*
X603708Y211942D01*
X603958Y211900D01*
X604208Y211733D01*
X604417Y211483D01*
X604500Y211192D01*
X604417Y210858D01*
X604167Y210567D01*
X603792Y210400D01*
X603375Y210358D01*
X602833Y210442D01*
X602542Y210567D01*
X602250Y210775D01*
X602042Y211067D01*
X602000Y211358D01*
X602083Y211650D01*
X602292Y211858D01*
G01X599708Y228267D02*
X599583Y228017D01*
X599500Y227725D01*
Y227392D01*
X599625Y227017D01*
X599833Y226725D01*
X600083Y226517D01*
X600500Y226350D01*
X600875Y226308D01*
X601250Y226392D01*
X601500Y226517D01*
X601750Y226767D01*
X601917Y227058D01*
X602000Y227350D01*
Y227642D01*
X601917Y227933D01*
X601792Y228183D01*
X601625Y228392D01*
G01X601500Y229533D02*
X601792Y229783D01*
X601958Y230117D01*
X602000Y230492D01*
X601958Y230825D01*
X601750Y231158D01*
X601500Y231367D01*
X601250Y231408D01*
X600958Y231325D01*
X600750Y231033D01*
X600667Y230742D01*
Y230367D01*
G01Y230742D02*
X600542Y230992D01*
X600333Y231200D01*
X600083Y231283D01*
X599833Y231200D01*
X599625Y230992D01*
X599500Y230617D01*
X599542Y230242D01*
X599708Y229867D01*
G01X600958Y232758D02*
X600667Y233050D01*
X600500Y233300D01*
X600417Y233633D01*
X600500Y233925D01*
X600667Y234133D01*
X600917Y234300D01*
X601208Y234342D01*
X601458Y234300D01*
X601708Y234133D01*
X601917Y233883D01*
X602000Y233592D01*
X601917Y233258D01*
X601667Y232967D01*
X601292Y232800D01*
X600875Y232758D01*
X600333Y232842D01*
X600042Y232967D01*
X599750Y233175D01*
X599542Y233467D01*
X599500Y233758D01*
X599583Y234050D01*
X599792Y234258D01*
G01X602000Y236650D02*
X601958Y236942D01*
X601833Y237275D01*
X601625Y237483D01*
X601333Y237567D01*
X601042Y237483D01*
X600792Y237233D01*
X600667Y236858D01*
Y236442D01*
X600583Y236192D01*
X600375Y235983D01*
X600083Y235900D01*
X599792Y236025D01*
X599583Y236317D01*
X599500Y236650D01*
X599583Y236983D01*
X599792Y237275D01*
X600083Y237400D01*
X600375Y237317D01*
X600583Y237108D01*
X600667Y236858D01*
Y236442D01*
X600792Y236067D01*
X601042Y235817D01*
X601333Y235733D01*
X601625Y235817D01*
X601833Y236025D01*
X601958Y236358D01*
X602000Y236650D01*
G01X604267Y240792D02*
X604017Y240917D01*
X603725Y241000D01*
X603392D01*
X603017Y240875D01*
X602725Y240667D01*
X602517Y240417D01*
X602350Y240000D01*
X602308Y239625D01*
X602392Y239250D01*
X602517Y239000D01*
X602767Y238750D01*
X603058Y238583D01*
X603350Y238500D01*
X603642D01*
X603933Y238583D01*
X604183Y238708D01*
X604392Y238875D01*
G01X605533Y239000D02*
X605783Y238708D01*
X606117Y238542D01*
X606492Y238500D01*
X606825Y238542D01*
X607158Y238750D01*
X607367Y239000D01*
X607408Y239250D01*
X607325Y239542D01*
X607033Y239750D01*
X606742Y239833D01*
X606367D01*
G01X606742D02*
X606992Y239958D01*
X607200Y240167D01*
X607283Y240417D01*
X607200Y240667D01*
X606992Y240875D01*
X606617Y241000D01*
X606242Y240958D01*
X605867Y240792D01*
G01X608758Y240583D02*
X609008Y240833D01*
X609300Y240958D01*
X609633Y241000D01*
X610050Y240917D01*
X610342Y240708D01*
X610425Y240458D01*
X610383Y240208D01*
X610217Y240000D01*
X609383Y239583D01*
X609008Y239292D01*
X608758Y238875D01*
X608675Y238500D01*
X610425D01*
G01X611858Y239542D02*
X612150Y239833D01*
X612400Y240000D01*
X612733Y240083D01*
X613025Y240000D01*
X613233Y239833D01*
X613400Y239583D01*
X613442Y239292D01*
X613400Y239042D01*
X613233Y238792D01*
X612983Y238583D01*
X612692Y238500D01*
X612358Y238583D01*
X612067Y238833D01*
X611900Y239208D01*
X611858Y239625D01*
X611942Y240167D01*
X612067Y240458D01*
X612275Y240750D01*
X612567Y240958D01*
X612858Y241000D01*
X613150Y240917D01*
X613358Y240708D01*
G01X614767Y59792D02*
X614517Y59917D01*
X614225Y60000D01*
X613892D01*
X613517Y59875D01*
X613225Y59667D01*
X613017Y59417D01*
X612850Y59000D01*
X612808Y58625D01*
X612892Y58250D01*
X613017Y58000D01*
X613267Y57750D01*
X613558Y57583D01*
X613850Y57500D01*
X614142D01*
X614433Y57583D01*
X614683Y57708D01*
X614892Y57875D01*
G01X616033Y58000D02*
X616283Y57708D01*
X616617Y57542D01*
X616992Y57500D01*
X617325Y57542D01*
X617658Y57750D01*
X617867Y58000D01*
X617908Y58250D01*
X617825Y58542D01*
X617533Y58750D01*
X617242Y58833D01*
X616867D01*
G01X617242D02*
X617492Y58958D01*
X617700Y59167D01*
X617783Y59417D01*
X617700Y59667D01*
X617492Y59875D01*
X617117Y60000D01*
X616742Y59958D01*
X616367Y59792D01*
G01X619967Y57500D02*
X620050Y58042D01*
X620175Y58500D01*
X620342Y58917D01*
X620550Y59375D01*
X620883Y60000D01*
X619217D01*
G01X623150Y57500D02*
Y60000D01*
X622650Y59500D01*
G01Y57500D02*
X623650D01*
G01X612517Y65000D02*
Y67500D01*
X613558D01*
X613892Y67375D01*
X614100Y67208D01*
X614183Y66875D01*
X614100Y66542D01*
X613850Y66333D01*
X613558Y66208D01*
X612517D01*
G01X613558D02*
X614183Y65000D01*
G01X616950D02*
Y67500D01*
X615408Y65708D01*
X617492D01*
G01X619550Y65000D02*
Y67500D01*
X619050Y67000D01*
G01Y65000D02*
X620050D01*
G01X623150D02*
Y67500D01*
X621608Y65708D01*
X623692D01*
G01X612517Y69000D02*
Y71500D01*
X613558D01*
X613892Y71375D01*
X614100Y71208D01*
X614183Y70875D01*
X614100Y70542D01*
X613850Y70333D01*
X613558Y70208D01*
X612517D01*
G01X613558D02*
X614183Y69000D01*
G01X616450D02*
Y71500D01*
X615950Y71000D01*
G01Y69000D02*
X616950D01*
G01X619550D02*
Y71500D01*
X619050Y71000D01*
G01Y69000D02*
X620050D01*
G01X623150D02*
Y71500D01*
X621608Y69708D01*
X623692D01*
G01X605817Y90292D02*
X605567Y90417D01*
X605275Y90500D01*
X604942D01*
X604567Y90375D01*
X604275Y90167D01*
X604067Y89917D01*
X603900Y89500D01*
X603858Y89125D01*
X603942Y88750D01*
X604067Y88500D01*
X604317Y88250D01*
X604608Y88083D01*
X604900Y88000D01*
X605192D01*
X605483Y88083D01*
X605733Y88208D01*
X605942Y88375D01*
G01X607917Y88000D02*
X608000Y88542D01*
X608125Y89000D01*
X608292Y89417D01*
X608500Y89875D01*
X608833Y90500D01*
X607167D01*
G01X611600Y88000D02*
Y90500D01*
X610058Y88708D01*
X612142D01*
G01X605817Y86292D02*
X605567Y86417D01*
X605275Y86500D01*
X604942D01*
X604567Y86375D01*
X604275Y86167D01*
X604067Y85917D01*
X603900Y85500D01*
X603858Y85125D01*
X603942Y84750D01*
X604067Y84500D01*
X604317Y84250D01*
X604608Y84083D01*
X604900Y84000D01*
X605192D01*
X605483Y84083D01*
X605733Y84208D01*
X605942Y84375D01*
G01X607917Y84000D02*
X608000Y84542D01*
X608125Y85000D01*
X608292Y85417D01*
X608500Y85875D01*
X608833Y86500D01*
X607167D01*
G01X610183Y84500D02*
X610433Y84208D01*
X610767Y84042D01*
X611142Y84000D01*
X611475Y84042D01*
X611808Y84250D01*
X612017Y84500D01*
X612058Y84750D01*
X611975Y85042D01*
X611683Y85250D01*
X611392Y85333D01*
X611017D01*
G01X611392D02*
X611642Y85458D01*
X611850Y85667D01*
X611933Y85917D01*
X611850Y86167D01*
X611642Y86375D01*
X611267Y86500D01*
X610892Y86458D01*
X610517Y86292D01*
G01X608500Y121483D02*
X610292D01*
X610667Y121650D01*
X610917Y121983D01*
X611000Y122400D01*
X610917Y122817D01*
X610667Y123150D01*
X610292Y123317D01*
X608500D01*
G01X611000Y125500D02*
X608500D01*
X609000Y125000D01*
G01X611000D02*
Y126000D01*
G01Y129100D02*
X608500D01*
X610292Y127558D01*
Y129642D01*
G01X615017Y144500D02*
Y142000D01*
X616683D01*
G01X619783D02*
X618117D01*
Y144500D01*
X619783D01*
G01X619117Y143292D02*
X618117D01*
G01X621133Y142000D02*
Y144500D01*
X621967D01*
X622300Y144375D01*
X622550Y144208D01*
X622758Y143958D01*
X622925Y143667D01*
X622967Y143250D01*
X622925Y142833D01*
X622758Y142542D01*
X622550Y142292D01*
X622300Y142125D01*
X621967Y142000D01*
X621133D01*
G01X625650D02*
Y144500D01*
X624108Y142708D01*
X626192D01*
G01X615217Y137400D02*
Y139900D01*
X616258D01*
X616592Y139775D01*
X616800Y139608D01*
X616883Y139275D01*
X616800Y138942D01*
X616550Y138733D01*
X616258Y138608D01*
X615217D01*
G01X616258D02*
X616883Y137400D01*
G01X619150D02*
Y139900D01*
X618650Y139400D01*
G01Y137400D02*
X619650D01*
G01X622750D02*
Y139900D01*
X621208Y138108D01*
X623292D01*
G01X624558Y139483D02*
X624808Y139733D01*
X625100Y139858D01*
X625433Y139900D01*
X625850Y139817D01*
X626142Y139608D01*
X626225Y139358D01*
X626183Y139108D01*
X626017Y138900D01*
X625183Y138483D01*
X624808Y138192D01*
X624558Y137775D01*
X624475Y137400D01*
X626225D01*
G01X617500Y165017D02*
X615000D01*
Y166058D01*
X615125Y166392D01*
X615292Y166600D01*
X615625Y166683D01*
X615958Y166600D01*
X616167Y166350D01*
X616292Y166058D01*
Y165017D01*
G01Y166058D02*
X617500Y166683D01*
G01X615417Y168158D02*
X615167Y168408D01*
X615042Y168700D01*
X615000Y169033D01*
X615083Y169450D01*
X615292Y169742D01*
X615542Y169825D01*
X615792Y169783D01*
X616000Y169617D01*
X616417Y168783D01*
X616708Y168408D01*
X617125Y168158D01*
X617500Y168075D01*
Y169825D01*
G01Y172050D02*
X615000D01*
X615500Y171550D01*
G01X617500D02*
Y172550D01*
G01X617000Y174233D02*
X617292Y174483D01*
X617458Y174817D01*
X617500Y175192D01*
X617458Y175525D01*
X617250Y175858D01*
X617000Y176067D01*
X616750Y176108D01*
X616458Y176025D01*
X616250Y175733D01*
X616167Y175442D01*
Y175067D01*
G01Y175442D02*
X616042Y175692D01*
X615833Y175900D01*
X615583Y175983D01*
X615333Y175900D01*
X615125Y175692D01*
X615000Y175317D01*
X615042Y174942D01*
X615208Y174567D01*
G01X618250Y180250D02*
X621750D01*
Y193750D01*
X618250D01*
Y180250D01*
G01X610000Y186850D02*
X612500D01*
G01X610000Y185892D02*
Y187808D01*
G01X612500Y189117D02*
X610000D01*
Y190117D01*
X610125Y190450D01*
X610417Y190700D01*
X610750Y190783D01*
X611083Y190700D01*
X611333Y190492D01*
X611458Y190117D01*
Y189117D01*
G01X612000Y192133D02*
X612292Y192383D01*
X612458Y192717D01*
X612500Y193092D01*
X612458Y193425D01*
X612250Y193758D01*
X612000Y193967D01*
X611750Y194008D01*
X611458Y193925D01*
X611250Y193633D01*
X611167Y193342D01*
Y192967D01*
G01Y193342D02*
X611042Y193592D01*
X610833Y193800D01*
X610583Y193883D01*
X610333Y193800D01*
X610125Y193592D01*
X610000Y193217D01*
X610042Y192842D01*
X610208Y192467D01*
G01X612208Y195442D02*
X612417Y195733D01*
X612500Y196067D01*
X612417Y196400D01*
X612167Y196692D01*
X611792Y196900D01*
X611417Y196983D01*
X610958D01*
X610583Y196900D01*
X610250Y196692D01*
X610083Y196442D01*
X610000Y196150D01*
X610083Y195817D01*
X610250Y195567D01*
X610500Y195400D01*
X610833Y195317D01*
X611125Y195400D01*
X611417Y195608D01*
X611583Y195858D01*
X611625Y196150D01*
X611542Y196483D01*
X611333Y196733D01*
X610958Y196983D01*
G01X616450Y195000D02*
X616117Y195042D01*
X615825Y195208D01*
X615575Y195458D01*
X615408Y195750D01*
X615325Y196083D01*
Y196417D01*
X615408Y196750D01*
X615575Y197042D01*
X615825Y197292D01*
X616117Y197458D01*
X616450Y197500D01*
X616783Y197458D01*
X617075Y197292D01*
X617325Y197042D01*
X617492Y196750D01*
X617575Y196417D01*
Y196083D01*
X617492Y195750D01*
X617325Y195458D01*
X617075Y195208D01*
X616783Y195042D01*
X616450Y195000D01*
G01X616783Y195667D02*
X617283Y195000D01*
G01X618758Y196042D02*
X619050Y196333D01*
X619300Y196500D01*
X619633Y196583D01*
X619925Y196500D01*
X620133Y196333D01*
X620300Y196083D01*
X620342Y195792D01*
X620300Y195542D01*
X620133Y195292D01*
X619883Y195083D01*
X619592Y195000D01*
X619258Y195083D01*
X618967Y195333D01*
X618800Y195708D01*
X618758Y196125D01*
X618842Y196667D01*
X618967Y196958D01*
X619175Y197250D01*
X619467Y197458D01*
X619758Y197500D01*
X620050Y197417D01*
X620258Y197208D01*
G01X607500Y186017D02*
X605000D01*
Y187058D01*
X605125Y187392D01*
X605292Y187600D01*
X605625Y187683D01*
X605958Y187600D01*
X606167Y187350D01*
X606292Y187058D01*
Y186017D01*
G01Y187058D02*
X607500Y187683D01*
G01Y190450D02*
X605000D01*
X606792Y188908D01*
Y190992D01*
G01X607500Y193050D02*
X607458Y193342D01*
X607333Y193675D01*
X607125Y193883D01*
X606833Y193967D01*
X606542Y193883D01*
X606292Y193633D01*
X606167Y193258D01*
Y192842D01*
X606083Y192592D01*
X605875Y192383D01*
X605583Y192300D01*
X605292Y192425D01*
X605083Y192717D01*
X605000Y193050D01*
X605083Y193383D01*
X605292Y193675D01*
X605583Y193800D01*
X605875Y193717D01*
X606083Y193508D01*
X606167Y193258D01*
Y192842D01*
X606292Y192467D01*
X606542Y192217D01*
X606833Y192133D01*
X607125Y192217D01*
X607333Y192425D01*
X607458Y192758D01*
X607500Y193050D01*
G01Y196650D02*
X605000D01*
X606792Y195108D01*
Y197192D01*
G01X614267Y202292D02*
X614017Y202417D01*
X613725Y202500D01*
X613392D01*
X613017Y202375D01*
X612725Y202167D01*
X612517Y201917D01*
X612350Y201500D01*
X612308Y201125D01*
X612392Y200750D01*
X612517Y200500D01*
X612767Y200250D01*
X613058Y200083D01*
X613350Y200000D01*
X613642D01*
X613933Y200083D01*
X614183Y200208D01*
X614392Y200375D01*
G01X615533Y200500D02*
X615783Y200208D01*
X616117Y200042D01*
X616492Y200000D01*
X616825Y200042D01*
X617158Y200250D01*
X617367Y200500D01*
X617408Y200750D01*
X617325Y201042D01*
X617033Y201250D01*
X616742Y201333D01*
X616367D01*
G01X616742D02*
X616992Y201458D01*
X617200Y201667D01*
X617283Y201917D01*
X617200Y202167D01*
X616992Y202375D01*
X616617Y202500D01*
X616242Y202458D01*
X615867Y202292D01*
G01X619550Y200000D02*
Y202500D01*
X619050Y202000D01*
G01Y200000D02*
X620050D01*
G01X622650D02*
Y202500D01*
X622150Y202000D01*
G01Y200000D02*
X623150D01*
G01X609500Y206017D02*
X607000D01*
Y207058D01*
X607125Y207392D01*
X607292Y207600D01*
X607625Y207683D01*
X607958Y207600D01*
X608167Y207350D01*
X608292Y207058D01*
Y206017D01*
G01Y207058D02*
X609500Y207683D01*
G01X607417Y209158D02*
X607167Y209408D01*
X607042Y209700D01*
X607000Y210033D01*
X607083Y210450D01*
X607292Y210742D01*
X607542Y210825D01*
X607792Y210783D01*
X608000Y210617D01*
X608417Y209783D01*
X608708Y209408D01*
X609125Y209158D01*
X609500Y209075D01*
Y210825D01*
G01X609208Y212342D02*
X609417Y212633D01*
X609500Y212967D01*
X609417Y213300D01*
X609167Y213592D01*
X608792Y213800D01*
X608417Y213883D01*
X607958D01*
X607583Y213800D01*
X607250Y213592D01*
X607083Y213342D01*
X607000Y213050D01*
X607083Y212717D01*
X607250Y212467D01*
X607500Y212300D01*
X607833Y212217D01*
X608125Y212300D01*
X608417Y212508D01*
X608583Y212758D01*
X608625Y213050D01*
X608542Y213383D01*
X608333Y213633D01*
X607958Y213883D01*
G01X607000Y216150D02*
X607083Y215817D01*
X607292Y215567D01*
X607542Y215400D01*
X607875Y215275D01*
X608250Y215233D01*
X608625Y215275D01*
X608958Y215400D01*
X609208Y215567D01*
X609417Y215817D01*
X609500Y216150D01*
X609417Y216483D01*
X609208Y216733D01*
X608958Y216900D01*
X608625Y217025D01*
X608250Y217067D01*
X607875Y217025D01*
X607542Y216900D01*
X607292Y216733D01*
X607083Y216483D01*
X607000Y216150D01*
G01X608208Y220767D02*
X608083Y220517D01*
X608000Y220225D01*
Y219892D01*
X608125Y219517D01*
X608333Y219225D01*
X608583Y219017D01*
X609000Y218850D01*
X609375Y218808D01*
X609750Y218892D01*
X610000Y219017D01*
X610250Y219267D01*
X610417Y219558D01*
X610500Y219850D01*
Y220142D01*
X610417Y220433D01*
X610292Y220683D01*
X610125Y220892D01*
G01X610000Y222033D02*
X610292Y222283D01*
X610458Y222617D01*
X610500Y222992D01*
X610458Y223325D01*
X610250Y223658D01*
X610000Y223867D01*
X609750Y223908D01*
X609458Y223825D01*
X609250Y223533D01*
X609167Y223242D01*
Y222867D01*
G01Y223242D02*
X609042Y223492D01*
X608833Y223700D01*
X608583Y223783D01*
X608333Y223700D01*
X608125Y223492D01*
X608000Y223117D01*
X608042Y222742D01*
X608208Y222367D01*
G01X608417Y225258D02*
X608167Y225508D01*
X608042Y225800D01*
X608000Y226133D01*
X608083Y226550D01*
X608292Y226842D01*
X608542Y226925D01*
X608792Y226883D01*
X609000Y226717D01*
X609417Y225883D01*
X609708Y225508D01*
X610125Y225258D01*
X610500Y225175D01*
Y226925D01*
G01X610208Y228442D02*
X610417Y228733D01*
X610500Y229067D01*
X610417Y229400D01*
X610167Y229692D01*
X609792Y229900D01*
X609417Y229983D01*
X608958D01*
X608583Y229900D01*
X608250Y229692D01*
X608083Y229442D01*
X608000Y229150D01*
X608083Y228817D01*
X608250Y228567D01*
X608500Y228400D01*
X608833Y228317D01*
X609125Y228400D01*
X609417Y228608D01*
X609583Y228858D01*
X609625Y229150D01*
X609542Y229483D01*
X609333Y229733D01*
X608958Y229983D01*
G01X615208Y230267D02*
X615083Y230017D01*
X615000Y229725D01*
Y229392D01*
X615125Y229017D01*
X615333Y228725D01*
X615583Y228517D01*
X616000Y228350D01*
X616375Y228308D01*
X616750Y228392D01*
X617000Y228517D01*
X617250Y228767D01*
X617417Y229058D01*
X617500Y229350D01*
Y229642D01*
X617417Y229933D01*
X617292Y230183D01*
X617125Y230392D01*
G01X617000Y231533D02*
X617292Y231783D01*
X617458Y232117D01*
X617500Y232492D01*
X617458Y232825D01*
X617250Y233158D01*
X617000Y233367D01*
X616750Y233408D01*
X616458Y233325D01*
X616250Y233033D01*
X616167Y232742D01*
Y232367D01*
G01Y232742D02*
X616042Y232992D01*
X615833Y233200D01*
X615583Y233283D01*
X615333Y233200D01*
X615125Y232992D01*
X615000Y232617D01*
X615042Y232242D01*
X615208Y231867D01*
G01X615417Y234758D02*
X615167Y235008D01*
X615042Y235300D01*
X615000Y235633D01*
X615083Y236050D01*
X615292Y236342D01*
X615542Y236425D01*
X615792Y236383D01*
X616000Y236217D01*
X616417Y235383D01*
X616708Y235008D01*
X617125Y234758D01*
X617500Y234675D01*
Y236425D01*
G01Y238650D02*
X617458Y238942D01*
X617333Y239275D01*
X617125Y239483D01*
X616833Y239567D01*
X616542Y239483D01*
X616292Y239233D01*
X616167Y238858D01*
Y238442D01*
X616083Y238192D01*
X615875Y237983D01*
X615583Y237900D01*
X615292Y238025D01*
X615083Y238317D01*
X615000Y238650D01*
X615083Y238983D01*
X615292Y239275D01*
X615583Y239400D01*
X615875Y239317D01*
X616083Y239108D01*
X616167Y238858D01*
Y238442D01*
X616292Y238067D01*
X616542Y237817D01*
X616833Y237733D01*
X617125Y237817D01*
X617333Y238025D01*
X617458Y238358D01*
X617500Y238650D01*
G01X604208Y221817D02*
X604083Y221567D01*
X604000Y221275D01*
Y220942D01*
X604125Y220567D01*
X604333Y220275D01*
X604583Y220067D01*
X605000Y219900D01*
X605375Y219858D01*
X605750Y219942D01*
X606000Y220067D01*
X606250Y220317D01*
X606417Y220608D01*
X606500Y220900D01*
Y221192D01*
X606417Y221483D01*
X606292Y221733D01*
X606125Y221942D01*
G01X606208Y223292D02*
X606417Y223583D01*
X606500Y223917D01*
X606417Y224250D01*
X606167Y224542D01*
X605792Y224750D01*
X605417Y224833D01*
X604958D01*
X604583Y224750D01*
X604250Y224542D01*
X604083Y224292D01*
X604000Y224000D01*
X604083Y223667D01*
X604250Y223417D01*
X604500Y223250D01*
X604833Y223167D01*
X605125Y223250D01*
X605417Y223458D01*
X605583Y223708D01*
X605625Y224000D01*
X605542Y224333D01*
X605333Y224583D01*
X604958Y224833D01*
G01X606500Y227017D02*
X605958Y227100D01*
X605500Y227225D01*
X605083Y227392D01*
X604625Y227600D01*
X604000Y227933D01*
Y226267D01*
G01X625708Y59274D02*
X625583Y59024D01*
X625500Y58732D01*
Y58399D01*
X625625Y58024D01*
X625833Y57732D01*
X626083Y57524D01*
X626500Y57357D01*
X626875Y57315D01*
X627250Y57399D01*
X627500Y57524D01*
X627750Y57774D01*
X627917Y58065D01*
X628000Y58357D01*
Y58649D01*
X627917Y58940D01*
X627792Y59190D01*
X627625Y59399D01*
G01X627500Y60540D02*
X627792Y60790D01*
X627958Y61124D01*
X628000Y61499D01*
X627958Y61832D01*
X627750Y62165D01*
X627500Y62374D01*
X627250Y62415D01*
X626958Y62332D01*
X626750Y62040D01*
X626667Y61749D01*
Y61374D01*
G01Y61749D02*
X626542Y61999D01*
X626333Y62207D01*
X626083Y62290D01*
X625833Y62207D01*
X625625Y61999D01*
X625500Y61624D01*
X625542Y61249D01*
X625708Y60874D01*
G01X628000Y64474D02*
X627458Y64557D01*
X627000Y64682D01*
X626583Y64849D01*
X626125Y65057D01*
X625500Y65390D01*
Y63724D01*
G01Y67657D02*
X625583Y67324D01*
X625792Y67074D01*
X626042Y66907D01*
X626375Y66782D01*
X626750Y66740D01*
X627125Y66782D01*
X627458Y66907D01*
X627708Y67074D01*
X627917Y67324D01*
X628000Y67657D01*
X627917Y67990D01*
X627708Y68240D01*
X627458Y68407D01*
X627125Y68532D01*
X626750Y68574D01*
X626375Y68532D01*
X626042Y68407D01*
X625792Y68240D01*
X625583Y67990D01*
X625500Y67657D01*
G01X630208Y56774D02*
X630083Y56524D01*
X630000Y56232D01*
Y55899D01*
X630125Y55524D01*
X630333Y55232D01*
X630583Y55024D01*
X631000Y54857D01*
X631375Y54815D01*
X631750Y54899D01*
X632000Y55024D01*
X632250Y55274D01*
X632417Y55565D01*
X632500Y55857D01*
Y56149D01*
X632417Y56440D01*
X632292Y56690D01*
X632125Y56899D01*
G01X632000Y58040D02*
X632292Y58290D01*
X632458Y58624D01*
X632500Y58999D01*
X632458Y59332D01*
X632250Y59665D01*
X632000Y59874D01*
X631750Y59915D01*
X631458Y59832D01*
X631250Y59540D01*
X631167Y59249D01*
Y58874D01*
G01Y59249D02*
X631042Y59499D01*
X630833Y59707D01*
X630583Y59790D01*
X630333Y59707D01*
X630125Y59499D01*
X630000Y59124D01*
X630042Y58749D01*
X630208Y58374D01*
G01X632500Y62557D02*
X630000D01*
X631792Y61015D01*
Y63099D01*
G01X632500Y65657D02*
X630000D01*
X631792Y64115D01*
Y66199D01*
G01X631500Y91500D02*
Y89500D01*
G01Y93500D02*
X634000Y107500D01*
G01X632500Y92500D02*
G03I-1000J0D01*
G01X631500Y109500D02*
Y111500D01*
G01X632500Y108500D02*
G03I-1000J0D01*
G01X633017Y148500D02*
Y146000D01*
X634683D01*
G01X637783D02*
X636117D01*
Y148500D01*
X637783D01*
G01X637117Y147292D02*
X636117D01*
G01X639133Y146000D02*
Y148500D01*
X639967D01*
X640300Y148375D01*
X640550Y148208D01*
X640758Y147958D01*
X640925Y147667D01*
X640967Y147250D01*
X640925Y146833D01*
X640758Y146542D01*
X640550Y146292D01*
X640300Y146125D01*
X639967Y146000D01*
X639133D01*
G01X642233Y146500D02*
X642483Y146208D01*
X642817Y146042D01*
X643192Y146000D01*
X643525Y146042D01*
X643858Y146250D01*
X644067Y146500D01*
X644108Y146750D01*
X644025Y147042D01*
X643733Y147250D01*
X643442Y147333D01*
X643067D01*
G01X643442D02*
X643692Y147458D01*
X643900Y147667D01*
X643983Y147917D01*
X643900Y148167D01*
X643692Y148375D01*
X643317Y148500D01*
X642942Y148458D01*
X642567Y148292D01*
G01X633017Y142000D02*
Y144500D01*
X634058D01*
X634392Y144375D01*
X634600Y144208D01*
X634683Y143875D01*
X634600Y143542D01*
X634350Y143333D01*
X634058Y143208D01*
X633017D01*
G01X634058D02*
X634683Y142000D01*
G01X636950D02*
Y144500D01*
X636450Y144000D01*
G01Y142000D02*
X637450D01*
G01X639133Y142500D02*
X639383Y142208D01*
X639717Y142042D01*
X640092Y142000D01*
X640425Y142042D01*
X640758Y142250D01*
X640967Y142500D01*
X641008Y142750D01*
X640925Y143042D01*
X640633Y143250D01*
X640342Y143333D01*
X639967D01*
G01X640342D02*
X640592Y143458D01*
X640800Y143667D01*
X640883Y143917D01*
X640800Y144167D01*
X640592Y144375D01*
X640217Y144500D01*
X639842Y144458D01*
X639467Y144292D01*
G01X643150Y142000D02*
Y144500D01*
X642650Y144000D01*
G01Y142000D02*
X643650D01*
G01X631000Y140517D02*
X628500D01*
Y141558D01*
X628625Y141892D01*
X628792Y142100D01*
X629125Y142183D01*
X629458Y142100D01*
X629667Y141850D01*
X629792Y141558D01*
Y140517D01*
G01Y141558D02*
X631000Y142183D01*
G01X628917Y143658D02*
X628667Y143908D01*
X628542Y144200D01*
X628500Y144533D01*
X628583Y144950D01*
X628792Y145242D01*
X629042Y145325D01*
X629292Y145283D01*
X629500Y145117D01*
X629917Y144283D01*
X630208Y143908D01*
X630625Y143658D01*
X631000Y143575D01*
Y145325D01*
G01Y147550D02*
X628500D01*
X629000Y147050D01*
G01X631000D02*
Y148050D01*
G01X629958Y149858D02*
X629667Y150150D01*
X629500Y150400D01*
X629417Y150733D01*
X629500Y151025D01*
X629667Y151233D01*
X629917Y151400D01*
X630208Y151442D01*
X630458Y151400D01*
X630708Y151233D01*
X630917Y150983D01*
X631000Y150692D01*
X630917Y150358D01*
X630667Y150067D01*
X630292Y149900D01*
X629875Y149858D01*
X629333Y149942D01*
X629042Y150067D01*
X628750Y150275D01*
X628542Y150567D01*
X628500Y150858D01*
X628583Y151150D01*
X628792Y151358D01*
G01X630000Y161017D02*
X627500D01*
Y162058D01*
X627625Y162392D01*
X627792Y162600D01*
X628125Y162683D01*
X628458Y162600D01*
X628667Y162350D01*
X628792Y162058D01*
Y161017D01*
G01Y162058D02*
X630000Y162683D01*
G01X627917Y164158D02*
X627667Y164408D01*
X627542Y164700D01*
X627500Y165033D01*
X627583Y165450D01*
X627792Y165742D01*
X628042Y165825D01*
X628292Y165783D01*
X628500Y165617D01*
X628917Y164783D01*
X629208Y164408D01*
X629625Y164158D01*
X630000Y164075D01*
Y165825D01*
G01Y168050D02*
X627500D01*
X628000Y167550D01*
G01X630000D02*
Y168550D01*
G01X629625Y170233D02*
X629833Y170483D01*
X629958Y170775D01*
X630000Y171150D01*
X629917Y171525D01*
X629750Y171817D01*
X629458Y172025D01*
X629125Y172067D01*
X628792Y171983D01*
X628583Y171775D01*
X628417Y171483D01*
X628375Y171192D01*
X628417Y170900D01*
X628583Y170525D01*
X627500Y170650D01*
Y171775D01*
G01X622500Y165517D02*
X620000D01*
Y166558D01*
X620125Y166892D01*
X620292Y167100D01*
X620625Y167183D01*
X620958Y167100D01*
X621167Y166850D01*
X621292Y166558D01*
Y165517D01*
G01Y166558D02*
X622500Y167183D01*
G01X620417Y168658D02*
X620167Y168908D01*
X620042Y169200D01*
X620000Y169533D01*
X620083Y169950D01*
X620292Y170242D01*
X620542Y170325D01*
X620792Y170283D01*
X621000Y170117D01*
X621417Y169283D01*
X621708Y168908D01*
X622125Y168658D01*
X622500Y168575D01*
Y170325D01*
G01Y172550D02*
X620000D01*
X620500Y172050D01*
G01X622500D02*
Y173050D01*
G01Y176150D02*
X620000D01*
X621792Y174608D01*
Y176692D01*
G01X632000Y171483D02*
X633792D01*
X634167Y171650D01*
X634417Y171983D01*
X634500Y172400D01*
X634417Y172817D01*
X634167Y173150D01*
X633792Y173317D01*
X632000D01*
G01X632417Y174708D02*
X632167Y174958D01*
X632042Y175250D01*
X632000Y175583D01*
X632083Y176000D01*
X632292Y176292D01*
X632542Y176375D01*
X632792Y176333D01*
X633000Y176167D01*
X633417Y175333D01*
X633708Y174958D01*
X634125Y174708D01*
X634500Y174625D01*
Y176375D01*
G01X634125Y177683D02*
X634333Y177933D01*
X634458Y178225D01*
X634500Y178600D01*
X634417Y178975D01*
X634250Y179267D01*
X633958Y179475D01*
X633625Y179517D01*
X633292Y179433D01*
X633083Y179225D01*
X632917Y178933D01*
X632875Y178642D01*
X632917Y178350D01*
X633083Y177975D01*
X632000Y178100D01*
Y179225D01*
G01X624017Y196500D02*
Y199000D01*
X625058D01*
X625392Y198875D01*
X625600Y198708D01*
X625683Y198375D01*
X625600Y198042D01*
X625350Y197833D01*
X625058Y197708D01*
X624017D01*
G01X625058D02*
X625683Y196500D01*
G01X627158Y198583D02*
X627408Y198833D01*
X627700Y198958D01*
X628033Y199000D01*
X628450Y198917D01*
X628742Y198708D01*
X628825Y198458D01*
X628783Y198208D01*
X628617Y198000D01*
X627783Y197583D01*
X627408Y197292D01*
X627158Y196875D01*
X627075Y196500D01*
X628825D01*
G01X631050Y199000D02*
X630717Y198917D01*
X630467Y198708D01*
X630300Y198458D01*
X630175Y198125D01*
X630133Y197750D01*
X630175Y197375D01*
X630300Y197042D01*
X630467Y196792D01*
X630717Y196583D01*
X631050Y196500D01*
X631383Y196583D01*
X631633Y196792D01*
X631800Y197042D01*
X631925Y197375D01*
X631967Y197750D01*
X631925Y198125D01*
X631800Y198458D01*
X631633Y198708D01*
X631383Y198917D01*
X631050Y199000D01*
G01X633233Y196875D02*
X633483Y196667D01*
X633775Y196542D01*
X634150Y196500D01*
X634525Y196583D01*
X634817Y196750D01*
X635025Y197042D01*
X635067Y197375D01*
X634983Y197708D01*
X634775Y197917D01*
X634483Y198083D01*
X634192Y198125D01*
X633900Y198083D01*
X633525Y197917D01*
X633650Y199000D01*
X634775D01*
G01X631983Y203000D02*
Y201208D01*
X632150Y200833D01*
X632483Y200583D01*
X632900Y200500D01*
X633317Y200583D01*
X633650Y200833D01*
X633817Y201208D01*
Y203000D01*
G01X636000Y200500D02*
Y203000D01*
X635500Y202500D01*
G01Y200500D02*
X636500D01*
G01X639017D02*
X639100Y201042D01*
X639225Y201500D01*
X639392Y201917D01*
X639600Y202375D01*
X639933Y203000D01*
X638267D01*
G01X622200Y206650D02*
Y203650D01*
X625200D01*
G01X622708Y230767D02*
X622583Y230517D01*
X622500Y230225D01*
Y229892D01*
X622625Y229517D01*
X622833Y229225D01*
X623083Y229017D01*
X623500Y228850D01*
X623875Y228808D01*
X624250Y228892D01*
X624500Y229017D01*
X624750Y229267D01*
X624917Y229558D01*
X625000Y229850D01*
Y230142D01*
X624917Y230433D01*
X624792Y230683D01*
X624625Y230892D01*
G01X624500Y232033D02*
X624792Y232283D01*
X624958Y232617D01*
X625000Y232992D01*
X624958Y233325D01*
X624750Y233658D01*
X624500Y233867D01*
X624250Y233908D01*
X623958Y233825D01*
X623750Y233533D01*
X623667Y233242D01*
Y232867D01*
G01Y233242D02*
X623542Y233492D01*
X623333Y233700D01*
X623083Y233783D01*
X622833Y233700D01*
X622625Y233492D01*
X622500Y233117D01*
X622542Y232742D01*
X622708Y232367D01*
G01X622917Y235258D02*
X622667Y235508D01*
X622542Y235800D01*
X622500Y236133D01*
X622583Y236550D01*
X622792Y236842D01*
X623042Y236925D01*
X623292Y236883D01*
X623500Y236717D01*
X623917Y235883D01*
X624208Y235508D01*
X624625Y235258D01*
X625000Y235175D01*
Y236925D01*
G01Y239067D02*
X624458Y239150D01*
X624000Y239275D01*
X623583Y239442D01*
X623125Y239650D01*
X622500Y239983D01*
Y238317D01*
G01X625200Y227350D02*
X622200D01*
Y224350D01*
G01X623289Y223000D02*
X621289D01*
G01X634208Y56774D02*
X634083Y56524D01*
X634000Y56232D01*
Y55899D01*
X634125Y55524D01*
X634333Y55232D01*
X634583Y55024D01*
X635000Y54857D01*
X635375Y54815D01*
X635750Y54899D01*
X636000Y55024D01*
X636250Y55274D01*
X636417Y55565D01*
X636500Y55857D01*
Y56149D01*
X636417Y56440D01*
X636292Y56690D01*
X636125Y56899D01*
G01X636000Y58040D02*
X636292Y58290D01*
X636458Y58624D01*
X636500Y58999D01*
X636458Y59332D01*
X636250Y59665D01*
X636000Y59874D01*
X635750Y59915D01*
X635458Y59832D01*
X635250Y59540D01*
X635167Y59249D01*
Y58874D01*
G01Y59249D02*
X635042Y59499D01*
X634833Y59707D01*
X634583Y59790D01*
X634333Y59707D01*
X634125Y59499D01*
X634000Y59124D01*
X634042Y58749D01*
X634208Y58374D01*
G01X636500Y62557D02*
X634000D01*
X635792Y61015D01*
Y63099D01*
G01X636000Y64240D02*
X636292Y64490D01*
X636458Y64824D01*
X636500Y65199D01*
X636458Y65532D01*
X636250Y65865D01*
X636000Y66074D01*
X635750Y66115D01*
X635458Y66032D01*
X635250Y65740D01*
X635167Y65449D01*
Y65074D01*
G01Y65449D02*
X635042Y65699D01*
X634833Y65907D01*
X634583Y65990D01*
X634333Y65907D01*
X634125Y65699D01*
X634000Y65324D01*
X634042Y64949D01*
X634208Y64574D01*
G01X639208Y47274D02*
X639083Y47024D01*
X639000Y46732D01*
Y46399D01*
X639125Y46024D01*
X639333Y45732D01*
X639583Y45524D01*
X640000Y45357D01*
X640375Y45315D01*
X640750Y45399D01*
X641000Y45524D01*
X641250Y45774D01*
X641417Y46065D01*
X641500Y46357D01*
Y46649D01*
X641417Y46940D01*
X641292Y47190D01*
X641125Y47399D01*
G01X641000Y48540D02*
X641292Y48790D01*
X641458Y49124D01*
X641500Y49499D01*
X641458Y49832D01*
X641250Y50165D01*
X641000Y50374D01*
X640750Y50415D01*
X640458Y50332D01*
X640250Y50040D01*
X640167Y49749D01*
Y49374D01*
G01Y49749D02*
X640042Y49999D01*
X639833Y50207D01*
X639583Y50290D01*
X639333Y50207D01*
X639125Y49999D01*
X639000Y49624D01*
X639042Y49249D01*
X639208Y48874D01*
G01X641500Y53057D02*
X639000D01*
X640792Y51515D01*
Y53599D01*
G01X639417Y54865D02*
X639167Y55115D01*
X639042Y55407D01*
X639000Y55740D01*
X639083Y56157D01*
X639292Y56449D01*
X639542Y56532D01*
X639792Y56490D01*
X640000Y56324D01*
X640417Y55490D01*
X640708Y55115D01*
X641125Y54865D01*
X641500Y54782D01*
Y56532D01*
G01X645767Y56799D02*
X645517Y56924D01*
X645225Y57007D01*
X644892D01*
X644517Y56882D01*
X644225Y56674D01*
X644017Y56424D01*
X643850Y56007D01*
X643808Y55632D01*
X643892Y55257D01*
X644017Y55007D01*
X644267Y54757D01*
X644558Y54590D01*
X644850Y54507D01*
X645142D01*
X645433Y54590D01*
X645683Y54715D01*
X645892Y54882D01*
G01X647033Y55007D02*
X647283Y54715D01*
X647617Y54549D01*
X647992Y54507D01*
X648325Y54549D01*
X648658Y54757D01*
X648867Y55007D01*
X648908Y55257D01*
X648825Y55549D01*
X648533Y55757D01*
X648242Y55840D01*
X647867D01*
G01X648242D02*
X648492Y55965D01*
X648700Y56174D01*
X648783Y56424D01*
X648700Y56674D01*
X648492Y56882D01*
X648117Y57007D01*
X647742Y56965D01*
X647367Y56799D01*
G01X651550Y54507D02*
Y57007D01*
X650008Y55215D01*
X652092D01*
G01X654150Y54507D02*
Y57007D01*
X653650Y56507D01*
G01Y54507D02*
X654650D01*
G01X642000Y62458D02*
X639500D01*
Y64042D01*
G01X640708Y63458D02*
Y62458D01*
G01X642000Y65517D02*
X639500D01*
Y66517D01*
X639625Y66850D01*
X639917Y67100D01*
X640250Y67183D01*
X640583Y67100D01*
X640833Y66892D01*
X640958Y66517D01*
Y65517D01*
G01X640750Y69700D02*
Y70533D01*
X641500D01*
X641750Y70283D01*
X641917Y69992D01*
X642000Y69575D01*
X641917Y69158D01*
X641750Y68867D01*
X641500Y68617D01*
X641208Y68450D01*
X640875Y68367D01*
X640583D01*
X640333Y68450D01*
X640042Y68617D01*
X639792Y68867D01*
X639625Y69117D01*
X639500Y69450D01*
Y69742D01*
X639583Y70075D01*
X639750Y70325D01*
G01X642000Y71508D02*
X639500Y72550D01*
X642000Y73592D01*
G01X641125Y73217D02*
Y71883D01*
G01X639500Y79500D02*
X642000D01*
G01X641625D02*
X641833Y79333D01*
X641958Y79083D01*
X642000Y78792D01*
X641917Y78458D01*
X641708Y78208D01*
X641458Y78042D01*
X641167Y78000D01*
X640875Y78042D01*
X640625Y78208D01*
X640417Y78458D01*
X640333Y78792D01*
X640375Y79083D01*
X640458Y79292D01*
X640625Y79500D01*
G01X640333Y81850D02*
X642000D01*
G01X639667D02*
X639625Y81767D01*
X639542D01*
X639500Y81850D01*
X639542Y81933D01*
X639625D01*
X639667Y81850D01*
G01X641708Y84325D02*
X641875Y84533D01*
X642000Y84825D01*
Y85075D01*
X641917Y85325D01*
X641792Y85492D01*
X641625Y85575D01*
X641375Y85533D01*
X641250Y85367D01*
X641000Y84617D01*
X640708Y84450D01*
X640500Y84533D01*
X640375Y84700D01*
X640333Y84950D01*
X640375Y85200D01*
X640500Y85450D01*
G01X642000Y88800D02*
X640333D01*
G01X640625D02*
X640458Y88633D01*
X640375Y88383D01*
X640333Y88092D01*
X640417Y87800D01*
X640583Y87550D01*
X640833Y87383D01*
X641167Y87300D01*
X641500Y87383D01*
X641750Y87550D01*
X641917Y87800D01*
X642000Y88092D01*
X641958Y88383D01*
X641833Y88633D01*
X641667Y88800D01*
G01X642000Y90400D02*
X639500D01*
G01X640750D02*
X640500Y90608D01*
X640375Y90858D01*
X640333Y91108D01*
X640417Y91483D01*
X640583Y91733D01*
X640875Y91900D01*
X641208D01*
X641542Y91817D01*
X641792Y91650D01*
X641958Y91358D01*
X642000Y91108D01*
X641958Y90858D01*
X641833Y90608D01*
X641625Y90400D01*
G01X642000Y94250D02*
X639500D01*
G01X640875Y96725D02*
Y98058D01*
X640583Y97933D01*
X640417Y97725D01*
X640333Y97433D01*
X640375Y97142D01*
X640500Y96892D01*
X640792Y96725D01*
X641042Y96642D01*
X641292D01*
X641542Y96725D01*
X641792Y96933D01*
X641958Y97183D01*
X642000Y97475D01*
X641917Y97767D01*
X641667Y98058D01*
G01X648500Y63250D02*
X648458Y62917D01*
X648292Y62625D01*
X648042Y62375D01*
X647750Y62208D01*
X647417Y62125D01*
X647083D01*
X646750Y62208D01*
X646458Y62375D01*
X646208Y62625D01*
X646042Y62917D01*
X646000Y63250D01*
X646042Y63583D01*
X646208Y63875D01*
X646458Y64125D01*
X646750Y64292D01*
X647083Y64375D01*
X647417D01*
X647750Y64292D01*
X648042Y64125D01*
X648292Y63875D01*
X648458Y63583D01*
X648500Y63250D01*
G01Y65642D02*
X646833D01*
G01X647250D02*
X647042Y65808D01*
X646875Y66058D01*
X646833Y66392D01*
X646875Y66683D01*
X647042Y66933D01*
X647333Y67058D01*
X648500D01*
G01X648583Y69450D02*
X648542Y69367D01*
X648458D01*
X648417Y69450D01*
X648458Y69533D01*
X648542D01*
X648583Y69450D01*
G01X647458D02*
X647417Y69367D01*
X647333D01*
X647292Y69450D01*
X647333Y69533D01*
X647417D01*
X647458Y69450D01*
G01X648500Y74733D02*
X646000D01*
Y75567D01*
X646125Y75900D01*
X646292Y76150D01*
X646542Y76358D01*
X646833Y76525D01*
X647250Y76567D01*
X647667Y76525D01*
X647958Y76358D01*
X648208Y76150D01*
X648375Y75900D01*
X648500Y75567D01*
Y74733D01*
G01X646833Y78750D02*
X648500D01*
G01X646167D02*
X646125Y78667D01*
X646042D01*
X646000Y78750D01*
X646042Y78833D01*
X646125D01*
X646167Y78750D01*
G01X648208Y81225D02*
X648375Y81433D01*
X648500Y81725D01*
Y81975D01*
X648417Y82225D01*
X648292Y82392D01*
X648125Y82475D01*
X647875Y82433D01*
X647750Y82267D01*
X647500Y81517D01*
X647208Y81350D01*
X647000Y81433D01*
X646875Y81600D01*
X646833Y81850D01*
X646875Y82100D01*
X647000Y82350D01*
G01X648500Y85700D02*
X646833D01*
G01X647125D02*
X646958Y85533D01*
X646875Y85283D01*
X646833Y84992D01*
X646917Y84700D01*
X647083Y84450D01*
X647333Y84283D01*
X647667Y84200D01*
X648000Y84283D01*
X648250Y84450D01*
X648417Y84700D01*
X648500Y84992D01*
X648458Y85283D01*
X648333Y85533D01*
X648167Y85700D01*
G01X648500Y87300D02*
X646000D01*
G01X647250D02*
X647000Y87508D01*
X646875Y87758D01*
X646833Y88008D01*
X646917Y88383D01*
X647083Y88633D01*
X647375Y88800D01*
X647708D01*
X648042Y88717D01*
X648292Y88550D01*
X648458Y88258D01*
X648500Y88008D01*
X648458Y87758D01*
X648333Y87508D01*
X648125Y87300D01*
G01X648500Y91150D02*
X646000D01*
G01X647375Y93625D02*
Y94958D01*
X647083Y94833D01*
X646917Y94625D01*
X646833Y94333D01*
X646875Y94042D01*
X647000Y93792D01*
X647292Y93625D01*
X647542Y93542D01*
X647792D01*
X648042Y93625D01*
X648292Y93833D01*
X648458Y94083D01*
X648500Y94375D01*
X648417Y94667D01*
X648167Y94958D01*
G01X643408Y102167D02*
X643283Y101917D01*
X643200Y101625D01*
Y101292D01*
X643325Y100917D01*
X643533Y100625D01*
X643783Y100417D01*
X644200Y100250D01*
X644575Y100208D01*
X644950Y100292D01*
X645200Y100417D01*
X645450Y100667D01*
X645617Y100958D01*
X645700Y101250D01*
Y101542D01*
X645617Y101833D01*
X645492Y102083D01*
X645325Y102292D01*
G01X643617Y103558D02*
X643367Y103808D01*
X643242Y104100D01*
X643200Y104433D01*
X643283Y104850D01*
X643492Y105142D01*
X643742Y105225D01*
X643992Y105183D01*
X644200Y105017D01*
X644617Y104183D01*
X644908Y103808D01*
X645325Y103558D01*
X645700Y103475D01*
Y105225D01*
G01X645200Y106533D02*
X645492Y106783D01*
X645658Y107117D01*
X645700Y107492D01*
X645658Y107825D01*
X645450Y108158D01*
X645200Y108367D01*
X644950Y108408D01*
X644658Y108325D01*
X644450Y108033D01*
X644367Y107742D01*
Y107367D01*
G01Y107742D02*
X644242Y107992D01*
X644033Y108200D01*
X643783Y108283D01*
X643533Y108200D01*
X643325Y107992D01*
X643200Y107617D01*
X643242Y107242D01*
X643408Y106867D01*
G01X644658Y109758D02*
X644367Y110050D01*
X644200Y110300D01*
X644117Y110633D01*
X644200Y110925D01*
X644367Y111133D01*
X644617Y111300D01*
X644908Y111342D01*
X645158Y111300D01*
X645408Y111133D01*
X645617Y110883D01*
X645700Y110592D01*
X645617Y110258D01*
X645367Y109967D01*
X644992Y109800D01*
X644575Y109758D01*
X644033Y109842D01*
X643742Y109967D01*
X643450Y110175D01*
X643242Y110467D01*
X643200Y110758D01*
X643283Y111050D01*
X643492Y111258D01*
G01X639208Y101867D02*
X639083Y101617D01*
X639000Y101325D01*
Y100992D01*
X639125Y100617D01*
X639333Y100325D01*
X639583Y100117D01*
X640000Y99950D01*
X640375Y99908D01*
X640750Y99992D01*
X641000Y100117D01*
X641250Y100367D01*
X641417Y100658D01*
X641500Y100950D01*
Y101242D01*
X641417Y101533D01*
X641292Y101783D01*
X641125Y101992D01*
G01X639417Y103258D02*
X639167Y103508D01*
X639042Y103800D01*
X639000Y104133D01*
X639083Y104550D01*
X639292Y104842D01*
X639542Y104925D01*
X639792Y104883D01*
X640000Y104717D01*
X640417Y103883D01*
X640708Y103508D01*
X641125Y103258D01*
X641500Y103175D01*
Y104925D01*
G01X641000Y106233D02*
X641292Y106483D01*
X641458Y106817D01*
X641500Y107192D01*
X641458Y107525D01*
X641250Y107858D01*
X641000Y108067D01*
X640750Y108108D01*
X640458Y108025D01*
X640250Y107733D01*
X640167Y107442D01*
Y107067D01*
G01Y107442D02*
X640042Y107692D01*
X639833Y107900D01*
X639583Y107983D01*
X639333Y107900D01*
X639125Y107692D01*
X639000Y107317D01*
X639042Y106942D01*
X639208Y106567D01*
G01X641125Y109333D02*
X641333Y109583D01*
X641458Y109875D01*
X641500Y110250D01*
X641417Y110625D01*
X641250Y110917D01*
X640958Y111125D01*
X640625Y111167D01*
X640292Y111083D01*
X640083Y110875D01*
X639917Y110583D01*
X639875Y110292D01*
X639917Y110000D01*
X640083Y109625D01*
X639000Y109750D01*
Y110875D01*
G01X641500Y113117D02*
X639000D01*
Y114158D01*
X639125Y114492D01*
X639292Y114700D01*
X639625Y114783D01*
X639958Y114700D01*
X640167Y114450D01*
X640292Y114158D01*
Y113117D01*
G01Y114158D02*
X641500Y114783D01*
G01Y117050D02*
X639000D01*
X639500Y116550D01*
G01X641500D02*
Y117550D01*
G01Y120650D02*
X639000D01*
X640792Y119108D01*
Y121192D01*
G01X639000Y123250D02*
X639083Y122917D01*
X639292Y122667D01*
X639542Y122500D01*
X639875Y122375D01*
X640250Y122333D01*
X640625Y122375D01*
X640958Y122500D01*
X641208Y122667D01*
X641417Y122917D01*
X641500Y123250D01*
X641417Y123583D01*
X641208Y123833D01*
X640958Y124000D01*
X640625Y124125D01*
X640250Y124167D01*
X639875Y124125D01*
X639542Y124000D01*
X639292Y123833D01*
X639083Y123583D01*
X639000Y123250D01*
G01X645700Y113317D02*
X643200D01*
Y114358D01*
X643325Y114692D01*
X643492Y114900D01*
X643825Y114983D01*
X644158Y114900D01*
X644367Y114650D01*
X644492Y114358D01*
Y113317D01*
G01Y114358D02*
X645700Y114983D01*
G01Y117250D02*
X643200D01*
X643700Y116750D01*
G01X645700D02*
Y117750D01*
G01Y120850D02*
X643200D01*
X644992Y119308D01*
Y121392D01*
G01X645700Y123450D02*
X643200D01*
X643700Y122950D01*
G01X645700D02*
Y123950D01*
G01X650000Y110917D02*
X647500D01*
Y111958D01*
X647625Y112292D01*
X647792Y112500D01*
X648125Y112583D01*
X648458Y112500D01*
X648667Y112250D01*
X648792Y111958D01*
Y110917D01*
G01Y111958D02*
X650000Y112583D01*
G01Y114850D02*
X647500D01*
X648000Y114350D01*
G01X650000D02*
Y115350D01*
G01Y118450D02*
X647500D01*
X649292Y116908D01*
Y118992D01*
G01X650000Y120967D02*
X649458Y121050D01*
X649000Y121175D01*
X648583Y121342D01*
X648125Y121550D01*
X647500Y121883D01*
Y120217D01*
G01X641517Y133500D02*
Y136000D01*
X642517D01*
X642850Y135875D01*
X643100Y135583D01*
X643183Y135250D01*
X643100Y134917D01*
X642892Y134667D01*
X642517Y134542D01*
X641517D01*
G01X646367Y135792D02*
X646117Y135917D01*
X645825Y136000D01*
X645492D01*
X645117Y135875D01*
X644825Y135667D01*
X644617Y135417D01*
X644450Y135000D01*
X644408Y134625D01*
X644492Y134250D01*
X644617Y134000D01*
X644867Y133750D01*
X645158Y133583D01*
X645450Y133500D01*
X645742D01*
X646033Y133583D01*
X646283Y133708D01*
X646492Y133875D01*
G01X648550Y133500D02*
X648842Y133542D01*
X649175Y133667D01*
X649383Y133875D01*
X649467Y134167D01*
X649383Y134458D01*
X649133Y134708D01*
X648758Y134833D01*
X648342D01*
X648092Y134917D01*
X647883Y135125D01*
X647800Y135417D01*
X647925Y135708D01*
X648217Y135917D01*
X648550Y136000D01*
X648883Y135917D01*
X649175Y135708D01*
X649300Y135417D01*
X649217Y135125D01*
X649008Y134917D01*
X648758Y134833D01*
X648342D01*
X647967Y134708D01*
X647717Y134458D01*
X647633Y134167D01*
X647717Y133875D01*
X647925Y133667D01*
X648258Y133542D01*
X648550Y133500D01*
G01X650733Y134000D02*
X650983Y133708D01*
X651317Y133542D01*
X651692Y133500D01*
X652025Y133542D01*
X652358Y133750D01*
X652567Y134000D01*
X652608Y134250D01*
X652525Y134542D01*
X652233Y134750D01*
X651942Y134833D01*
X651567D01*
G01X651942D02*
X652192Y134958D01*
X652400Y135167D01*
X652483Y135417D01*
X652400Y135667D01*
X652192Y135875D01*
X651817Y136000D01*
X651442Y135958D01*
X651067Y135792D01*
G01X641517Y129500D02*
Y132000D01*
X642558D01*
X642892Y131875D01*
X643100Y131708D01*
X643183Y131375D01*
X643100Y131042D01*
X642850Y130833D01*
X642558Y130708D01*
X641517D01*
G01X642558D02*
X643183Y129500D01*
G01X645450D02*
Y132000D01*
X644950Y131500D01*
G01Y129500D02*
X645950D01*
G01X647758Y130542D02*
X648050Y130833D01*
X648300Y131000D01*
X648633Y131083D01*
X648925Y131000D01*
X649133Y130833D01*
X649300Y130583D01*
X649342Y130292D01*
X649300Y130042D01*
X649133Y129792D01*
X648883Y129583D01*
X648592Y129500D01*
X648258Y129583D01*
X647967Y129833D01*
X647800Y130208D01*
X647758Y130625D01*
X647842Y131167D01*
X647967Y131458D01*
X648175Y131750D01*
X648467Y131958D01*
X648758Y132000D01*
X649050Y131917D01*
X649258Y131708D01*
G01X652150Y129500D02*
Y132000D01*
X650608Y130208D01*
X652692D01*
G01X639500Y127517D02*
X637000D01*
Y128558D01*
X637125Y128892D01*
X637292Y129100D01*
X637625Y129183D01*
X637958Y129100D01*
X638167Y128850D01*
X638292Y128558D01*
Y127517D01*
G01Y128558D02*
X639500Y129183D01*
G01Y131450D02*
X637000D01*
X637500Y130950D01*
G01X639500D02*
Y131950D01*
G01Y135050D02*
X637000D01*
X638792Y133508D01*
Y135592D01*
G01X639500Y137650D02*
X639458Y137942D01*
X639333Y138275D01*
X639125Y138483D01*
X638833Y138567D01*
X638542Y138483D01*
X638292Y138233D01*
X638167Y137858D01*
Y137442D01*
X638083Y137192D01*
X637875Y136983D01*
X637583Y136900D01*
X637292Y137025D01*
X637083Y137317D01*
X637000Y137650D01*
X637083Y137983D01*
X637292Y138275D01*
X637583Y138400D01*
X637875Y138317D01*
X638083Y138108D01*
X638167Y137858D01*
Y137442D01*
X638292Y137067D01*
X638542Y136817D01*
X638833Y136733D01*
X639125Y136817D01*
X639333Y137025D01*
X639458Y137358D01*
X639500Y137650D01*
G01X641517Y125500D02*
Y128000D01*
X642558D01*
X642892Y127875D01*
X643100Y127708D01*
X643183Y127375D01*
X643100Y127042D01*
X642850Y126833D01*
X642558Y126708D01*
X641517D01*
G01X642558D02*
X643183Y125500D01*
G01X645450D02*
Y128000D01*
X644950Y127500D01*
G01Y125500D02*
X645950D01*
G01X647758Y126542D02*
X648050Y126833D01*
X648300Y127000D01*
X648633Y127083D01*
X648925Y127000D01*
X649133Y126833D01*
X649300Y126583D01*
X649342Y126292D01*
X649300Y126042D01*
X649133Y125792D01*
X648883Y125583D01*
X648592Y125500D01*
X648258Y125583D01*
X647967Y125833D01*
X647800Y126208D01*
X647758Y126625D01*
X647842Y127167D01*
X647967Y127458D01*
X648175Y127750D01*
X648467Y127958D01*
X648758Y128000D01*
X649050Y127917D01*
X649258Y127708D01*
G01X650733Y126000D02*
X650983Y125708D01*
X651317Y125542D01*
X651692Y125500D01*
X652025Y125542D01*
X652358Y125750D01*
X652567Y126000D01*
X652608Y126250D01*
X652525Y126542D01*
X652233Y126750D01*
X651942Y126833D01*
X651567D01*
G01X651942D02*
X652192Y126958D01*
X652400Y127167D01*
X652483Y127417D01*
X652400Y127667D01*
X652192Y127875D01*
X651817Y128000D01*
X651442Y127958D01*
X651067Y127792D01*
G01X641467Y137500D02*
Y140000D01*
X642467D01*
X642800Y139875D01*
X643050Y139583D01*
X643133Y139250D01*
X643050Y138917D01*
X642842Y138667D01*
X642467Y138542D01*
X641467D01*
G01X644567Y137500D02*
Y140000D01*
X645608D01*
X645942Y139875D01*
X646150Y139708D01*
X646233Y139375D01*
X646150Y139042D01*
X645900Y138833D01*
X645608Y138708D01*
X644567D01*
G01X645608D02*
X646233Y137500D01*
G01X648500D02*
Y140000D01*
X648000Y139500D01*
G01Y137500D02*
X649000D01*
G01X651600Y140000D02*
X651267Y139917D01*
X651017Y139708D01*
X650850Y139458D01*
X650725Y139125D01*
X650683Y138750D01*
X650725Y138375D01*
X650850Y138042D01*
X651017Y137792D01*
X651267Y137583D01*
X651600Y137500D01*
X651933Y137583D01*
X652183Y137792D01*
X652350Y138042D01*
X652475Y138375D01*
X652517Y138750D01*
X652475Y139125D01*
X652350Y139458D01*
X652183Y139708D01*
X651933Y139917D01*
X651600Y140000D01*
G01X654617Y137500D02*
X654700Y138042D01*
X654825Y138500D01*
X654992Y138917D01*
X655200Y139375D01*
X655533Y140000D01*
X653867D01*
G01X649000Y143067D02*
X646500D01*
Y144108D01*
X646625Y144442D01*
X646792Y144650D01*
X647125Y144733D01*
X647458Y144650D01*
X647667Y144400D01*
X647792Y144108D01*
Y143067D01*
G01Y144108D02*
X649000Y144733D01*
G01Y146917D02*
X648458Y147000D01*
X648000Y147125D01*
X647583Y147292D01*
X647125Y147500D01*
X646500Y147833D01*
Y146167D01*
G01X648625Y149183D02*
X648833Y149433D01*
X648958Y149725D01*
X649000Y150100D01*
X648917Y150475D01*
X648750Y150767D01*
X648458Y150975D01*
X648125Y151017D01*
X647792Y150933D01*
X647583Y150725D01*
X647417Y150433D01*
X647375Y150142D01*
X647417Y149850D01*
X647583Y149475D01*
X646500Y149600D01*
Y150725D01*
G01X641500Y150017D02*
X639000D01*
Y151058D01*
X639125Y151392D01*
X639292Y151600D01*
X639625Y151683D01*
X639958Y151600D01*
X640167Y151350D01*
X640292Y151058D01*
Y150017D01*
G01Y151058D02*
X641500Y151683D01*
G01X639417Y153158D02*
X639167Y153408D01*
X639042Y153700D01*
X639000Y154033D01*
X639083Y154450D01*
X639292Y154742D01*
X639542Y154825D01*
X639792Y154783D01*
X640000Y154617D01*
X640417Y153783D01*
X640708Y153408D01*
X641125Y153158D01*
X641500Y153075D01*
Y154825D01*
G01Y157050D02*
X639000D01*
X639500Y156550D01*
G01X641500D02*
Y157550D01*
G01X639000Y160150D02*
X639083Y159817D01*
X639292Y159567D01*
X639542Y159400D01*
X639875Y159275D01*
X640250Y159233D01*
X640625Y159275D01*
X640958Y159400D01*
X641208Y159567D01*
X641417Y159817D01*
X641500Y160150D01*
X641417Y160483D01*
X641208Y160733D01*
X640958Y160900D01*
X640625Y161025D01*
X640250Y161067D01*
X639875Y161025D01*
X639542Y160900D01*
X639292Y160733D01*
X639083Y160483D01*
X639000Y160150D01*
G01X645067Y153000D02*
Y155500D01*
X646108D01*
X646442Y155375D01*
X646650Y155208D01*
X646733Y154875D01*
X646650Y154542D01*
X646400Y154333D01*
X646108Y154208D01*
X645067D01*
G01X646108D02*
X646733Y153000D01*
G01X649000D02*
X649292Y153042D01*
X649625Y153167D01*
X649833Y153375D01*
X649917Y153667D01*
X649833Y153958D01*
X649583Y154208D01*
X649208Y154333D01*
X648792D01*
X648542Y154417D01*
X648333Y154625D01*
X648250Y154917D01*
X648375Y155208D01*
X648667Y155417D01*
X649000Y155500D01*
X649333Y155417D01*
X649625Y155208D01*
X649750Y154917D01*
X649667Y154625D01*
X649458Y154417D01*
X649208Y154333D01*
X648792D01*
X648417Y154208D01*
X648167Y153958D01*
X648083Y153667D01*
X648167Y153375D01*
X648375Y153167D01*
X648708Y153042D01*
X649000Y153000D01*
G01X651308Y154042D02*
X651600Y154333D01*
X651850Y154500D01*
X652183Y154583D01*
X652475Y154500D01*
X652683Y154333D01*
X652850Y154083D01*
X652892Y153792D01*
X652850Y153542D01*
X652683Y153292D01*
X652433Y153083D01*
X652142Y153000D01*
X651808Y153083D01*
X651517Y153333D01*
X651350Y153708D01*
X651308Y154125D01*
X651392Y154667D01*
X651517Y154958D01*
X651725Y155250D01*
X652017Y155458D01*
X652308Y155500D01*
X652600Y155417D01*
X652808Y155208D01*
G01X637017Y196500D02*
Y199000D01*
X638058D01*
X638392Y198875D01*
X638600Y198708D01*
X638683Y198375D01*
X638600Y198042D01*
X638350Y197833D01*
X638058Y197708D01*
X637017D01*
G01X638058D02*
X638683Y196500D01*
G01X640158Y198583D02*
X640408Y198833D01*
X640700Y198958D01*
X641033Y199000D01*
X641450Y198917D01*
X641742Y198708D01*
X641825Y198458D01*
X641783Y198208D01*
X641617Y198000D01*
X640783Y197583D01*
X640408Y197292D01*
X640158Y196875D01*
X640075Y196500D01*
X641825D01*
G01X644050Y199000D02*
X643717Y198917D01*
X643467Y198708D01*
X643300Y198458D01*
X643175Y198125D01*
X643133Y197750D01*
X643175Y197375D01*
X643300Y197042D01*
X643467Y196792D01*
X643717Y196583D01*
X644050Y196500D01*
X644383Y196583D01*
X644633Y196792D01*
X644800Y197042D01*
X644925Y197375D01*
X644967Y197750D01*
X644925Y198125D01*
X644800Y198458D01*
X644633Y198708D01*
X644383Y198917D01*
X644050Y199000D01*
G01X647067Y196500D02*
X647150Y197042D01*
X647275Y197500D01*
X647442Y197917D01*
X647650Y198375D01*
X647983Y199000D01*
X646317D01*
G01X657767Y59799D02*
X657517Y59924D01*
X657225Y60007D01*
X656892D01*
X656517Y59882D01*
X656225Y59674D01*
X656017Y59424D01*
X655850Y59007D01*
X655808Y58632D01*
X655892Y58257D01*
X656017Y58007D01*
X656267Y57757D01*
X656558Y57590D01*
X656850Y57507D01*
X657142D01*
X657433Y57590D01*
X657683Y57715D01*
X657892Y57882D01*
G01X659033Y58007D02*
X659283Y57715D01*
X659617Y57549D01*
X659992Y57507D01*
X660325Y57549D01*
X660658Y57757D01*
X660867Y58007D01*
X660908Y58257D01*
X660825Y58549D01*
X660533Y58757D01*
X660242Y58840D01*
X659867D01*
G01X660242D02*
X660492Y58965D01*
X660700Y59174D01*
X660783Y59424D01*
X660700Y59674D01*
X660492Y59882D01*
X660117Y60007D01*
X659742Y59965D01*
X659367Y59799D01*
G01X662967Y57507D02*
X663050Y58049D01*
X663175Y58507D01*
X663342Y58924D01*
X663550Y59382D01*
X663883Y60007D01*
X662217D01*
G01X665358Y59590D02*
X665608Y59840D01*
X665900Y59965D01*
X666233Y60007D01*
X666650Y59924D01*
X666942Y59715D01*
X667025Y59465D01*
X666983Y59215D01*
X666817Y59007D01*
X665983Y58590D01*
X665608Y58299D01*
X665358Y57882D01*
X665275Y57507D01*
X667025D01*
G01X652500Y63250D02*
X652458Y62917D01*
X652292Y62625D01*
X652042Y62375D01*
X651750Y62208D01*
X651417Y62125D01*
X651083D01*
X650750Y62208D01*
X650458Y62375D01*
X650208Y62625D01*
X650042Y62917D01*
X650000Y63250D01*
X650042Y63583D01*
X650208Y63875D01*
X650458Y64125D01*
X650750Y64292D01*
X651083Y64375D01*
X651417D01*
X651750Y64292D01*
X652042Y64125D01*
X652292Y63875D01*
X652458Y63583D01*
X652500Y63250D01*
G01Y66100D02*
X650375D01*
X650167Y66183D01*
X650042Y66350D01*
X650000Y66600D01*
X650083Y66850D01*
X650292Y66975D01*
G01X651000Y66475D02*
Y65642D01*
G01X652500Y69200D02*
X650375D01*
X650167Y69283D01*
X650042Y69450D01*
X650000Y69700D01*
X650083Y69950D01*
X650292Y70075D01*
G01X651000Y69575D02*
Y68742D01*
G01X652583Y72550D02*
X652542Y72467D01*
X652458D01*
X652417Y72550D01*
X652458Y72633D01*
X652542D01*
X652583Y72550D01*
G01X651458D02*
X651417Y72467D01*
X651333D01*
X651292Y72550D01*
X651333Y72633D01*
X651417D01*
X651458Y72550D01*
G01X652500Y79583D02*
Y77917D01*
X650000D01*
Y79583D01*
G01X651208Y78917D02*
Y77917D01*
G01X652500Y81142D02*
X650833D01*
G01X651250D02*
X651042Y81308D01*
X650875Y81558D01*
X650833Y81892D01*
X650875Y82183D01*
X651042Y82433D01*
X651333Y82558D01*
X652500D01*
G01Y85700D02*
X650833D01*
G01X651125D02*
X650958Y85533D01*
X650875Y85283D01*
X650833Y84992D01*
X650917Y84700D01*
X651083Y84450D01*
X651333Y84283D01*
X651667Y84200D01*
X652000Y84283D01*
X652250Y84450D01*
X652417Y84700D01*
X652500Y84992D01*
X652458Y85283D01*
X652333Y85533D01*
X652167Y85700D01*
G01X652500Y87300D02*
X650000D01*
G01X651250D02*
X651000Y87508D01*
X650875Y87758D01*
X650833Y88008D01*
X650917Y88383D01*
X651083Y88633D01*
X651375Y88800D01*
X651708D01*
X652042Y88717D01*
X652292Y88550D01*
X652458Y88258D01*
X652500Y88008D01*
X652458Y87758D01*
X652333Y87508D01*
X652125Y87300D01*
G01X652500Y91150D02*
X650000D01*
G01X651375Y93625D02*
Y94958D01*
X651083Y94833D01*
X650917Y94625D01*
X650833Y94333D01*
X650875Y94042D01*
X651000Y93792D01*
X651292Y93625D01*
X651542Y93542D01*
X651792D01*
X652042Y93625D01*
X652292Y93833D01*
X652458Y94083D01*
X652500Y94375D01*
X652417Y94667D01*
X652167Y94958D01*
G01X656017Y64200D02*
Y66700D01*
X657017D01*
X657350Y66575D01*
X657600Y66283D01*
X657683Y65950D01*
X657600Y65617D01*
X657392Y65367D01*
X657017Y65242D01*
X656017D01*
G01X659117Y64200D02*
Y66700D01*
X660158D01*
X660492Y66575D01*
X660700Y66408D01*
X660783Y66075D01*
X660700Y65742D01*
X660450Y65533D01*
X660158Y65408D01*
X659117D01*
G01X660158D02*
X660783Y64200D01*
G01X663050D02*
Y66700D01*
X662550Y66200D01*
G01Y64200D02*
X663550D01*
G01X666650D02*
Y66700D01*
X665108Y64908D01*
X667192D01*
G01X668458Y65242D02*
X668750Y65533D01*
X669000Y65700D01*
X669333Y65783D01*
X669625Y65700D01*
X669833Y65533D01*
X670000Y65283D01*
X670042Y64992D01*
X670000Y64742D01*
X669833Y64492D01*
X669583Y64283D01*
X669292Y64200D01*
X668958Y64283D01*
X668667Y64533D01*
X668500Y64908D01*
X668458Y65325D01*
X668542Y65867D01*
X668667Y66158D01*
X668875Y66450D01*
X669167Y66658D01*
X669458Y66700D01*
X669750Y66617D01*
X669958Y66408D01*
G01X656017Y72200D02*
Y74700D01*
X657017D01*
X657350Y74575D01*
X657600Y74283D01*
X657683Y73950D01*
X657600Y73617D01*
X657392Y73367D01*
X657017Y73242D01*
X656017D01*
G01X660867Y74492D02*
X660617Y74617D01*
X660325Y74700D01*
X659992D01*
X659617Y74575D01*
X659325Y74367D01*
X659117Y74117D01*
X658950Y73700D01*
X658908Y73325D01*
X658992Y72950D01*
X659117Y72700D01*
X659367Y72450D01*
X659658Y72283D01*
X659950Y72200D01*
X660242D01*
X660533Y72283D01*
X660783Y72408D01*
X660992Y72575D01*
G01X662342Y72492D02*
X662633Y72283D01*
X662967Y72200D01*
X663300Y72283D01*
X663592Y72533D01*
X663800Y72908D01*
X663883Y73283D01*
Y73742D01*
X663800Y74117D01*
X663592Y74450D01*
X663342Y74617D01*
X663050Y74700D01*
X662717Y74617D01*
X662467Y74450D01*
X662300Y74200D01*
X662217Y73867D01*
X662300Y73575D01*
X662508Y73283D01*
X662758Y73117D01*
X663050Y73075D01*
X663383Y73158D01*
X663633Y73367D01*
X663883Y73742D01*
G01X665358Y73242D02*
X665650Y73533D01*
X665900Y73700D01*
X666233Y73783D01*
X666525Y73700D01*
X666733Y73533D01*
X666900Y73283D01*
X666942Y72992D01*
X666900Y72742D01*
X666733Y72492D01*
X666483Y72283D01*
X666192Y72200D01*
X665858Y72283D01*
X665567Y72533D01*
X665400Y72908D01*
X665358Y73325D01*
X665442Y73867D01*
X665567Y74158D01*
X665775Y74450D01*
X666067Y74658D01*
X666358Y74700D01*
X666650Y74617D01*
X666858Y74408D01*
G01X656017Y68200D02*
Y70700D01*
X657017D01*
X657350Y70575D01*
X657600Y70283D01*
X657683Y69950D01*
X657600Y69617D01*
X657392Y69367D01*
X657017Y69242D01*
X656017D01*
G01X660867Y70492D02*
X660617Y70617D01*
X660325Y70700D01*
X659992D01*
X659617Y70575D01*
X659325Y70367D01*
X659117Y70117D01*
X658950Y69700D01*
X658908Y69325D01*
X658992Y68950D01*
X659117Y68700D01*
X659367Y68450D01*
X659658Y68283D01*
X659950Y68200D01*
X660242D01*
X660533Y68283D01*
X660783Y68408D01*
X660992Y68575D01*
G01X662342Y68492D02*
X662633Y68283D01*
X662967Y68200D01*
X663300Y68283D01*
X663592Y68533D01*
X663800Y68908D01*
X663883Y69283D01*
Y69742D01*
X663800Y70117D01*
X663592Y70450D01*
X663342Y70617D01*
X663050Y70700D01*
X662717Y70617D01*
X662467Y70450D01*
X662300Y70200D01*
X662217Y69867D01*
X662300Y69575D01*
X662508Y69283D01*
X662758Y69117D01*
X663050Y69075D01*
X663383Y69158D01*
X663633Y69367D01*
X663883Y69742D01*
G01X666150Y68200D02*
X666442Y68242D01*
X666775Y68367D01*
X666983Y68575D01*
X667067Y68867D01*
X666983Y69158D01*
X666733Y69408D01*
X666358Y69533D01*
X665942D01*
X665692Y69617D01*
X665483Y69825D01*
X665400Y70117D01*
X665525Y70408D01*
X665817Y70617D01*
X666150Y70700D01*
X666483Y70617D01*
X666775Y70408D01*
X666900Y70117D01*
X666817Y69825D01*
X666608Y69617D01*
X666358Y69533D01*
X665942D01*
X665567Y69408D01*
X665317Y69158D01*
X665233Y68867D01*
X665317Y68575D01*
X665525Y68367D01*
X665858Y68242D01*
X666150Y68200D01*
G01X656167Y80500D02*
Y83000D01*
X657167D01*
X657500Y82875D01*
X657750Y82583D01*
X657833Y82250D01*
X657750Y81917D01*
X657542Y81667D01*
X657167Y81542D01*
X656167D01*
G01X659267Y80500D02*
Y83000D01*
X660308D01*
X660642Y82875D01*
X660850Y82708D01*
X660933Y82375D01*
X660850Y82042D01*
X660600Y81833D01*
X660308Y81708D01*
X659267D01*
G01X660308D02*
X660933Y80500D01*
G01X663200D02*
Y83000D01*
X662700Y82500D01*
G01Y80500D02*
X663700D01*
G01X665383Y81000D02*
X665633Y80708D01*
X665967Y80542D01*
X666342Y80500D01*
X666675Y80542D01*
X667008Y80750D01*
X667217Y81000D01*
X667258Y81250D01*
X667175Y81542D01*
X666883Y81750D01*
X666592Y81833D01*
X666217D01*
G01X666592D02*
X666842Y81958D01*
X667050Y82167D01*
X667133Y82417D01*
X667050Y82667D01*
X666842Y82875D01*
X666467Y83000D01*
X666092Y82958D01*
X665717Y82792D01*
G01X668608Y82583D02*
X668858Y82833D01*
X669150Y82958D01*
X669483Y83000D01*
X669900Y82917D01*
X670192Y82708D01*
X670275Y82458D01*
X670233Y82208D01*
X670067Y82000D01*
X669233Y81583D01*
X668858Y81292D01*
X668608Y80875D01*
X668525Y80500D01*
X670275D01*
G01X656017Y76200D02*
Y78700D01*
X657017D01*
X657350Y78575D01*
X657600Y78283D01*
X657683Y77950D01*
X657600Y77617D01*
X657392Y77367D01*
X657017Y77242D01*
X656017D01*
G01X659117Y76200D02*
Y78700D01*
X660158D01*
X660492Y78575D01*
X660700Y78408D01*
X660783Y78075D01*
X660700Y77742D01*
X660450Y77533D01*
X660158Y77408D01*
X659117D01*
G01X660158D02*
X660783Y76200D01*
G01X663050D02*
Y78700D01*
X662550Y78200D01*
G01Y76200D02*
X663550D01*
G01X665233Y76700D02*
X665483Y76408D01*
X665817Y76242D01*
X666192Y76200D01*
X666525Y76242D01*
X666858Y76450D01*
X667067Y76700D01*
X667108Y76950D01*
X667025Y77242D01*
X666733Y77450D01*
X666442Y77533D01*
X666067D01*
G01X666442D02*
X666692Y77658D01*
X666900Y77867D01*
X666983Y78117D01*
X666900Y78367D01*
X666692Y78575D01*
X666317Y78700D01*
X665942Y78658D01*
X665567Y78492D01*
G01X668458Y77242D02*
X668750Y77533D01*
X669000Y77700D01*
X669333Y77783D01*
X669625Y77700D01*
X669833Y77533D01*
X670000Y77283D01*
X670042Y76992D01*
X670000Y76742D01*
X669833Y76492D01*
X669583Y76283D01*
X669292Y76200D01*
X668958Y76283D01*
X668667Y76533D01*
X668500Y76908D01*
X668458Y77325D01*
X668542Y77867D01*
X668667Y78158D01*
X668875Y78450D01*
X669167Y78658D01*
X669458Y78700D01*
X669750Y78617D01*
X669958Y78408D01*
G01X656317Y84500D02*
Y87000D01*
X657317D01*
X657650Y86875D01*
X657900Y86583D01*
X657983Y86250D01*
X657900Y85917D01*
X657692Y85667D01*
X657317Y85542D01*
X656317D01*
G01X661167Y86792D02*
X660917Y86917D01*
X660625Y87000D01*
X660292D01*
X659917Y86875D01*
X659625Y86667D01*
X659417Y86417D01*
X659250Y86000D01*
X659208Y85625D01*
X659292Y85250D01*
X659417Y85000D01*
X659667Y84750D01*
X659958Y84583D01*
X660250Y84500D01*
X660542D01*
X660833Y84583D01*
X661083Y84708D01*
X661292Y84875D01*
G01X663350Y84500D02*
X663642Y84542D01*
X663975Y84667D01*
X664183Y84875D01*
X664267Y85167D01*
X664183Y85458D01*
X663933Y85708D01*
X663558Y85833D01*
X663142D01*
X662892Y85917D01*
X662683Y86125D01*
X662600Y86417D01*
X662725Y86708D01*
X663017Y86917D01*
X663350Y87000D01*
X663683Y86917D01*
X663975Y86708D01*
X664100Y86417D01*
X664017Y86125D01*
X663808Y85917D01*
X663558Y85833D01*
X663142D01*
X662767Y85708D01*
X662517Y85458D01*
X662433Y85167D01*
X662517Y84875D01*
X662725Y84667D01*
X663058Y84542D01*
X663350Y84500D01*
G01X666450D02*
X666742Y84542D01*
X667075Y84667D01*
X667283Y84875D01*
X667367Y85167D01*
X667283Y85458D01*
X667033Y85708D01*
X666658Y85833D01*
X666242D01*
X665992Y85917D01*
X665783Y86125D01*
X665700Y86417D01*
X665825Y86708D01*
X666117Y86917D01*
X666450Y87000D01*
X666783Y86917D01*
X667075Y86708D01*
X667200Y86417D01*
X667117Y86125D01*
X666908Y85917D01*
X666658Y85833D01*
X666242D01*
X665867Y85708D01*
X665617Y85458D01*
X665533Y85167D01*
X665617Y84875D01*
X665825Y84667D01*
X666158Y84542D01*
X666450Y84500D01*
G01X654167Y112525D02*
X654375Y112858D01*
X654500Y113233D01*
Y113567D01*
X654375Y113900D01*
X654167Y114150D01*
X653875Y114275D01*
X653583Y114192D01*
X653333Y113983D01*
X653167Y113608D01*
X653083Y113108D01*
X652917Y112817D01*
X652625Y112692D01*
X652333Y112775D01*
X652125Y112983D01*
X652000Y113275D01*
Y113567D01*
X652083Y113858D01*
X652292Y114108D01*
G01X652000Y115250D02*
X654500Y115833D01*
X652000Y116500D01*
X654500Y117167D01*
X652000Y117750D01*
G01X652417Y118808D02*
X652167Y119058D01*
X652042Y119350D01*
X652000Y119683D01*
X652083Y120100D01*
X652292Y120392D01*
X652542Y120475D01*
X652792Y120433D01*
X653000Y120267D01*
X653417Y119433D01*
X653708Y119058D01*
X654125Y118808D01*
X654500Y118725D01*
Y120475D01*
G01X705000Y155000D02*
Y154500D01*
X683500D01*
Y149500D01*
X662500D01*
Y153000D01*
G01X650708Y144817D02*
X650583Y144567D01*
X650500Y144275D01*
Y143942D01*
X650625Y143567D01*
X650833Y143275D01*
X651083Y143067D01*
X651500Y142900D01*
X651875Y142858D01*
X652250Y142942D01*
X652500Y143067D01*
X652750Y143317D01*
X652917Y143608D01*
X653000Y143900D01*
Y144192D01*
X652917Y144483D01*
X652792Y144733D01*
X652625Y144942D01*
G01X650917Y146208D02*
X650667Y146458D01*
X650542Y146750D01*
X650500Y147083D01*
X650583Y147500D01*
X650792Y147792D01*
X651042Y147875D01*
X651292Y147833D01*
X651500Y147667D01*
X651917Y146833D01*
X652208Y146458D01*
X652625Y146208D01*
X653000Y146125D01*
Y147875D01*
G01Y150100D02*
X650500D01*
X651000Y149600D01*
G01X653000D02*
Y150600D01*
G01X657500Y147350D02*
X657458Y147017D01*
X657292Y146725D01*
X657042Y146475D01*
X656750Y146308D01*
X656417Y146225D01*
X656083D01*
X655750Y146308D01*
X655458Y146475D01*
X655208Y146725D01*
X655042Y147017D01*
X655000Y147350D01*
X655042Y147683D01*
X655208Y147975D01*
X655458Y148225D01*
X655750Y148392D01*
X656083Y148475D01*
X656417D01*
X656750Y148392D01*
X657042Y148225D01*
X657292Y147975D01*
X657458Y147683D01*
X657500Y147350D01*
G01X657167Y149575D02*
X657375Y149908D01*
X657500Y150283D01*
Y150617D01*
X657375Y150950D01*
X657167Y151200D01*
X656875Y151325D01*
X656583Y151242D01*
X656333Y151033D01*
X656167Y150658D01*
X656083Y150158D01*
X655917Y149867D01*
X655625Y149742D01*
X655333Y149825D01*
X655125Y150033D01*
X655000Y150325D01*
Y150617D01*
X655083Y150908D01*
X655292Y151158D01*
G01X655208Y154467D02*
X655083Y154217D01*
X655000Y153925D01*
Y153592D01*
X655125Y153217D01*
X655333Y152925D01*
X655583Y152717D01*
X656000Y152550D01*
X656375Y152508D01*
X656750Y152592D01*
X657000Y152717D01*
X657250Y152967D01*
X657417Y153258D01*
X657500Y153550D01*
Y153842D01*
X657417Y154133D01*
X657292Y154383D01*
X657125Y154592D01*
G01X657500Y156650D02*
X655000D01*
X655500Y156150D01*
G01X657500D02*
Y157150D01*
G01X657483Y174000D02*
Y172208D01*
X657650Y171833D01*
X657983Y171583D01*
X658400Y171500D01*
X658817Y171583D01*
X659150Y171833D01*
X659317Y172208D01*
Y174000D01*
G01X660708Y173583D02*
X660958Y173833D01*
X661250Y173958D01*
X661583Y174000D01*
X662000Y173917D01*
X662292Y173708D01*
X662375Y173458D01*
X662333Y173208D01*
X662167Y173000D01*
X661333Y172583D01*
X660958Y172292D01*
X660708Y171875D01*
X660625Y171500D01*
X662375D01*
G01X665100D02*
Y174000D01*
X663558Y172208D01*
X665642D01*
G01X654517Y175500D02*
Y178000D01*
X655558D01*
X655892Y177875D01*
X656100Y177708D01*
X656183Y177375D01*
X656100Y177042D01*
X655850Y176833D01*
X655558Y176708D01*
X654517D01*
G01X655558D02*
X656183Y175500D01*
G01X657658Y177583D02*
X657908Y177833D01*
X658200Y177958D01*
X658533Y178000D01*
X658950Y177917D01*
X659242Y177708D01*
X659325Y177458D01*
X659283Y177208D01*
X659117Y177000D01*
X658283Y176583D01*
X657908Y176292D01*
X657658Y175875D01*
X657575Y175500D01*
X659325D01*
G01X661550D02*
Y178000D01*
X661050Y177500D01*
G01Y175500D02*
X662050D01*
G01X663858Y177583D02*
X664108Y177833D01*
X664400Y177958D01*
X664733Y178000D01*
X665150Y177917D01*
X665442Y177708D01*
X665525Y177458D01*
X665483Y177208D01*
X665317Y177000D01*
X664483Y176583D01*
X664108Y176292D01*
X663858Y175875D01*
X663775Y175500D01*
X665525D01*
G01X655017Y194500D02*
Y197000D01*
X656058D01*
X656392Y196875D01*
X656600Y196708D01*
X656683Y196375D01*
X656600Y196042D01*
X656350Y195833D01*
X656058Y195708D01*
X655017D01*
G01X656058D02*
X656683Y194500D01*
G01X658158Y196583D02*
X658408Y196833D01*
X658700Y196958D01*
X659033Y197000D01*
X659450Y196917D01*
X659742Y196708D01*
X659825Y196458D01*
X659783Y196208D01*
X659617Y196000D01*
X658783Y195583D01*
X658408Y195292D01*
X658158Y194875D01*
X658075Y194500D01*
X659825D01*
G01X662050Y197000D02*
X661717Y196917D01*
X661467Y196708D01*
X661300Y196458D01*
X661175Y196125D01*
X661133Y195750D01*
X661175Y195375D01*
X661300Y195042D01*
X661467Y194792D01*
X661717Y194583D01*
X662050Y194500D01*
X662383Y194583D01*
X662633Y194792D01*
X662800Y195042D01*
X662925Y195375D01*
X662967Y195750D01*
X662925Y196125D01*
X662800Y196458D01*
X662633Y196708D01*
X662383Y196917D01*
X662050Y197000D01*
G01X664358Y195542D02*
X664650Y195833D01*
X664900Y196000D01*
X665233Y196083D01*
X665525Y196000D01*
X665733Y195833D01*
X665900Y195583D01*
X665942Y195292D01*
X665900Y195042D01*
X665733Y194792D01*
X665483Y194583D01*
X665192Y194500D01*
X664858Y194583D01*
X664567Y194833D01*
X664400Y195208D01*
X664358Y195625D01*
X664442Y196167D01*
X664567Y196458D01*
X664775Y196750D01*
X665067Y196958D01*
X665358Y197000D01*
X665650Y196917D01*
X665858Y196708D01*
G01X655017Y198000D02*
Y200500D01*
X656058D01*
X656392Y200375D01*
X656600Y200208D01*
X656683Y199875D01*
X656600Y199542D01*
X656350Y199333D01*
X656058Y199208D01*
X655017D01*
G01X656058D02*
X656683Y198000D01*
G01X659450D02*
Y200500D01*
X657908Y198708D01*
X659992D01*
G01X661342Y198292D02*
X661633Y198083D01*
X661967Y198000D01*
X662300Y198083D01*
X662592Y198333D01*
X662800Y198708D01*
X662883Y199083D01*
Y199542D01*
X662800Y199917D01*
X662592Y200250D01*
X662342Y200417D01*
X662050Y200500D01*
X661717Y200417D01*
X661467Y200250D01*
X661300Y200000D01*
X661217Y199667D01*
X661300Y199375D01*
X661508Y199083D01*
X661758Y198917D01*
X662050Y198875D01*
X662383Y198958D01*
X662633Y199167D01*
X662883Y199542D01*
G01X665650Y198000D02*
Y200500D01*
X664108Y198708D01*
X666192D01*
G01X654717Y210500D02*
Y213000D01*
X655758D01*
X656092Y212875D01*
X656300Y212708D01*
X656383Y212375D01*
X656300Y212042D01*
X656050Y211833D01*
X655758Y211708D01*
X654717D01*
G01X655758D02*
X656383Y210500D01*
G01X658650D02*
Y213000D01*
X658150Y212500D01*
G01Y210500D02*
X659150D01*
G01X661750D02*
X662042Y210542D01*
X662375Y210667D01*
X662583Y210875D01*
X662667Y211167D01*
X662583Y211458D01*
X662333Y211708D01*
X661958Y211833D01*
X661542D01*
X661292Y211917D01*
X661083Y212125D01*
X661000Y212417D01*
X661125Y212708D01*
X661417Y212917D01*
X661750Y213000D01*
X662083Y212917D01*
X662375Y212708D01*
X662500Y212417D01*
X662417Y212125D01*
X662208Y211917D01*
X661958Y211833D01*
X661542D01*
X661167Y211708D01*
X660917Y211458D01*
X660833Y211167D01*
X660917Y210875D01*
X661125Y210667D01*
X661458Y210542D01*
X661750Y210500D01*
G01X664058Y212583D02*
X664308Y212833D01*
X664600Y212958D01*
X664933Y213000D01*
X665350Y212917D01*
X665642Y212708D01*
X665725Y212458D01*
X665683Y212208D01*
X665517Y212000D01*
X664683Y211583D01*
X664308Y211292D01*
X664058Y210875D01*
X663975Y210500D01*
X665725D01*
G01X650208Y230767D02*
X650083Y230517D01*
X650000Y230225D01*
Y229892D01*
X650125Y229517D01*
X650333Y229225D01*
X650583Y229017D01*
X651000Y228850D01*
X651375Y228808D01*
X651750Y228892D01*
X652000Y229017D01*
X652250Y229267D01*
X652417Y229558D01*
X652500Y229850D01*
Y230142D01*
X652417Y230433D01*
X652292Y230683D01*
X652125Y230892D01*
G01X652000Y232033D02*
X652292Y232283D01*
X652458Y232617D01*
X652500Y232992D01*
X652458Y233325D01*
X652250Y233658D01*
X652000Y233867D01*
X651750Y233908D01*
X651458Y233825D01*
X651250Y233533D01*
X651167Y233242D01*
Y232867D01*
G01Y233242D02*
X651042Y233492D01*
X650833Y233700D01*
X650583Y233783D01*
X650333Y233700D01*
X650125Y233492D01*
X650000Y233117D01*
X650042Y232742D01*
X650208Y232367D01*
G01X652500Y235967D02*
X651958Y236050D01*
X651500Y236175D01*
X651083Y236342D01*
X650625Y236550D01*
X650000Y236883D01*
Y235217D01*
G01X652500Y239650D02*
X650000D01*
X651792Y238108D01*
Y240192D01*
G01X653708Y230767D02*
X653583Y230517D01*
X653500Y230225D01*
Y229892D01*
X653625Y229517D01*
X653833Y229225D01*
X654083Y229017D01*
X654500Y228850D01*
X654875Y228808D01*
X655250Y228892D01*
X655500Y229017D01*
X655750Y229267D01*
X655917Y229558D01*
X656000Y229850D01*
Y230142D01*
X655917Y230433D01*
X655792Y230683D01*
X655625Y230892D01*
G01X655500Y232033D02*
X655792Y232283D01*
X655958Y232617D01*
X656000Y232992D01*
X655958Y233325D01*
X655750Y233658D01*
X655500Y233867D01*
X655250Y233908D01*
X654958Y233825D01*
X654750Y233533D01*
X654667Y233242D01*
Y232867D01*
G01Y233242D02*
X654542Y233492D01*
X654333Y233700D01*
X654083Y233783D01*
X653833Y233700D01*
X653625Y233492D01*
X653500Y233117D01*
X653542Y232742D01*
X653708Y232367D01*
G01X654958Y235258D02*
X654667Y235550D01*
X654500Y235800D01*
X654417Y236133D01*
X654500Y236425D01*
X654667Y236633D01*
X654917Y236800D01*
X655208Y236842D01*
X655458Y236800D01*
X655708Y236633D01*
X655917Y236383D01*
X656000Y236092D01*
X655917Y235758D01*
X655667Y235467D01*
X655292Y235300D01*
X654875Y235258D01*
X654333Y235342D01*
X654042Y235467D01*
X653750Y235675D01*
X653542Y235967D01*
X653500Y236258D01*
X653583Y236550D01*
X653792Y236758D01*
G01X656000Y239067D02*
X655458Y239150D01*
X655000Y239275D01*
X654583Y239442D01*
X654125Y239650D01*
X653500Y239983D01*
Y238317D01*
G01X661208Y227267D02*
X661083Y227017D01*
X661000Y226725D01*
Y226392D01*
X661125Y226017D01*
X661333Y225725D01*
X661583Y225517D01*
X662000Y225350D01*
X662375Y225308D01*
X662750Y225392D01*
X663000Y225517D01*
X663250Y225767D01*
X663417Y226058D01*
X663500Y226350D01*
Y226642D01*
X663417Y226933D01*
X663292Y227183D01*
X663125Y227392D01*
G01X661417Y228658D02*
X661167Y228908D01*
X661042Y229200D01*
X661000Y229533D01*
X661083Y229950D01*
X661292Y230242D01*
X661542Y230325D01*
X661792Y230283D01*
X662000Y230117D01*
X662417Y229283D01*
X662708Y228908D01*
X663125Y228658D01*
X663500Y228575D01*
Y230325D01*
G01X663000Y231633D02*
X663292Y231883D01*
X663458Y232217D01*
X663500Y232592D01*
X663458Y232925D01*
X663250Y233258D01*
X663000Y233467D01*
X662750Y233508D01*
X662458Y233425D01*
X662250Y233133D01*
X662167Y232842D01*
Y232467D01*
G01Y232842D02*
X662042Y233092D01*
X661833Y233300D01*
X661583Y233383D01*
X661333Y233300D01*
X661125Y233092D01*
X661000Y232717D01*
X661042Y232342D01*
X661208Y231967D01*
G01X661417Y234858D02*
X661167Y235108D01*
X661042Y235400D01*
X661000Y235733D01*
X661083Y236150D01*
X661292Y236442D01*
X661542Y236525D01*
X661792Y236483D01*
X662000Y236317D01*
X662417Y235483D01*
X662708Y235108D01*
X663125Y234858D01*
X663500Y234775D01*
Y236525D01*
G01X660000Y229017D02*
X657500D01*
Y230058D01*
X657625Y230392D01*
X657792Y230600D01*
X658125Y230683D01*
X658458Y230600D01*
X658667Y230350D01*
X658792Y230058D01*
Y229017D01*
G01Y230058D02*
X660000Y230683D01*
G01X657917Y232158D02*
X657667Y232408D01*
X657542Y232700D01*
X657500Y233033D01*
X657583Y233450D01*
X657792Y233742D01*
X658042Y233825D01*
X658292Y233783D01*
X658500Y233617D01*
X658917Y232783D01*
X659208Y232408D01*
X659625Y232158D01*
X660000Y232075D01*
Y233825D01*
G01X659500Y235133D02*
X659792Y235383D01*
X659958Y235717D01*
X660000Y236092D01*
X659958Y236425D01*
X659750Y236758D01*
X659500Y236967D01*
X659250Y237008D01*
X658958Y236925D01*
X658750Y236633D01*
X658667Y236342D01*
Y235967D01*
G01Y236342D02*
X658542Y236592D01*
X658333Y236800D01*
X658083Y236883D01*
X657833Y236800D01*
X657625Y236592D01*
X657500Y236217D01*
X657542Y235842D01*
X657708Y235467D01*
G01X660000Y239067D02*
X659458Y239150D01*
X659000Y239275D01*
X658583Y239442D01*
X658125Y239650D01*
X657500Y239983D01*
Y238317D01*
G01X654717Y214500D02*
Y217000D01*
X655758D01*
X656092Y216875D01*
X656300Y216708D01*
X656383Y216375D01*
X656300Y216042D01*
X656050Y215833D01*
X655758Y215708D01*
X654717D01*
G01X655758D02*
X656383Y214500D01*
G01X658650D02*
Y217000D01*
X658150Y216500D01*
G01Y214500D02*
X659150D01*
G01X661750D02*
X662042Y214542D01*
X662375Y214667D01*
X662583Y214875D01*
X662667Y215167D01*
X662583Y215458D01*
X662333Y215708D01*
X661958Y215833D01*
X661542D01*
X661292Y215917D01*
X661083Y216125D01*
X661000Y216417D01*
X661125Y216708D01*
X661417Y216917D01*
X661750Y217000D01*
X662083Y216917D01*
X662375Y216708D01*
X662500Y216417D01*
X662417Y216125D01*
X662208Y215917D01*
X661958Y215833D01*
X661542D01*
X661167Y215708D01*
X660917Y215458D01*
X660833Y215167D01*
X660917Y214875D01*
X661125Y214667D01*
X661458Y214542D01*
X661750Y214500D01*
G01X664850D02*
X665142Y214542D01*
X665475Y214667D01*
X665683Y214875D01*
X665767Y215167D01*
X665683Y215458D01*
X665433Y215708D01*
X665058Y215833D01*
X664642D01*
X664392Y215917D01*
X664183Y216125D01*
X664100Y216417D01*
X664225Y216708D01*
X664517Y216917D01*
X664850Y217000D01*
X665183Y216917D01*
X665475Y216708D01*
X665600Y216417D01*
X665517Y216125D01*
X665308Y215917D01*
X665058Y215833D01*
X664642D01*
X664267Y215708D01*
X664017Y215458D01*
X663933Y215167D01*
X664017Y214875D01*
X664225Y214667D01*
X664558Y214542D01*
X664850Y214500D01*
G01X653800Y224350D02*
Y227350D01*
X650800D01*
G01X677708Y46274D02*
X677583Y46024D01*
X677500Y45732D01*
Y45399D01*
X677625Y45024D01*
X677833Y44732D01*
X678083Y44524D01*
X678500Y44357D01*
X678875Y44315D01*
X679250Y44399D01*
X679500Y44524D01*
X679750Y44774D01*
X679917Y45065D01*
X680000Y45357D01*
Y45649D01*
X679917Y45940D01*
X679792Y46190D01*
X679625Y46399D01*
G01X679500Y47540D02*
X679792Y47790D01*
X679958Y48124D01*
X680000Y48499D01*
X679958Y48832D01*
X679750Y49165D01*
X679500Y49374D01*
X679250Y49415D01*
X678958Y49332D01*
X678750Y49040D01*
X678667Y48749D01*
Y48374D01*
G01Y48749D02*
X678542Y48999D01*
X678333Y49207D01*
X678083Y49290D01*
X677833Y49207D01*
X677625Y48999D01*
X677500Y48624D01*
X677542Y48249D01*
X677708Y47874D01*
G01X680000Y51474D02*
X679458Y51557D01*
X679000Y51682D01*
X678583Y51849D01*
X678125Y52057D01*
X677500Y52390D01*
Y50724D01*
G01X679500Y53740D02*
X679792Y53990D01*
X679958Y54324D01*
X680000Y54699D01*
X679958Y55032D01*
X679750Y55365D01*
X679500Y55574D01*
X679250Y55615D01*
X678958Y55532D01*
X678750Y55240D01*
X678667Y54949D01*
Y54574D01*
G01Y54949D02*
X678542Y55199D01*
X678333Y55407D01*
X678083Y55490D01*
X677833Y55407D01*
X677625Y55199D01*
X677500Y54824D01*
X677542Y54449D01*
X677708Y54074D01*
G01X707500Y68000D02*
Y75500D01*
X710500D01*
Y80500D01*
X700000D01*
Y89500D01*
X672000D01*
Y67000D01*
X673500D01*
Y61000D01*
X689000D01*
Y54500D01*
X696000D01*
Y67500D01*
X699500D01*
G01X679900Y69067D02*
X677400D01*
Y70067D01*
X677525Y70400D01*
X677817Y70650D01*
X678150Y70733D01*
X678483Y70650D01*
X678733Y70442D01*
X678858Y70067D01*
Y69067D01*
G01X677608Y73917D02*
X677483Y73667D01*
X677400Y73375D01*
Y73042D01*
X677525Y72667D01*
X677733Y72375D01*
X677983Y72167D01*
X678400Y72000D01*
X678775Y71958D01*
X679150Y72042D01*
X679400Y72167D01*
X679650Y72417D01*
X679817Y72708D01*
X679900Y73000D01*
Y73292D01*
X679817Y73583D01*
X679692Y73833D01*
X679525Y74042D01*
G01X679900Y76100D02*
X677400D01*
X677900Y75600D01*
G01X679900D02*
Y76600D01*
G01X677400Y79200D02*
X677483Y78867D01*
X677692Y78617D01*
X677942Y78450D01*
X678275Y78325D01*
X678650Y78283D01*
X679025Y78325D01*
X679358Y78450D01*
X679608Y78617D01*
X679817Y78867D01*
X679900Y79200D01*
X679817Y79533D01*
X679608Y79783D01*
X679358Y79950D01*
X679025Y80075D01*
X678650Y80117D01*
X678275Y80075D01*
X677942Y79950D01*
X677692Y79783D01*
X677483Y79533D01*
X677400Y79200D01*
G01X679608Y81592D02*
X679817Y81883D01*
X679900Y82217D01*
X679817Y82550D01*
X679567Y82842D01*
X679192Y83050D01*
X678817Y83133D01*
X678358D01*
X677983Y83050D01*
X677650Y82842D01*
X677483Y82592D01*
X677400Y82300D01*
X677483Y81967D01*
X677650Y81717D01*
X677900Y81550D01*
X678233Y81467D01*
X678525Y81550D01*
X678817Y81758D01*
X678983Y82008D01*
X679025Y82300D01*
X678942Y82633D01*
X678733Y82883D01*
X678358Y83133D01*
G01X676300Y69067D02*
X673800D01*
Y70067D01*
X673925Y70400D01*
X674217Y70650D01*
X674550Y70733D01*
X674883Y70650D01*
X675133Y70442D01*
X675258Y70067D01*
Y69067D01*
G01X676300Y72167D02*
X673800D01*
Y73208D01*
X673925Y73542D01*
X674092Y73750D01*
X674425Y73833D01*
X674758Y73750D01*
X674967Y73500D01*
X675092Y73208D01*
Y72167D01*
G01Y73208D02*
X676300Y73833D01*
G01Y76100D02*
X673800D01*
X674300Y75600D01*
G01X676300D02*
Y76600D01*
G01X675925Y78283D02*
X676133Y78533D01*
X676258Y78825D01*
X676300Y79200D01*
X676217Y79575D01*
X676050Y79867D01*
X675758Y80075D01*
X675425Y80117D01*
X675092Y80033D01*
X674883Y79825D01*
X674717Y79533D01*
X674675Y79242D01*
X674717Y78950D01*
X674883Y78575D01*
X673800Y78700D01*
Y79825D01*
G01X676300Y82300D02*
X676258Y82592D01*
X676133Y82925D01*
X675925Y83133D01*
X675633Y83217D01*
X675342Y83133D01*
X675092Y82883D01*
X674967Y82508D01*
Y82092D01*
X674883Y81842D01*
X674675Y81633D01*
X674383Y81550D01*
X674092Y81675D01*
X673883Y81967D01*
X673800Y82300D01*
X673883Y82633D01*
X674092Y82925D01*
X674383Y83050D01*
X674675Y82967D01*
X674883Y82758D01*
X674967Y82508D01*
Y82092D01*
X675092Y81717D01*
X675342Y81467D01*
X675633Y81383D01*
X675925Y81467D01*
X676133Y81675D01*
X676258Y82008D01*
X676300Y82300D01*
G01X674967Y63500D02*
Y66000D01*
X675967D01*
X676300Y65875D01*
X676550Y65583D01*
X676633Y65250D01*
X676550Y64917D01*
X676342Y64667D01*
X675967Y64542D01*
X674967D01*
G01X678067Y63500D02*
Y66000D01*
X679108D01*
X679442Y65875D01*
X679650Y65708D01*
X679733Y65375D01*
X679650Y65042D01*
X679400Y64833D01*
X679108Y64708D01*
X678067D01*
G01X679108D02*
X679733Y63500D01*
G01X682000D02*
Y66000D01*
X681500Y65500D01*
G01Y63500D02*
X682500D01*
G01X684308Y64542D02*
X684600Y64833D01*
X684850Y65000D01*
X685183Y65083D01*
X685475Y65000D01*
X685683Y64833D01*
X685850Y64583D01*
X685892Y64292D01*
X685850Y64042D01*
X685683Y63792D01*
X685433Y63583D01*
X685142Y63500D01*
X684808Y63583D01*
X684517Y63833D01*
X684350Y64208D01*
X684308Y64625D01*
X684392Y65167D01*
X684517Y65458D01*
X684725Y65750D01*
X685017Y65958D01*
X685308Y66000D01*
X685600Y65917D01*
X685808Y65708D01*
G01X687408Y65583D02*
X687658Y65833D01*
X687950Y65958D01*
X688283Y66000D01*
X688700Y65917D01*
X688992Y65708D01*
X689075Y65458D01*
X689033Y65208D01*
X688867Y65000D01*
X688033Y64583D01*
X687658Y64292D01*
X687408Y63875D01*
X687325Y63500D01*
X689075D01*
G01X673467Y85500D02*
Y88000D01*
X674467D01*
X674800Y87875D01*
X675050Y87583D01*
X675133Y87250D01*
X675050Y86917D01*
X674842Y86667D01*
X674467Y86542D01*
X673467D01*
G01X678317Y87792D02*
X678067Y87917D01*
X677775Y88000D01*
X677442D01*
X677067Y87875D01*
X676775Y87667D01*
X676567Y87417D01*
X676400Y87000D01*
X676358Y86625D01*
X676442Y86250D01*
X676567Y86000D01*
X676817Y85750D01*
X677108Y85583D01*
X677400Y85500D01*
X677692D01*
X677983Y85583D01*
X678233Y85708D01*
X678442Y85875D01*
G01X680500Y85500D02*
Y88000D01*
X680000Y87500D01*
G01Y85500D02*
X681000D01*
G01X683600Y88000D02*
X683267Y87917D01*
X683017Y87708D01*
X682850Y87458D01*
X682725Y87125D01*
X682683Y86750D01*
X682725Y86375D01*
X682850Y86042D01*
X683017Y85792D01*
X683267Y85583D01*
X683600Y85500D01*
X683933Y85583D01*
X684183Y85792D01*
X684350Y86042D01*
X684475Y86375D01*
X684517Y86750D01*
X684475Y87125D01*
X684350Y87458D01*
X684183Y87708D01*
X683933Y87917D01*
X683600Y88000D01*
G01X686617Y85500D02*
X686700Y86042D01*
X686825Y86500D01*
X686992Y86917D01*
X687200Y87375D01*
X687533Y88000D01*
X685867D01*
G01X665567Y145500D02*
Y148000D01*
X666567D01*
X666900Y147875D01*
X667150Y147583D01*
X667233Y147250D01*
X667150Y146917D01*
X666942Y146667D01*
X666567Y146542D01*
X665567D01*
G01X668583Y148000D02*
Y146208D01*
X668750Y145833D01*
X669083Y145583D01*
X669500Y145500D01*
X669917Y145583D01*
X670250Y145833D01*
X670417Y146208D01*
Y148000D01*
G01X672600Y145500D02*
X672892Y145542D01*
X673225Y145667D01*
X673433Y145875D01*
X673517Y146167D01*
X673433Y146458D01*
X673183Y146708D01*
X672808Y146833D01*
X672392D01*
X672142Y146917D01*
X671933Y147125D01*
X671850Y147417D01*
X671975Y147708D01*
X672267Y147917D01*
X672600Y148000D01*
X672933Y147917D01*
X673225Y147708D01*
X673350Y147417D01*
X673267Y147125D01*
X673058Y146917D01*
X672808Y146833D01*
X672392D01*
X672017Y146708D01*
X671767Y146458D01*
X671683Y146167D01*
X671767Y145875D01*
X671975Y145667D01*
X672308Y145542D01*
X672600Y145500D01*
G01X679250Y159300D02*
X680450Y160500D01*
X681650Y159300D01*
G01X682100Y170950D02*
X678900D01*
Y159300D01*
X682100D01*
Y170950D01*
G01X667500Y175500D02*
X684500D01*
Y178500D01*
X689500D01*
Y176000D01*
X705500D01*
Y173000D01*
X712000D01*
G01X672517Y177500D02*
Y180000D01*
X673558D01*
X673892Y179875D01*
X674100Y179708D01*
X674183Y179375D01*
X674100Y179042D01*
X673850Y178833D01*
X673558Y178708D01*
X672517D01*
G01X673558D02*
X674183Y177500D01*
G01X676450D02*
Y180000D01*
X675950Y179500D01*
G01Y177500D02*
X676950D01*
G01X678842Y177792D02*
X679133Y177583D01*
X679467Y177500D01*
X679800Y177583D01*
X680092Y177833D01*
X680300Y178208D01*
X680383Y178583D01*
Y179042D01*
X680300Y179417D01*
X680092Y179750D01*
X679842Y179917D01*
X679550Y180000D01*
X679217Y179917D01*
X678967Y179750D01*
X678800Y179500D01*
X678717Y179167D01*
X678800Y178875D01*
X679008Y178583D01*
X679258Y178417D01*
X679550Y178375D01*
X679883Y178458D01*
X680133Y178667D01*
X680383Y179042D01*
G01X682650Y177500D02*
Y180000D01*
X682150Y179500D01*
G01Y177500D02*
X683150D01*
G01X668017Y198500D02*
Y201000D01*
X669058D01*
X669392Y200875D01*
X669600Y200708D01*
X669683Y200375D01*
X669600Y200042D01*
X669350Y199833D01*
X669058Y199708D01*
X668017D01*
G01X669058D02*
X669683Y198500D01*
G01X672450D02*
Y201000D01*
X670908Y199208D01*
X672992D01*
G01X674967Y198500D02*
X675050Y199042D01*
X675175Y199500D01*
X675342Y199917D01*
X675550Y200375D01*
X675883Y201000D01*
X674217D01*
G01X678150Y198500D02*
Y201000D01*
X677650Y200500D01*
G01Y198500D02*
X678650D01*
G01X668017Y190500D02*
Y193000D01*
X669058D01*
X669392Y192875D01*
X669600Y192708D01*
X669683Y192375D01*
X669600Y192042D01*
X669350Y191833D01*
X669058Y191708D01*
X668017D01*
G01X669058D02*
X669683Y190500D01*
G01X672450D02*
Y193000D01*
X670908Y191208D01*
X672992D01*
G01X675050Y193000D02*
X674717Y192917D01*
X674467Y192708D01*
X674300Y192458D01*
X674175Y192125D01*
X674133Y191750D01*
X674175Y191375D01*
X674300Y191042D01*
X674467Y190792D01*
X674717Y190583D01*
X675050Y190500D01*
X675383Y190583D01*
X675633Y190792D01*
X675800Y191042D01*
X675925Y191375D01*
X675967Y191750D01*
X675925Y192125D01*
X675800Y192458D01*
X675633Y192708D01*
X675383Y192917D01*
X675050Y193000D01*
G01X678150Y190500D02*
Y193000D01*
X677650Y192500D01*
G01Y190500D02*
X678650D01*
G01X668017Y194500D02*
Y197000D01*
X669058D01*
X669392Y196875D01*
X669600Y196708D01*
X669683Y196375D01*
X669600Y196042D01*
X669350Y195833D01*
X669058Y195708D01*
X668017D01*
G01X669058D02*
X669683Y194500D01*
G01X671158Y196583D02*
X671408Y196833D01*
X671700Y196958D01*
X672033Y197000D01*
X672450Y196917D01*
X672742Y196708D01*
X672825Y196458D01*
X672783Y196208D01*
X672617Y196000D01*
X671783Y195583D01*
X671408Y195292D01*
X671158Y194875D01*
X671075Y194500D01*
X672825D01*
G01X675050D02*
Y197000D01*
X674550Y196500D01*
G01Y194500D02*
X675550D01*
G01X678150D02*
Y197000D01*
X677650Y196500D01*
G01Y194500D02*
X678650D01*
G01X668017Y186500D02*
Y189000D01*
X669058D01*
X669392Y188875D01*
X669600Y188708D01*
X669683Y188375D01*
X669600Y188042D01*
X669350Y187833D01*
X669058Y187708D01*
X668017D01*
G01X669058D02*
X669683Y186500D01*
G01X671950D02*
Y189000D01*
X671450Y188500D01*
G01Y186500D02*
X672450D01*
G01X674342Y186792D02*
X674633Y186583D01*
X674967Y186500D01*
X675300Y186583D01*
X675592Y186833D01*
X675800Y187208D01*
X675883Y187583D01*
Y188042D01*
X675800Y188417D01*
X675592Y188750D01*
X675342Y188917D01*
X675050Y189000D01*
X674717Y188917D01*
X674467Y188750D01*
X674300Y188500D01*
X674217Y188167D01*
X674300Y187875D01*
X674508Y187583D01*
X674758Y187417D01*
X675050Y187375D01*
X675383Y187458D01*
X675633Y187667D01*
X675883Y188042D01*
G01X677442Y186792D02*
X677733Y186583D01*
X678067Y186500D01*
X678400Y186583D01*
X678692Y186833D01*
X678900Y187208D01*
X678983Y187583D01*
Y188042D01*
X678900Y188417D01*
X678692Y188750D01*
X678442Y188917D01*
X678150Y189000D01*
X677817Y188917D01*
X677567Y188750D01*
X677400Y188500D01*
X677317Y188167D01*
X677400Y187875D01*
X677608Y187583D01*
X677858Y187417D01*
X678150Y187375D01*
X678483Y187458D01*
X678733Y187667D01*
X678983Y188042D01*
G01X674500Y207983D02*
X676292D01*
X676667Y208150D01*
X676917Y208483D01*
X677000Y208900D01*
X676917Y209317D01*
X676667Y209650D01*
X676292Y209817D01*
X674500D01*
G01X674917Y211208D02*
X674667Y211458D01*
X674542Y211750D01*
X674500Y212083D01*
X674583Y212500D01*
X674792Y212792D01*
X675042Y212875D01*
X675292Y212833D01*
X675500Y212667D01*
X675917Y211833D01*
X676208Y211458D01*
X676625Y211208D01*
X677000Y211125D01*
Y212875D01*
G01X674917Y214308D02*
X674667Y214558D01*
X674542Y214850D01*
X674500Y215183D01*
X674583Y215600D01*
X674792Y215892D01*
X675042Y215975D01*
X675292Y215933D01*
X675500Y215767D01*
X675917Y214933D01*
X676208Y214558D01*
X676625Y214308D01*
X677000Y214225D01*
Y215975D01*
G01X673000Y207067D02*
X670500D01*
Y208108D01*
X670625Y208442D01*
X670792Y208650D01*
X671125Y208733D01*
X671458Y208650D01*
X671667Y208400D01*
X671792Y208108D01*
Y207067D01*
G01Y208108D02*
X673000Y208733D01*
G01Y210917D02*
X672458Y211000D01*
X672000Y211125D01*
X671583Y211292D01*
X671125Y211500D01*
X670500Y211833D01*
Y210167D01*
G01X672708Y213392D02*
X672917Y213683D01*
X673000Y214017D01*
X672917Y214350D01*
X672667Y214642D01*
X672292Y214850D01*
X671917Y214933D01*
X671458D01*
X671083Y214850D01*
X670750Y214642D01*
X670583Y214392D01*
X670500Y214100D01*
X670583Y213767D01*
X670750Y213517D01*
X671000Y213350D01*
X671333Y213267D01*
X671625Y213350D01*
X671917Y213558D01*
X672083Y213808D01*
X672125Y214100D01*
X672042Y214433D01*
X671833Y214683D01*
X671458Y214933D01*
G01X676000Y220517D02*
X673500D01*
Y221558D01*
X673625Y221892D01*
X673792Y222100D01*
X674125Y222183D01*
X674458Y222100D01*
X674667Y221850D01*
X674792Y221558D01*
Y220517D01*
G01Y221558D02*
X676000Y222183D01*
G01Y224450D02*
X673500D01*
X674000Y223950D01*
G01X676000D02*
Y224950D01*
G01Y227467D02*
X675458Y227550D01*
X675000Y227675D01*
X674583Y227842D01*
X674125Y228050D01*
X673500Y228383D01*
Y226717D01*
G01X674958Y229858D02*
X674667Y230150D01*
X674500Y230400D01*
X674417Y230733D01*
X674500Y231025D01*
X674667Y231233D01*
X674917Y231400D01*
X675208Y231442D01*
X675458Y231400D01*
X675708Y231233D01*
X675917Y230983D01*
X676000Y230692D01*
X675917Y230358D01*
X675667Y230067D01*
X675292Y229900D01*
X674875Y229858D01*
X674333Y229942D01*
X674042Y230067D01*
X673750Y230275D01*
X673542Y230567D01*
X673500Y230858D01*
X673583Y231150D01*
X673792Y231358D01*
G01X672000Y220517D02*
X669500D01*
Y221558D01*
X669625Y221892D01*
X669792Y222100D01*
X670125Y222183D01*
X670458Y222100D01*
X670667Y221850D01*
X670792Y221558D01*
Y220517D01*
G01Y221558D02*
X672000Y222183D01*
G01Y224450D02*
X669500D01*
X670000Y223950D01*
G01X672000D02*
Y224950D01*
G01X671708Y226842D02*
X671917Y227133D01*
X672000Y227467D01*
X671917Y227800D01*
X671667Y228092D01*
X671292Y228300D01*
X670917Y228383D01*
X670458D01*
X670083Y228300D01*
X669750Y228092D01*
X669583Y227842D01*
X669500Y227550D01*
X669583Y227217D01*
X669750Y226967D01*
X670000Y226800D01*
X670333Y226717D01*
X670625Y226800D01*
X670917Y227008D01*
X671083Y227258D01*
X671125Y227550D01*
X671042Y227883D01*
X670833Y228133D01*
X670458Y228383D01*
G01X669917Y229858D02*
X669667Y230108D01*
X669542Y230400D01*
X669500Y230733D01*
X669583Y231150D01*
X669792Y231442D01*
X670042Y231525D01*
X670292Y231483D01*
X670500Y231317D01*
X670917Y230483D01*
X671208Y230108D01*
X671625Y229858D01*
X672000Y229775D01*
Y231525D01*
G01X680000Y220517D02*
X677500D01*
Y221558D01*
X677625Y221892D01*
X677792Y222100D01*
X678125Y222183D01*
X678458Y222100D01*
X678667Y221850D01*
X678792Y221558D01*
Y220517D01*
G01Y221558D02*
X680000Y222183D01*
G01Y224450D02*
X677500D01*
X678000Y223950D01*
G01X680000D02*
Y224950D01*
G01Y227550D02*
X679958Y227842D01*
X679833Y228175D01*
X679625Y228383D01*
X679333Y228467D01*
X679042Y228383D01*
X678792Y228133D01*
X678667Y227758D01*
Y227342D01*
X678583Y227092D01*
X678375Y226883D01*
X678083Y226800D01*
X677792Y226925D01*
X677583Y227217D01*
X677500Y227550D01*
X677583Y227883D01*
X677792Y228175D01*
X678083Y228300D01*
X678375Y228217D01*
X678583Y228008D01*
X678667Y227758D01*
Y227342D01*
X678792Y226967D01*
X679042Y226717D01*
X679333Y226633D01*
X679625Y226717D01*
X679833Y226925D01*
X679958Y227258D01*
X680000Y227550D01*
G01Y230650D02*
X677500D01*
X678000Y230150D01*
G01X680000D02*
Y231150D01*
G01X668000Y220517D02*
X665500D01*
Y221558D01*
X665625Y221892D01*
X665792Y222100D01*
X666125Y222183D01*
X666458Y222100D01*
X666667Y221850D01*
X666792Y221558D01*
Y220517D01*
G01Y221558D02*
X668000Y222183D01*
G01Y224450D02*
X665500D01*
X666000Y223950D01*
G01X668000D02*
Y224950D01*
G01Y227550D02*
X667958Y227842D01*
X667833Y228175D01*
X667625Y228383D01*
X667333Y228467D01*
X667042Y228383D01*
X666792Y228133D01*
X666667Y227758D01*
Y227342D01*
X666583Y227092D01*
X666375Y226883D01*
X666083Y226800D01*
X665792Y226925D01*
X665583Y227217D01*
X665500Y227550D01*
X665583Y227883D01*
X665792Y228175D01*
X666083Y228300D01*
X666375Y228217D01*
X666583Y228008D01*
X666667Y227758D01*
Y227342D01*
X666792Y226967D01*
X667042Y226717D01*
X667333Y226633D01*
X667625Y226717D01*
X667833Y226925D01*
X667958Y227258D01*
X668000Y227550D01*
G01X667625Y229733D02*
X667833Y229983D01*
X667958Y230275D01*
X668000Y230650D01*
X667917Y231025D01*
X667750Y231317D01*
X667458Y231525D01*
X667125Y231567D01*
X666792Y231483D01*
X666583Y231275D01*
X666417Y230983D01*
X666375Y230692D01*
X666417Y230400D01*
X666583Y230025D01*
X665500Y230150D01*
Y231275D01*
G01X670000Y241500D02*
Y233000D01*
X681500D01*
Y229500D01*
G01X671467Y234000D02*
Y236500D01*
X672467D01*
X672800Y236375D01*
X673050Y236083D01*
X673133Y235750D01*
X673050Y235417D01*
X672842Y235167D01*
X672467Y235042D01*
X671467D01*
G01X674567Y234000D02*
Y236500D01*
X675608D01*
X675942Y236375D01*
X676150Y236208D01*
X676233Y235875D01*
X676150Y235542D01*
X675900Y235333D01*
X675608Y235208D01*
X674567D01*
G01X675608D02*
X676233Y234000D01*
G01X678500D02*
Y236500D01*
X678000Y236000D01*
G01Y234000D02*
X679000D01*
G01X680683Y234500D02*
X680933Y234208D01*
X681267Y234042D01*
X681642Y234000D01*
X681975Y234042D01*
X682308Y234250D01*
X682517Y234500D01*
X682558Y234750D01*
X682475Y235042D01*
X682183Y235250D01*
X681892Y235333D01*
X681517D01*
G01X681892D02*
X682142Y235458D01*
X682350Y235667D01*
X682433Y235917D01*
X682350Y236167D01*
X682142Y236375D01*
X681767Y236500D01*
X681392Y236458D01*
X681017Y236292D01*
G01X684700Y234000D02*
Y236500D01*
X684200Y236000D01*
G01Y234000D02*
X685200D01*
G01X671467Y238000D02*
Y240500D01*
X672467D01*
X672800Y240375D01*
X673050Y240083D01*
X673133Y239750D01*
X673050Y239417D01*
X672842Y239167D01*
X672467Y239042D01*
X671467D01*
G01X674567Y238000D02*
Y240500D01*
X675608D01*
X675942Y240375D01*
X676150Y240208D01*
X676233Y239875D01*
X676150Y239542D01*
X675900Y239333D01*
X675608Y239208D01*
X674567D01*
G01X675608D02*
X676233Y238000D01*
G01X678500D02*
Y240500D01*
X678000Y240000D01*
G01Y238000D02*
X679000D01*
G01X680808Y240083D02*
X681058Y240333D01*
X681350Y240458D01*
X681683Y240500D01*
X682100Y240417D01*
X682392Y240208D01*
X682475Y239958D01*
X682433Y239708D01*
X682267Y239500D01*
X681433Y239083D01*
X681058Y238792D01*
X680808Y238375D01*
X680725Y238000D01*
X682475D01*
G01X683908Y239042D02*
X684200Y239333D01*
X684450Y239500D01*
X684783Y239583D01*
X685075Y239500D01*
X685283Y239333D01*
X685450Y239083D01*
X685492Y238792D01*
X685450Y238542D01*
X685283Y238292D01*
X685033Y238083D01*
X684742Y238000D01*
X684408Y238083D01*
X684117Y238333D01*
X683950Y238708D01*
X683908Y239125D01*
X683992Y239667D01*
X684117Y239958D01*
X684325Y240250D01*
X684617Y240458D01*
X684908Y240500D01*
X685200Y240417D01*
X685408Y240208D01*
G01X693000Y58467D02*
X690500D01*
Y59467D01*
X690625Y59800D01*
X690917Y60050D01*
X691250Y60133D01*
X691583Y60050D01*
X691833Y59842D01*
X691958Y59467D01*
Y58467D01*
G01X690708Y63317D02*
X690583Y63067D01*
X690500Y62775D01*
Y62442D01*
X690625Y62067D01*
X690833Y61775D01*
X691083Y61567D01*
X691500Y61400D01*
X691875Y61358D01*
X692250Y61442D01*
X692500Y61567D01*
X692750Y61817D01*
X692917Y62108D01*
X693000Y62400D01*
Y62692D01*
X692917Y62983D01*
X692792Y63233D01*
X692625Y63442D01*
G01X693000Y65500D02*
X690500D01*
X691000Y65000D01*
G01X693000D02*
Y66000D01*
G01X692708Y67892D02*
X692917Y68183D01*
X693000Y68517D01*
X692917Y68850D01*
X692667Y69142D01*
X692292Y69350D01*
X691917Y69433D01*
X691458D01*
X691083Y69350D01*
X690750Y69142D01*
X690583Y68892D01*
X690500Y68600D01*
X690583Y68267D01*
X690750Y68017D01*
X691000Y67850D01*
X691333Y67767D01*
X691625Y67850D01*
X691917Y68058D01*
X692083Y68308D01*
X692125Y68600D01*
X692042Y68933D01*
X691833Y69183D01*
X691458Y69433D01*
G01X693000Y71700D02*
X690500D01*
X691000Y71200D01*
G01X693000D02*
Y72200D01*
G01X686467Y48000D02*
Y50500D01*
X687467D01*
X687800Y50375D01*
X688050Y50083D01*
X688133Y49750D01*
X688050Y49417D01*
X687842Y49167D01*
X687467Y49042D01*
X686467D01*
G01X691317Y50292D02*
X691067Y50417D01*
X690775Y50500D01*
X690442D01*
X690067Y50375D01*
X689775Y50167D01*
X689567Y49917D01*
X689400Y49500D01*
X689358Y49125D01*
X689442Y48750D01*
X689567Y48500D01*
X689817Y48250D01*
X690108Y48083D01*
X690400Y48000D01*
X690692D01*
X690983Y48083D01*
X691233Y48208D01*
X691442Y48375D01*
G01X693500Y48000D02*
Y50500D01*
X693000Y50000D01*
G01Y48000D02*
X694000D01*
G01X696600D02*
Y50500D01*
X696100Y50000D01*
G01Y48000D02*
X697100D01*
G01X699617D02*
X699700Y48542D01*
X699825Y49000D01*
X699992Y49417D01*
X700200Y49875D01*
X700533Y50500D01*
X698867D01*
G01X681708Y46274D02*
X681583Y46024D01*
X681500Y45732D01*
Y45399D01*
X681625Y45024D01*
X681833Y44732D01*
X682083Y44524D01*
X682500Y44357D01*
X682875Y44315D01*
X683250Y44399D01*
X683500Y44524D01*
X683750Y44774D01*
X683917Y45065D01*
X684000Y45357D01*
Y45649D01*
X683917Y45940D01*
X683792Y46190D01*
X683625Y46399D01*
G01X683500Y47540D02*
X683792Y47790D01*
X683958Y48124D01*
X684000Y48499D01*
X683958Y48832D01*
X683750Y49165D01*
X683500Y49374D01*
X683250Y49415D01*
X682958Y49332D01*
X682750Y49040D01*
X682667Y48749D01*
Y48374D01*
G01Y48749D02*
X682542Y48999D01*
X682333Y49207D01*
X682083Y49290D01*
X681833Y49207D01*
X681625Y48999D01*
X681500Y48624D01*
X681542Y48249D01*
X681708Y47874D01*
G01X681500Y51557D02*
X681583Y51224D01*
X681792Y50974D01*
X682042Y50807D01*
X682375Y50682D01*
X682750Y50640D01*
X683125Y50682D01*
X683458Y50807D01*
X683708Y50974D01*
X683917Y51224D01*
X684000Y51557D01*
X683917Y51890D01*
X683708Y52140D01*
X683458Y52307D01*
X683125Y52432D01*
X682750Y52474D01*
X682375Y52432D01*
X682042Y52307D01*
X681792Y52140D01*
X681583Y51890D01*
X681500Y51557D01*
G01Y54657D02*
X681583Y54324D01*
X681792Y54074D01*
X682042Y53907D01*
X682375Y53782D01*
X682750Y53740D01*
X683125Y53782D01*
X683458Y53907D01*
X683708Y54074D01*
X683917Y54324D01*
X684000Y54657D01*
X683917Y54990D01*
X683708Y55240D01*
X683458Y55407D01*
X683125Y55532D01*
X682750Y55574D01*
X682375Y55532D01*
X682042Y55407D01*
X681792Y55240D01*
X681583Y54990D01*
X681500Y54657D01*
G01X692000Y73967D02*
X689500D01*
Y74967D01*
X689625Y75300D01*
X689917Y75550D01*
X690250Y75633D01*
X690583Y75550D01*
X690833Y75342D01*
X690958Y74967D01*
Y73967D01*
G01X692000Y77067D02*
X689500D01*
Y78108D01*
X689625Y78442D01*
X689792Y78650D01*
X690125Y78733D01*
X690458Y78650D01*
X690667Y78400D01*
X690792Y78108D01*
Y77067D01*
G01Y78108D02*
X692000Y78733D01*
G01X689917Y80208D02*
X689667Y80458D01*
X689542Y80750D01*
X689500Y81083D01*
X689583Y81500D01*
X689792Y81792D01*
X690042Y81875D01*
X690292Y81833D01*
X690500Y81667D01*
X690917Y80833D01*
X691208Y80458D01*
X691625Y80208D01*
X692000Y80125D01*
Y81875D01*
G01Y84100D02*
X689500D01*
X690000Y83600D01*
G01X692000D02*
Y84600D01*
G01Y87200D02*
X689500D01*
X690000Y86700D01*
G01X692000D02*
Y87700D01*
G01X696000Y73967D02*
X693500D01*
Y74967D01*
X693625Y75300D01*
X693917Y75550D01*
X694250Y75633D01*
X694583Y75550D01*
X694833Y75342D01*
X694958Y74967D01*
Y73967D01*
G01X693708Y78817D02*
X693583Y78567D01*
X693500Y78275D01*
Y77942D01*
X693625Y77567D01*
X693833Y77275D01*
X694083Y77067D01*
X694500Y76900D01*
X694875Y76858D01*
X695250Y76942D01*
X695500Y77067D01*
X695750Y77317D01*
X695917Y77608D01*
X696000Y77900D01*
Y78192D01*
X695917Y78483D01*
X695792Y78733D01*
X695625Y78942D01*
G01X696000Y81000D02*
X693500D01*
X694000Y80500D01*
G01X696000D02*
Y81500D01*
G01X693500Y84100D02*
X693583Y83767D01*
X693792Y83517D01*
X694042Y83350D01*
X694375Y83225D01*
X694750Y83183D01*
X695125Y83225D01*
X695458Y83350D01*
X695708Y83517D01*
X695917Y83767D01*
X696000Y84100D01*
X695917Y84433D01*
X695708Y84683D01*
X695458Y84850D01*
X695125Y84975D01*
X694750Y85017D01*
X694375Y84975D01*
X694042Y84850D01*
X693792Y84683D01*
X693583Y84433D01*
X693500Y84100D01*
G01X694958Y86408D02*
X694667Y86700D01*
X694500Y86950D01*
X694417Y87283D01*
X694500Y87575D01*
X694667Y87783D01*
X694917Y87950D01*
X695208Y87992D01*
X695458Y87950D01*
X695708Y87783D01*
X695917Y87533D01*
X696000Y87242D01*
X695917Y86908D01*
X695667Y86617D01*
X695292Y86450D01*
X694875Y86408D01*
X694333Y86492D01*
X694042Y86617D01*
X693750Y86825D01*
X693542Y87117D01*
X693500Y87408D01*
X693583Y87700D01*
X693792Y87908D01*
G01X683500Y68867D02*
X681000D01*
Y69867D01*
X681125Y70200D01*
X681417Y70450D01*
X681750Y70533D01*
X682083Y70450D01*
X682333Y70242D01*
X682458Y69867D01*
Y68867D01*
G01X683500Y71967D02*
X681000D01*
Y73008D01*
X681125Y73342D01*
X681292Y73550D01*
X681625Y73633D01*
X681958Y73550D01*
X682167Y73300D01*
X682292Y73008D01*
Y71967D01*
G01Y73008D02*
X683500Y73633D01*
G01Y75900D02*
X681000D01*
X681500Y75400D01*
G01X683500D02*
Y76400D01*
G01X682458Y78208D02*
X682167Y78500D01*
X682000Y78750D01*
X681917Y79083D01*
X682000Y79375D01*
X682167Y79583D01*
X682417Y79750D01*
X682708Y79792D01*
X682958Y79750D01*
X683208Y79583D01*
X683417Y79333D01*
X683500Y79042D01*
X683417Y78708D01*
X683167Y78417D01*
X682792Y78250D01*
X682375Y78208D01*
X681833Y78292D01*
X681542Y78417D01*
X681250Y78625D01*
X681042Y78917D01*
X681000Y79208D01*
X681083Y79500D01*
X681292Y79708D01*
G01X681000Y82100D02*
X681083Y81767D01*
X681292Y81517D01*
X681542Y81350D01*
X681875Y81225D01*
X682250Y81183D01*
X682625Y81225D01*
X682958Y81350D01*
X683208Y81517D01*
X683417Y81767D01*
X683500Y82100D01*
X683417Y82433D01*
X683208Y82683D01*
X682958Y82850D01*
X682625Y82975D01*
X682250Y83017D01*
X681875Y82975D01*
X681542Y82850D01*
X681292Y82683D01*
X681083Y82433D01*
X681000Y82100D01*
G01X687500Y69467D02*
X685000D01*
Y70467D01*
X685125Y70800D01*
X685417Y71050D01*
X685750Y71133D01*
X686083Y71050D01*
X686333Y70842D01*
X686458Y70467D01*
Y69467D01*
G01X687500Y72567D02*
X685000D01*
Y73608D01*
X685125Y73942D01*
X685292Y74150D01*
X685625Y74233D01*
X685958Y74150D01*
X686167Y73900D01*
X686292Y73608D01*
Y72567D01*
G01Y73608D02*
X687500Y74233D01*
G01Y76500D02*
X685000D01*
X685500Y76000D01*
G01X687500D02*
Y77000D01*
G01X686458Y78808D02*
X686167Y79100D01*
X686000Y79350D01*
X685917Y79683D01*
X686000Y79975D01*
X686167Y80183D01*
X686417Y80350D01*
X686708Y80392D01*
X686958Y80350D01*
X687208Y80183D01*
X687417Y79933D01*
X687500Y79642D01*
X687417Y79308D01*
X687167Y79017D01*
X686792Y78850D01*
X686375Y78808D01*
X685833Y78892D01*
X685542Y79017D01*
X685250Y79225D01*
X685042Y79517D01*
X685000Y79808D01*
X685083Y80100D01*
X685292Y80308D01*
G01X687500Y82700D02*
X685000D01*
X685500Y82200D01*
G01X687500D02*
Y83200D01*
G01X695000Y113067D02*
X692500D01*
Y114067D01*
X692625Y114400D01*
X692917Y114650D01*
X693250Y114733D01*
X693583Y114650D01*
X693833Y114442D01*
X693958Y114067D01*
Y113067D01*
G01X692500Y116083D02*
X694292D01*
X694667Y116250D01*
X694917Y116583D01*
X695000Y117000D01*
X694917Y117417D01*
X694667Y117750D01*
X694292Y117917D01*
X692500D01*
G01X694708Y119392D02*
X694917Y119683D01*
X695000Y120017D01*
X694917Y120350D01*
X694667Y120642D01*
X694292Y120850D01*
X693917Y120933D01*
X693458D01*
X693083Y120850D01*
X692750Y120642D01*
X692583Y120392D01*
X692500Y120100D01*
X692583Y119767D01*
X692750Y119517D01*
X693000Y119350D01*
X693333Y119267D01*
X693625Y119350D01*
X693917Y119558D01*
X694083Y119808D01*
X694125Y120100D01*
X694042Y120433D01*
X693833Y120683D01*
X693458Y120933D01*
G01X693967Y150900D02*
Y153400D01*
X695008D01*
X695342Y153275D01*
X695550Y153108D01*
X695633Y152775D01*
X695550Y152442D01*
X695300Y152233D01*
X695008Y152108D01*
X693967D01*
G01X695008D02*
X695633Y150900D01*
G01X697192Y151192D02*
X697483Y150983D01*
X697817Y150900D01*
X698150Y150983D01*
X698442Y151233D01*
X698650Y151608D01*
X698733Y151983D01*
Y152442D01*
X698650Y152817D01*
X698442Y153150D01*
X698192Y153317D01*
X697900Y153400D01*
X697567Y153317D01*
X697317Y153150D01*
X697150Y152900D01*
X697067Y152567D01*
X697150Y152275D01*
X697358Y151983D01*
X697608Y151817D01*
X697900Y151775D01*
X698233Y151858D01*
X698483Y152067D01*
X698733Y152442D01*
G01X701000Y153400D02*
X700667Y153317D01*
X700417Y153108D01*
X700250Y152858D01*
X700125Y152525D01*
X700083Y152150D01*
X700125Y151775D01*
X700250Y151442D01*
X700417Y151192D01*
X700667Y150983D01*
X701000Y150900D01*
X701333Y150983D01*
X701583Y151192D01*
X701750Y151442D01*
X701875Y151775D01*
X701917Y152150D01*
X701875Y152525D01*
X701750Y152858D01*
X701583Y153108D01*
X701333Y153317D01*
X701000Y153400D01*
G01X693917Y143200D02*
Y145700D01*
X694958D01*
X695292Y145575D01*
X695500Y145408D01*
X695583Y145075D01*
X695500Y144742D01*
X695250Y144533D01*
X694958Y144408D01*
X693917D01*
G01X694958D02*
X695583Y143200D01*
G01X697850D02*
Y145700D01*
X697350Y145200D01*
G01Y143200D02*
X698350D01*
G01X701450D02*
Y145700D01*
X699908Y143908D01*
X701992D01*
G01X703133Y143700D02*
X703383Y143408D01*
X703717Y143242D01*
X704092Y143200D01*
X704425Y143242D01*
X704758Y143450D01*
X704967Y143700D01*
X705008Y143950D01*
X704925Y144242D01*
X704633Y144450D01*
X704342Y144533D01*
X703967D01*
G01X704342D02*
X704592Y144658D01*
X704800Y144867D01*
X704883Y145117D01*
X704800Y145367D01*
X704592Y145575D01*
X704217Y145700D01*
X703842Y145658D01*
X703467Y145492D01*
G01X693867Y146900D02*
Y149400D01*
X694867D01*
X695200Y149275D01*
X695450Y148983D01*
X695533Y148650D01*
X695450Y148317D01*
X695242Y148067D01*
X694867Y147942D01*
X693867D01*
G01X696967Y146900D02*
Y149400D01*
X698008D01*
X698342Y149275D01*
X698550Y149108D01*
X698633Y148775D01*
X698550Y148442D01*
X698300Y148233D01*
X698008Y148108D01*
X696967D01*
G01X698008D02*
X698633Y146900D01*
G01X700900D02*
Y149400D01*
X700400Y148900D01*
G01Y146900D02*
X701400D01*
G01X703083Y147400D02*
X703333Y147108D01*
X703667Y146942D01*
X704042Y146900D01*
X704375Y146942D01*
X704708Y147150D01*
X704917Y147400D01*
X704958Y147650D01*
X704875Y147942D01*
X704583Y148150D01*
X704292Y148233D01*
X703917D01*
G01X704292D02*
X704542Y148358D01*
X704750Y148567D01*
X704833Y148817D01*
X704750Y149067D01*
X704542Y149275D01*
X704167Y149400D01*
X703792Y149358D01*
X703417Y149192D01*
G01X707100Y149400D02*
X706767Y149317D01*
X706517Y149108D01*
X706350Y148858D01*
X706225Y148525D01*
X706183Y148150D01*
X706225Y147775D01*
X706350Y147442D01*
X706517Y147192D01*
X706767Y146983D01*
X707100Y146900D01*
X707433Y146983D01*
X707683Y147192D01*
X707850Y147442D01*
X707975Y147775D01*
X708017Y148150D01*
X707975Y148525D01*
X707850Y148858D01*
X707683Y149108D01*
X707433Y149317D01*
X707100Y149400D01*
G01X689467Y155500D02*
Y158000D01*
X690467D01*
X690800Y157875D01*
X691050Y157583D01*
X691133Y157250D01*
X691050Y156917D01*
X690842Y156667D01*
X690467Y156542D01*
X689467D01*
G01X692567Y155500D02*
Y158000D01*
X693608D01*
X693942Y157875D01*
X694150Y157708D01*
X694233Y157375D01*
X694150Y157042D01*
X693900Y156833D01*
X693608Y156708D01*
X692567D01*
G01X693608D02*
X694233Y155500D01*
G01X695708Y157583D02*
X695958Y157833D01*
X696250Y157958D01*
X696583Y158000D01*
X697000Y157917D01*
X697292Y157708D01*
X697375Y157458D01*
X697333Y157208D01*
X697167Y157000D01*
X696333Y156583D01*
X695958Y156292D01*
X695708Y155875D01*
X695625Y155500D01*
X697375D01*
G01X698808Y157583D02*
X699058Y157833D01*
X699350Y157958D01*
X699683Y158000D01*
X700100Y157917D01*
X700392Y157708D01*
X700475Y157458D01*
X700433Y157208D01*
X700267Y157000D01*
X699433Y156583D01*
X699058Y156292D01*
X698808Y155875D01*
X698725Y155500D01*
X700475D01*
G01X701908Y156542D02*
X702200Y156833D01*
X702450Y157000D01*
X702783Y157083D01*
X703075Y157000D01*
X703283Y156833D01*
X703450Y156583D01*
X703492Y156292D01*
X703450Y156042D01*
X703283Y155792D01*
X703033Y155583D01*
X702742Y155500D01*
X702408Y155583D01*
X702117Y155833D01*
X701950Y156208D01*
X701908Y156625D01*
X701992Y157167D01*
X702117Y157458D01*
X702325Y157750D01*
X702617Y157958D01*
X702908Y158000D01*
X703200Y157917D01*
X703408Y157708D01*
G01X689467Y163500D02*
Y166000D01*
X690467D01*
X690800Y165875D01*
X691050Y165583D01*
X691133Y165250D01*
X691050Y164917D01*
X690842Y164667D01*
X690467Y164542D01*
X689467D01*
G01X694317Y165792D02*
X694067Y165917D01*
X693775Y166000D01*
X693442D01*
X693067Y165875D01*
X692775Y165667D01*
X692567Y165417D01*
X692400Y165000D01*
X692358Y164625D01*
X692442Y164250D01*
X692567Y164000D01*
X692817Y163750D01*
X693108Y163583D01*
X693400Y163500D01*
X693692D01*
X693983Y163583D01*
X694233Y163708D01*
X694442Y163875D01*
G01X695708Y165583D02*
X695958Y165833D01*
X696250Y165958D01*
X696583Y166000D01*
X697000Y165917D01*
X697292Y165708D01*
X697375Y165458D01*
X697333Y165208D01*
X697167Y165000D01*
X696333Y164583D01*
X695958Y164292D01*
X695708Y163875D01*
X695625Y163500D01*
X697375D01*
G01X699600D02*
Y166000D01*
X699100Y165500D01*
G01Y163500D02*
X700100D01*
G01X702700Y166000D02*
X702367Y165917D01*
X702117Y165708D01*
X701950Y165458D01*
X701825Y165125D01*
X701783Y164750D01*
X701825Y164375D01*
X701950Y164042D01*
X702117Y163792D01*
X702367Y163583D01*
X702700Y163500D01*
X703033Y163583D01*
X703283Y163792D01*
X703450Y164042D01*
X703575Y164375D01*
X703617Y164750D01*
X703575Y165125D01*
X703450Y165458D01*
X703283Y165708D01*
X703033Y165917D01*
X702700Y166000D01*
G01X689467Y159500D02*
Y162000D01*
X690467D01*
X690800Y161875D01*
X691050Y161583D01*
X691133Y161250D01*
X691050Y160917D01*
X690842Y160667D01*
X690467Y160542D01*
X689467D01*
G01X692567Y159500D02*
Y162000D01*
X693608D01*
X693942Y161875D01*
X694150Y161708D01*
X694233Y161375D01*
X694150Y161042D01*
X693900Y160833D01*
X693608Y160708D01*
X692567D01*
G01X693608D02*
X694233Y159500D01*
G01X695708Y161583D02*
X695958Y161833D01*
X696250Y161958D01*
X696583Y162000D01*
X697000Y161917D01*
X697292Y161708D01*
X697375Y161458D01*
X697333Y161208D01*
X697167Y161000D01*
X696333Y160583D01*
X695958Y160292D01*
X695708Y159875D01*
X695625Y159500D01*
X697375D01*
G01X698808Y161583D02*
X699058Y161833D01*
X699350Y161958D01*
X699683Y162000D01*
X700100Y161917D01*
X700392Y161708D01*
X700475Y161458D01*
X700433Y161208D01*
X700267Y161000D01*
X699433Y160583D01*
X699058Y160292D01*
X698808Y159875D01*
X698725Y159500D01*
X700475D01*
G01X702617D02*
X702700Y160042D01*
X702825Y160500D01*
X702992Y160917D01*
X703200Y161375D01*
X703533Y162000D01*
X701867D01*
G01X689467Y167500D02*
Y170000D01*
X690467D01*
X690800Y169875D01*
X691050Y169583D01*
X691133Y169250D01*
X691050Y168917D01*
X690842Y168667D01*
X690467Y168542D01*
X689467D01*
G01X692567Y167500D02*
Y170000D01*
X693608D01*
X693942Y169875D01*
X694150Y169708D01*
X694233Y169375D01*
X694150Y169042D01*
X693900Y168833D01*
X693608Y168708D01*
X692567D01*
G01X693608D02*
X694233Y167500D01*
G01X695708Y169583D02*
X695958Y169833D01*
X696250Y169958D01*
X696583Y170000D01*
X697000Y169917D01*
X697292Y169708D01*
X697375Y169458D01*
X697333Y169208D01*
X697167Y169000D01*
X696333Y168583D01*
X695958Y168292D01*
X695708Y167875D01*
X695625Y167500D01*
X697375D01*
G01X698808Y169583D02*
X699058Y169833D01*
X699350Y169958D01*
X699683Y170000D01*
X700100Y169917D01*
X700392Y169708D01*
X700475Y169458D01*
X700433Y169208D01*
X700267Y169000D01*
X699433Y168583D01*
X699058Y168292D01*
X698808Y167875D01*
X698725Y167500D01*
X700475D01*
G01X702700D02*
X702992Y167542D01*
X703325Y167667D01*
X703533Y167875D01*
X703617Y168167D01*
X703533Y168458D01*
X703283Y168708D01*
X702908Y168833D01*
X702492D01*
X702242Y168917D01*
X702033Y169125D01*
X701950Y169417D01*
X702075Y169708D01*
X702367Y169917D01*
X702700Y170000D01*
X703033Y169917D01*
X703325Y169708D01*
X703450Y169417D01*
X703367Y169125D01*
X703158Y168917D01*
X702908Y168833D01*
X702492D01*
X702117Y168708D01*
X701867Y168458D01*
X701783Y168167D01*
X701867Y167875D01*
X702075Y167667D01*
X702408Y167542D01*
X702700Y167500D01*
G01X689467Y171500D02*
Y174000D01*
X690467D01*
X690800Y173875D01*
X691050Y173583D01*
X691133Y173250D01*
X691050Y172917D01*
X690842Y172667D01*
X690467Y172542D01*
X689467D01*
G01X694317Y173792D02*
X694067Y173917D01*
X693775Y174000D01*
X693442D01*
X693067Y173875D01*
X692775Y173667D01*
X692567Y173417D01*
X692400Y173000D01*
X692358Y172625D01*
X692442Y172250D01*
X692567Y172000D01*
X692817Y171750D01*
X693108Y171583D01*
X693400Y171500D01*
X693692D01*
X693983Y171583D01*
X694233Y171708D01*
X694442Y171875D01*
G01X695708Y173583D02*
X695958Y173833D01*
X696250Y173958D01*
X696583Y174000D01*
X697000Y173917D01*
X697292Y173708D01*
X697375Y173458D01*
X697333Y173208D01*
X697167Y173000D01*
X696333Y172583D01*
X695958Y172292D01*
X695708Y171875D01*
X695625Y171500D01*
X697375D01*
G01X699600D02*
Y174000D01*
X699100Y173500D01*
G01Y171500D02*
X700100D01*
G01X702700D02*
Y174000D01*
X702200Y173500D01*
G01Y171500D02*
X703200D01*
G01X699550Y198350D02*
Y209650D01*
X680550D01*
Y198350D01*
X699550D01*
G01X694250Y235000D02*
Y240000D01*
G01X690750D02*
Y235000D01*
G01Y237500D02*
X694250D01*
G01X693500Y230000D02*
X698500D01*
G01X683567D02*
Y232500D01*
X684608D01*
X684942Y232375D01*
X685150Y232208D01*
X685233Y231875D01*
X685150Y231542D01*
X684900Y231333D01*
X684608Y231208D01*
X683567D01*
G01X684608D02*
X685233Y230000D01*
G01X686792Y230292D02*
X687083Y230083D01*
X687417Y230000D01*
X687750Y230083D01*
X688042Y230333D01*
X688250Y230708D01*
X688333Y231083D01*
Y231542D01*
X688250Y231917D01*
X688042Y232250D01*
X687792Y232417D01*
X687500Y232500D01*
X687167Y232417D01*
X686917Y232250D01*
X686750Y232000D01*
X686667Y231667D01*
X686750Y231375D01*
X686958Y231083D01*
X687208Y230917D01*
X687500Y230875D01*
X687833Y230958D01*
X688083Y231167D01*
X688333Y231542D01*
G01X689808Y231042D02*
X690100Y231333D01*
X690350Y231500D01*
X690683Y231583D01*
X690975Y231500D01*
X691183Y231333D01*
X691350Y231083D01*
X691392Y230792D01*
X691350Y230542D01*
X691183Y230292D01*
X690933Y230083D01*
X690642Y230000D01*
X690308Y230083D01*
X690017Y230333D01*
X689850Y230708D01*
X689808Y231125D01*
X689892Y231667D01*
X690017Y231958D01*
X690225Y232250D01*
X690517Y232458D01*
X690808Y232500D01*
X691100Y232417D01*
X691308Y232208D01*
G01X708000Y51967D02*
X705500D01*
Y52967D01*
X705625Y53300D01*
X705917Y53550D01*
X706250Y53633D01*
X706583Y53550D01*
X706833Y53342D01*
X706958Y52967D01*
Y51967D01*
G01X705708Y56817D02*
X705583Y56567D01*
X705500Y56275D01*
Y55942D01*
X705625Y55567D01*
X705833Y55275D01*
X706083Y55067D01*
X706500Y54900D01*
X706875Y54858D01*
X707250Y54942D01*
X707500Y55067D01*
X707750Y55317D01*
X707917Y55608D01*
X708000Y55900D01*
Y56192D01*
X707917Y56483D01*
X707792Y56733D01*
X707625Y56942D01*
G01X708000Y59000D02*
X705500D01*
X706000Y58500D01*
G01X708000D02*
Y59500D01*
G01Y62100D02*
X705500D01*
X706000Y61600D01*
G01X708000D02*
Y62600D01*
G01X707625Y64283D02*
X707833Y64533D01*
X707958Y64825D01*
X708000Y65200D01*
X707917Y65575D01*
X707750Y65867D01*
X707458Y66075D01*
X707125Y66117D01*
X706792Y66033D01*
X706583Y65825D01*
X706417Y65533D01*
X706375Y65242D01*
X706417Y64950D01*
X706583Y64575D01*
X705500Y64700D01*
Y65825D01*
G01X702467Y48000D02*
Y50500D01*
X703467D01*
X703800Y50375D01*
X704050Y50083D01*
X704133Y49750D01*
X704050Y49417D01*
X703842Y49167D01*
X703467Y49042D01*
X702467D01*
G01X707317Y50292D02*
X707067Y50417D01*
X706775Y50500D01*
X706442D01*
X706067Y50375D01*
X705775Y50167D01*
X705567Y49917D01*
X705400Y49500D01*
X705358Y49125D01*
X705442Y48750D01*
X705567Y48500D01*
X705817Y48250D01*
X706108Y48083D01*
X706400Y48000D01*
X706692D01*
X706983Y48083D01*
X707233Y48208D01*
X707442Y48375D01*
G01X708708Y50083D02*
X708958Y50333D01*
X709250Y50458D01*
X709583Y50500D01*
X710000Y50417D01*
X710292Y50208D01*
X710375Y49958D01*
X710333Y49708D01*
X710167Y49500D01*
X709333Y49083D01*
X708958Y48792D01*
X708708Y48375D01*
X708625Y48000D01*
X710375D01*
G01X712600Y50500D02*
X712267Y50417D01*
X712017Y50208D01*
X711850Y49958D01*
X711725Y49625D01*
X711683Y49250D01*
X711725Y48875D01*
X711850Y48542D01*
X712017Y48292D01*
X712267Y48083D01*
X712600Y48000D01*
X712933Y48083D01*
X713183Y48292D01*
X713350Y48542D01*
X713475Y48875D01*
X713517Y49250D01*
X713475Y49625D01*
X713350Y49958D01*
X713183Y50208D01*
X712933Y50417D01*
X712600Y50500D01*
G01X715700Y48000D02*
X715992Y48042D01*
X716325Y48167D01*
X716533Y48375D01*
X716617Y48667D01*
X716533Y48958D01*
X716283Y49208D01*
X715908Y49333D01*
X715492D01*
X715242Y49417D01*
X715033Y49625D01*
X714950Y49917D01*
X715075Y50208D01*
X715367Y50417D01*
X715700Y50500D01*
X716033Y50417D01*
X716325Y50208D01*
X716450Y49917D01*
X716367Y49625D01*
X716158Y49417D01*
X715908Y49333D01*
X715492D01*
X715117Y49208D01*
X714867Y48958D01*
X714783Y48667D01*
X714867Y48375D01*
X715075Y48167D01*
X715408Y48042D01*
X715700Y48000D01*
G01X700000Y51967D02*
X697500D01*
Y52967D01*
X697625Y53300D01*
X697917Y53550D01*
X698250Y53633D01*
X698583Y53550D01*
X698833Y53342D01*
X698958Y52967D01*
Y51967D01*
G01X700000Y55067D02*
X697500D01*
Y56108D01*
X697625Y56442D01*
X697792Y56650D01*
X698125Y56733D01*
X698458Y56650D01*
X698667Y56400D01*
X698792Y56108D01*
Y55067D01*
G01Y56108D02*
X700000Y56733D01*
G01Y59000D02*
X697500D01*
X698000Y58500D01*
G01X700000D02*
Y59500D01*
G01X698958Y61308D02*
X698667Y61600D01*
X698500Y61850D01*
X698417Y62183D01*
X698500Y62475D01*
X698667Y62683D01*
X698917Y62850D01*
X699208Y62892D01*
X699458Y62850D01*
X699708Y62683D01*
X699917Y62433D01*
X700000Y62142D01*
X699917Y61808D01*
X699667Y61517D01*
X699292Y61350D01*
X698875Y61308D01*
X698333Y61392D01*
X698042Y61517D01*
X697750Y61725D01*
X697542Y62017D01*
X697500Y62308D01*
X697583Y62600D01*
X697792Y62808D01*
G01X699708Y64492D02*
X699917Y64783D01*
X700000Y65117D01*
X699917Y65450D01*
X699667Y65742D01*
X699292Y65950D01*
X698917Y66033D01*
X698458D01*
X698083Y65950D01*
X697750Y65742D01*
X697583Y65492D01*
X697500Y65200D01*
X697583Y64867D01*
X697750Y64617D01*
X698000Y64450D01*
X698333Y64367D01*
X698625Y64450D01*
X698917Y64658D01*
X699083Y64908D01*
X699125Y65200D01*
X699042Y65533D01*
X698833Y65783D01*
X698458Y66033D01*
G01X704000Y52467D02*
X701500D01*
Y53467D01*
X701625Y53800D01*
X701917Y54050D01*
X702250Y54133D01*
X702583Y54050D01*
X702833Y53842D01*
X702958Y53467D01*
Y52467D01*
G01X704000Y55567D02*
X701500D01*
Y56608D01*
X701625Y56942D01*
X701792Y57150D01*
X702125Y57233D01*
X702458Y57150D01*
X702667Y56900D01*
X702792Y56608D01*
Y55567D01*
G01Y56608D02*
X704000Y57233D01*
G01Y59500D02*
X701500D01*
X702000Y59000D01*
G01X704000D02*
Y60000D01*
G01X702958Y61808D02*
X702667Y62100D01*
X702500Y62350D01*
X702417Y62683D01*
X702500Y62975D01*
X702667Y63183D01*
X702917Y63350D01*
X703208Y63392D01*
X703458Y63350D01*
X703708Y63183D01*
X703917Y62933D01*
X704000Y62642D01*
X703917Y62308D01*
X703667Y62017D01*
X703292Y61850D01*
X702875Y61808D01*
X702333Y61892D01*
X702042Y62017D01*
X701750Y62225D01*
X701542Y62517D01*
X701500Y62808D01*
X701583Y63100D01*
X701792Y63308D01*
G01X704000Y65700D02*
X703958Y65992D01*
X703833Y66325D01*
X703625Y66533D01*
X703333Y66617D01*
X703042Y66533D01*
X702792Y66283D01*
X702667Y65908D01*
Y65492D01*
X702583Y65242D01*
X702375Y65033D01*
X702083Y64950D01*
X701792Y65075D01*
X701583Y65367D01*
X701500Y65700D01*
X701583Y66033D01*
X701792Y66325D01*
X702083Y66450D01*
X702375Y66367D01*
X702583Y66158D01*
X702667Y65908D01*
Y65492D01*
X702792Y65117D01*
X703042Y64867D01*
X703333Y64783D01*
X703625Y64867D01*
X703833Y65075D01*
X703958Y65408D01*
X704000Y65700D01*
G01X702800Y73000D02*
X705467D01*
Y70900D01*
X704667Y70200D01*
X703733Y69733D01*
X702400Y69500D01*
X701067Y69733D01*
X700133Y70200D01*
X699333Y70900D01*
X698800Y71717D01*
X698533Y72650D01*
Y73467D01*
X698800Y74167D01*
X699333Y74983D01*
X700133Y75683D01*
X700933Y76150D01*
X702000Y76500D01*
X702933D01*
X704000Y76267D01*
X704800Y75800D01*
G01X719300Y82000D02*
X702000D01*
Y90200D01*
X715800D01*
Y93300D01*
X725700D01*
G01X704117Y86600D02*
Y89100D01*
X705117D01*
X705450Y88975D01*
X705700Y88683D01*
X705783Y88350D01*
X705700Y88017D01*
X705492Y87767D01*
X705117Y87642D01*
X704117D01*
G01X707217Y86600D02*
Y89100D01*
X708258D01*
X708592Y88975D01*
X708800Y88808D01*
X708883Y88475D01*
X708800Y88142D01*
X708550Y87933D01*
X708258Y87808D01*
X707217D01*
G01X708258D02*
X708883Y86600D01*
G01X710358Y87642D02*
X710650Y87933D01*
X710900Y88100D01*
X711233Y88183D01*
X711525Y88100D01*
X711733Y87933D01*
X711900Y87683D01*
X711942Y87392D01*
X711900Y87142D01*
X711733Y86892D01*
X711483Y86683D01*
X711192Y86600D01*
X710858Y86683D01*
X710567Y86933D01*
X710400Y87308D01*
X710358Y87725D01*
X710442Y88267D01*
X710567Y88558D01*
X710775Y88850D01*
X711067Y89058D01*
X711358Y89100D01*
X711650Y89017D01*
X711858Y88808D01*
G01X714250Y89100D02*
X713917Y89017D01*
X713667Y88808D01*
X713500Y88558D01*
X713375Y88225D01*
X713333Y87850D01*
X713375Y87475D01*
X713500Y87142D01*
X713667Y86892D01*
X713917Y86683D01*
X714250Y86600D01*
X714583Y86683D01*
X714833Y86892D01*
X715000Y87142D01*
X715125Y87475D01*
X715167Y87850D01*
X715125Y88225D01*
X715000Y88558D01*
X714833Y88808D01*
X714583Y89017D01*
X714250Y89100D01*
G01X704117Y83000D02*
Y85500D01*
X705117D01*
X705450Y85375D01*
X705700Y85083D01*
X705783Y84750D01*
X705700Y84417D01*
X705492Y84167D01*
X705117Y84042D01*
X704117D01*
G01X708967Y85292D02*
X708717Y85417D01*
X708425Y85500D01*
X708092D01*
X707717Y85375D01*
X707425Y85167D01*
X707217Y84917D01*
X707050Y84500D01*
X707008Y84125D01*
X707092Y83750D01*
X707217Y83500D01*
X707467Y83250D01*
X707758Y83083D01*
X708050Y83000D01*
X708342D01*
X708633Y83083D01*
X708883Y83208D01*
X709092Y83375D01*
G01X711650Y83000D02*
Y85500D01*
X710108Y83708D01*
X712192D01*
G01X714250Y83000D02*
Y85500D01*
X713750Y85000D01*
G01Y83000D02*
X714750D01*
G01X699767Y95400D02*
Y97900D01*
X700767D01*
X701100Y97775D01*
X701350Y97483D01*
X701433Y97150D01*
X701350Y96817D01*
X701142Y96567D01*
X700767Y96442D01*
X699767D01*
G01X704617Y97692D02*
X704367Y97817D01*
X704075Y97900D01*
X703742D01*
X703367Y97775D01*
X703075Y97567D01*
X702867Y97317D01*
X702700Y96900D01*
X702658Y96525D01*
X702742Y96150D01*
X702867Y95900D01*
X703117Y95650D01*
X703408Y95483D01*
X703700Y95400D01*
X703992D01*
X704283Y95483D01*
X704533Y95608D01*
X704742Y95775D01*
G01X706800Y95400D02*
Y97900D01*
X706300Y97400D01*
G01Y95400D02*
X707300D01*
G01X709900Y97900D02*
X709567Y97817D01*
X709317Y97608D01*
X709150Y97358D01*
X709025Y97025D01*
X708983Y96650D01*
X709025Y96275D01*
X709150Y95942D01*
X709317Y95692D01*
X709567Y95483D01*
X709900Y95400D01*
X710233Y95483D01*
X710483Y95692D01*
X710650Y95942D01*
X710775Y96275D01*
X710817Y96650D01*
X710775Y97025D01*
X710650Y97358D01*
X710483Y97608D01*
X710233Y97817D01*
X709900Y97900D01*
G01X712083Y95775D02*
X712333Y95567D01*
X712625Y95442D01*
X713000Y95400D01*
X713375Y95483D01*
X713667Y95650D01*
X713875Y95942D01*
X713917Y96275D01*
X713833Y96608D01*
X713625Y96817D01*
X713333Y96983D01*
X713042Y97025D01*
X712750Y96983D01*
X712375Y96817D01*
X712500Y97900D01*
X713625D01*
G01X699767Y91400D02*
Y93900D01*
X700767D01*
X701100Y93775D01*
X701350Y93483D01*
X701433Y93150D01*
X701350Y92817D01*
X701142Y92567D01*
X700767Y92442D01*
X699767D01*
G01X704617Y93692D02*
X704367Y93817D01*
X704075Y93900D01*
X703742D01*
X703367Y93775D01*
X703075Y93567D01*
X702867Y93317D01*
X702700Y92900D01*
X702658Y92525D01*
X702742Y92150D01*
X702867Y91900D01*
X703117Y91650D01*
X703408Y91483D01*
X703700Y91400D01*
X703992D01*
X704283Y91483D01*
X704533Y91608D01*
X704742Y91775D01*
G01X706800Y91400D02*
Y93900D01*
X706300Y93400D01*
G01Y91400D02*
X707300D01*
G01X709900Y93900D02*
X709567Y93817D01*
X709317Y93608D01*
X709150Y93358D01*
X709025Y93025D01*
X708983Y92650D01*
X709025Y92275D01*
X709150Y91942D01*
X709317Y91692D01*
X709567Y91483D01*
X709900Y91400D01*
X710233Y91483D01*
X710483Y91692D01*
X710650Y91942D01*
X710775Y92275D01*
X710817Y92650D01*
X710775Y93025D01*
X710650Y93358D01*
X710483Y93608D01*
X710233Y93817D01*
X709900Y93900D01*
G01X713000Y91400D02*
X713292Y91442D01*
X713625Y91567D01*
X713833Y91775D01*
X713917Y92067D01*
X713833Y92358D01*
X713583Y92608D01*
X713208Y92733D01*
X712792D01*
X712542Y92817D01*
X712333Y93025D01*
X712250Y93317D01*
X712375Y93608D01*
X712667Y93817D01*
X713000Y93900D01*
X713333Y93817D01*
X713625Y93608D01*
X713750Y93317D01*
X713667Y93025D01*
X713458Y92817D01*
X713208Y92733D01*
X712792D01*
X712417Y92608D01*
X712167Y92358D01*
X712083Y92067D01*
X712167Y91775D01*
X712375Y91567D01*
X712708Y91442D01*
X713000Y91400D01*
G01X711800Y100067D02*
X709300D01*
Y101067D01*
X709425Y101400D01*
X709717Y101650D01*
X710050Y101733D01*
X710383Y101650D01*
X710633Y101442D01*
X710758Y101067D01*
Y100067D01*
G01X709508Y104917D02*
X709383Y104667D01*
X709300Y104375D01*
Y104042D01*
X709425Y103667D01*
X709633Y103375D01*
X709883Y103167D01*
X710300Y103000D01*
X710675Y102958D01*
X711050Y103042D01*
X711300Y103167D01*
X711550Y103417D01*
X711717Y103708D01*
X711800Y104000D01*
Y104292D01*
X711717Y104583D01*
X711592Y104833D01*
X711425Y105042D01*
G01X711800Y107100D02*
X709300D01*
X709800Y106600D01*
G01X711800D02*
Y107600D01*
G01X709300Y110200D02*
X709383Y109867D01*
X709592Y109617D01*
X709842Y109450D01*
X710175Y109325D01*
X710550Y109283D01*
X710925Y109325D01*
X711258Y109450D01*
X711508Y109617D01*
X711717Y109867D01*
X711800Y110200D01*
X711717Y110533D01*
X711508Y110783D01*
X711258Y110950D01*
X710925Y111075D01*
X710550Y111117D01*
X710175Y111075D01*
X709842Y110950D01*
X709592Y110783D01*
X709383Y110533D01*
X709300Y110200D01*
G01X711300Y112383D02*
X711592Y112633D01*
X711758Y112967D01*
X711800Y113342D01*
X711758Y113675D01*
X711550Y114008D01*
X711300Y114217D01*
X711050Y114258D01*
X710758Y114175D01*
X710550Y113883D01*
X710467Y113592D01*
Y113217D01*
G01Y113592D02*
X710342Y113842D01*
X710133Y114050D01*
X709883Y114133D01*
X709633Y114050D01*
X709425Y113842D01*
X709300Y113467D01*
X709342Y113092D01*
X709508Y112717D01*
G01X707800Y100067D02*
X705300D01*
Y101067D01*
X705425Y101400D01*
X705717Y101650D01*
X706050Y101733D01*
X706383Y101650D01*
X706633Y101442D01*
X706758Y101067D01*
Y100067D01*
G01X707800Y103167D02*
X705300D01*
Y104208D01*
X705425Y104542D01*
X705592Y104750D01*
X705925Y104833D01*
X706258Y104750D01*
X706467Y104500D01*
X706592Y104208D01*
Y103167D01*
G01Y104208D02*
X707800Y104833D01*
G01Y107100D02*
X705300D01*
X705800Y106600D01*
G01X707800D02*
Y107600D01*
G01X707425Y109283D02*
X707633Y109533D01*
X707758Y109825D01*
X707800Y110200D01*
X707717Y110575D01*
X707550Y110867D01*
X707258Y111075D01*
X706925Y111117D01*
X706592Y111033D01*
X706383Y110825D01*
X706217Y110533D01*
X706175Y110242D01*
X706217Y109950D01*
X706383Y109575D01*
X705300Y109700D01*
Y110825D01*
G01Y113300D02*
X705383Y112967D01*
X705592Y112717D01*
X705842Y112550D01*
X706175Y112425D01*
X706550Y112383D01*
X706925Y112425D01*
X707258Y112550D01*
X707508Y112717D01*
X707717Y112967D01*
X707800Y113300D01*
X707717Y113633D01*
X707508Y113883D01*
X707258Y114050D01*
X706925Y114175D01*
X706550Y114217D01*
X706175Y114175D01*
X705842Y114050D01*
X705592Y113883D01*
X705383Y113633D01*
X705300Y113300D01*
G01X703800Y100067D02*
X701300D01*
Y101067D01*
X701425Y101400D01*
X701717Y101650D01*
X702050Y101733D01*
X702383Y101650D01*
X702633Y101442D01*
X702758Y101067D01*
Y100067D01*
G01X703800Y103167D02*
X701300D01*
Y104208D01*
X701425Y104542D01*
X701592Y104750D01*
X701925Y104833D01*
X702258Y104750D01*
X702467Y104500D01*
X702592Y104208D01*
Y103167D01*
G01Y104208D02*
X703800Y104833D01*
G01Y107100D02*
X701300D01*
X701800Y106600D01*
G01X703800D02*
Y107600D01*
G01Y110700D02*
X701300D01*
X703092Y109158D01*
Y111242D01*
G01X703508Y112592D02*
X703717Y112883D01*
X703800Y113217D01*
X703717Y113550D01*
X703467Y113842D01*
X703092Y114050D01*
X702717Y114133D01*
X702258D01*
X701883Y114050D01*
X701550Y113842D01*
X701383Y113592D01*
X701300Y113300D01*
X701383Y112967D01*
X701550Y112717D01*
X701800Y112550D01*
X702133Y112467D01*
X702425Y112550D01*
X702717Y112758D01*
X702883Y113008D01*
X702925Y113300D01*
X702842Y113633D01*
X702633Y113883D01*
X702258Y114133D01*
G01X701767Y115800D02*
Y118300D01*
X702767D01*
X703100Y118175D01*
X703350Y117883D01*
X703433Y117550D01*
X703350Y117217D01*
X703142Y116967D01*
X702767Y116842D01*
X701767D01*
G01X704867Y115800D02*
Y118300D01*
X705908D01*
X706242Y118175D01*
X706450Y118008D01*
X706533Y117675D01*
X706450Y117342D01*
X706200Y117133D01*
X705908Y117008D01*
X704867D01*
G01X705908D02*
X706533Y115800D01*
G01X708800D02*
Y118300D01*
X708300Y117800D01*
G01Y115800D02*
X709300D01*
G01X712400D02*
Y118300D01*
X710858Y116508D01*
X712942D01*
G01X714208Y117883D02*
X714458Y118133D01*
X714750Y118258D01*
X715083Y118300D01*
X715500Y118217D01*
X715792Y118008D01*
X715875Y117758D01*
X715833Y117508D01*
X715667Y117300D01*
X714833Y116883D01*
X714458Y116592D01*
X714208Y116175D01*
X714125Y115800D01*
X715875D01*
G01X700467Y119500D02*
Y122000D01*
X701467D01*
X701800Y121875D01*
X702050Y121583D01*
X702133Y121250D01*
X702050Y120917D01*
X701842Y120667D01*
X701467Y120542D01*
X700467D01*
G01X703567Y119500D02*
Y122000D01*
X704608D01*
X704942Y121875D01*
X705150Y121708D01*
X705233Y121375D01*
X705150Y121042D01*
X704900Y120833D01*
X704608Y120708D01*
X703567D01*
G01X704608D02*
X705233Y119500D01*
G01X707500D02*
Y122000D01*
X707000Y121500D01*
G01Y119500D02*
X708000D01*
G01X711100D02*
Y122000D01*
X709558Y120208D01*
X711642D01*
G01X713700Y122000D02*
X713367Y121917D01*
X713117Y121708D01*
X712950Y121458D01*
X712825Y121125D01*
X712783Y120750D01*
X712825Y120375D01*
X712950Y120042D01*
X713117Y119792D01*
X713367Y119583D01*
X713700Y119500D01*
X714033Y119583D01*
X714283Y119792D01*
X714450Y120042D01*
X714575Y120375D01*
X714617Y120750D01*
X714575Y121125D01*
X714450Y121458D01*
X714283Y121708D01*
X714033Y121917D01*
X713700Y122000D01*
G01X708808Y129417D02*
X708683Y129167D01*
X708600Y128875D01*
Y128542D01*
X708725Y128167D01*
X708933Y127875D01*
X709183Y127667D01*
X709600Y127500D01*
X709975Y127458D01*
X710350Y127542D01*
X710600Y127667D01*
X710850Y127917D01*
X711017Y128208D01*
X711100Y128500D01*
Y128792D01*
X711017Y129083D01*
X710892Y129333D01*
X710725Y129542D01*
G01X710600Y130683D02*
X710892Y130933D01*
X711058Y131267D01*
X711100Y131642D01*
X711058Y131975D01*
X710850Y132308D01*
X710600Y132517D01*
X710350Y132558D01*
X710058Y132475D01*
X709850Y132183D01*
X709767Y131892D01*
Y131517D01*
G01Y131892D02*
X709642Y132142D01*
X709433Y132350D01*
X709183Y132433D01*
X708933Y132350D01*
X708725Y132142D01*
X708600Y131767D01*
X708642Y131392D01*
X708808Y131017D01*
G01X711100Y134700D02*
X711058Y134992D01*
X710933Y135325D01*
X710725Y135533D01*
X710433Y135617D01*
X710142Y135533D01*
X709892Y135283D01*
X709767Y134908D01*
Y134492D01*
X709683Y134242D01*
X709475Y134033D01*
X709183Y133950D01*
X708892Y134075D01*
X708683Y134367D01*
X708600Y134700D01*
X708683Y135033D01*
X708892Y135325D01*
X709183Y135450D01*
X709475Y135367D01*
X709683Y135158D01*
X709767Y134908D01*
Y134492D01*
X709892Y134117D01*
X710142Y133867D01*
X710433Y133783D01*
X710725Y133867D01*
X710933Y134075D01*
X711058Y134408D01*
X711100Y134700D01*
G01X700667Y123200D02*
Y125700D01*
X701667D01*
X702000Y125575D01*
X702250Y125283D01*
X702333Y124950D01*
X702250Y124617D01*
X702042Y124367D01*
X701667Y124242D01*
X700667D01*
G01X703767Y123200D02*
Y125700D01*
X704808D01*
X705142Y125575D01*
X705350Y125408D01*
X705433Y125075D01*
X705350Y124742D01*
X705100Y124533D01*
X704808Y124408D01*
X703767D01*
G01X704808D02*
X705433Y123200D01*
G01X707700D02*
Y125700D01*
X707200Y125200D01*
G01Y123200D02*
X708200D01*
G01X709883Y123700D02*
X710133Y123408D01*
X710467Y123242D01*
X710842Y123200D01*
X711175Y123242D01*
X711508Y123450D01*
X711717Y123700D01*
X711758Y123950D01*
X711675Y124242D01*
X711383Y124450D01*
X711092Y124533D01*
X710717D01*
G01X711092D02*
X711342Y124658D01*
X711550Y124867D01*
X711633Y125117D01*
X711550Y125367D01*
X711342Y125575D01*
X710967Y125700D01*
X710592Y125658D01*
X710217Y125492D01*
G01X713900Y123200D02*
X714192Y123242D01*
X714525Y123367D01*
X714733Y123575D01*
X714817Y123867D01*
X714733Y124158D01*
X714483Y124408D01*
X714108Y124533D01*
X713692D01*
X713442Y124617D01*
X713233Y124825D01*
X713150Y125117D01*
X713275Y125408D01*
X713567Y125617D01*
X713900Y125700D01*
X714233Y125617D01*
X714525Y125408D01*
X714650Y125117D01*
X714567Y124825D01*
X714358Y124617D01*
X714108Y124533D01*
X713692D01*
X713317Y124408D01*
X713067Y124158D01*
X712983Y123867D01*
X713067Y123575D01*
X713275Y123367D01*
X713608Y123242D01*
X713900Y123200D01*
G01X707100Y127567D02*
X704600D01*
Y128567D01*
X704725Y128900D01*
X705017Y129150D01*
X705350Y129233D01*
X705683Y129150D01*
X705933Y128942D01*
X706058Y128567D01*
Y127567D01*
G01X707100Y130667D02*
X704600D01*
Y131708D01*
X704725Y132042D01*
X704892Y132250D01*
X705225Y132333D01*
X705558Y132250D01*
X705767Y132000D01*
X705892Y131708D01*
Y130667D01*
G01Y131708D02*
X707100Y132333D01*
G01Y134600D02*
X704600D01*
X705100Y134100D01*
G01X707100D02*
Y135100D01*
G01X706600Y136783D02*
X706892Y137033D01*
X707058Y137367D01*
X707100Y137742D01*
X707058Y138075D01*
X706850Y138408D01*
X706600Y138617D01*
X706350Y138658D01*
X706058Y138575D01*
X705850Y138283D01*
X705767Y137992D01*
Y137617D01*
G01Y137992D02*
X705642Y138242D01*
X705433Y138450D01*
X705183Y138533D01*
X704933Y138450D01*
X704725Y138242D01*
X704600Y137867D01*
X704642Y137492D01*
X704808Y137117D01*
G01X706725Y139883D02*
X706933Y140133D01*
X707058Y140425D01*
X707100Y140800D01*
X707017Y141175D01*
X706850Y141467D01*
X706558Y141675D01*
X706225Y141717D01*
X705892Y141633D01*
X705683Y141425D01*
X705517Y141133D01*
X705475Y140842D01*
X705517Y140550D01*
X705683Y140175D01*
X704600Y140300D01*
Y141425D01*
G01X703100Y127567D02*
X700600D01*
Y128567D01*
X700725Y128900D01*
X701017Y129150D01*
X701350Y129233D01*
X701683Y129150D01*
X701933Y128942D01*
X702058Y128567D01*
Y127567D01*
G01X703100Y130667D02*
X700600D01*
Y131708D01*
X700725Y132042D01*
X700892Y132250D01*
X701225Y132333D01*
X701558Y132250D01*
X701767Y132000D01*
X701892Y131708D01*
Y130667D01*
G01Y131708D02*
X703100Y132333D01*
G01Y134600D02*
X700600D01*
X701100Y134100D01*
G01X703100D02*
Y135100D01*
G01X702600Y136783D02*
X702892Y137033D01*
X703058Y137367D01*
X703100Y137742D01*
X703058Y138075D01*
X702850Y138408D01*
X702600Y138617D01*
X702350Y138658D01*
X702058Y138575D01*
X701850Y138283D01*
X701767Y137992D01*
Y137617D01*
G01Y137992D02*
X701642Y138242D01*
X701433Y138450D01*
X701183Y138533D01*
X700933Y138450D01*
X700725Y138242D01*
X700600Y137867D01*
X700642Y137492D01*
X700808Y137117D01*
G01X703100Y141300D02*
X700600D01*
X702392Y139758D01*
Y141842D01*
G01X708967Y156500D02*
Y159000D01*
X709967D01*
X710300Y158875D01*
X710550Y158583D01*
X710633Y158250D01*
X710550Y157917D01*
X710342Y157667D01*
X709967Y157542D01*
X708967D01*
G01X713817Y158792D02*
X713567Y158917D01*
X713275Y159000D01*
X712942D01*
X712567Y158875D01*
X712275Y158667D01*
X712067Y158417D01*
X711900Y158000D01*
X711858Y157625D01*
X711942Y157250D01*
X712067Y157000D01*
X712317Y156750D01*
X712608Y156583D01*
X712900Y156500D01*
X713192D01*
X713483Y156583D01*
X713733Y156708D01*
X713942Y156875D01*
G01X715208Y158583D02*
X715458Y158833D01*
X715750Y158958D01*
X716083Y159000D01*
X716500Y158917D01*
X716792Y158708D01*
X716875Y158458D01*
X716833Y158208D01*
X716667Y158000D01*
X715833Y157583D01*
X715458Y157292D01*
X715208Y156875D01*
X715125Y156500D01*
X716875D01*
G01X719100D02*
Y159000D01*
X718600Y158500D01*
G01Y156500D02*
X719600D01*
G01X721408Y158583D02*
X721658Y158833D01*
X721950Y158958D01*
X722283Y159000D01*
X722700Y158917D01*
X722992Y158708D01*
X723075Y158458D01*
X723033Y158208D01*
X722867Y158000D01*
X722033Y157583D01*
X721658Y157292D01*
X721408Y156875D01*
X721325Y156500D01*
X723075D01*
G01X707467Y169000D02*
Y171500D01*
X708467D01*
X708800Y171375D01*
X709050Y171083D01*
X709133Y170750D01*
X709050Y170417D01*
X708842Y170167D01*
X708467Y170042D01*
X707467D01*
G01X712317Y171292D02*
X712067Y171417D01*
X711775Y171500D01*
X711442D01*
X711067Y171375D01*
X710775Y171167D01*
X710567Y170917D01*
X710400Y170500D01*
X710358Y170125D01*
X710442Y169750D01*
X710567Y169500D01*
X710817Y169250D01*
X711108Y169083D01*
X711400Y169000D01*
X711692D01*
X711983Y169083D01*
X712233Y169208D01*
X712442Y169375D01*
G01X713708Y171083D02*
X713958Y171333D01*
X714250Y171458D01*
X714583Y171500D01*
X715000Y171417D01*
X715292Y171208D01*
X715375Y170958D01*
X715333Y170708D01*
X715167Y170500D01*
X714333Y170083D01*
X713958Y169792D01*
X713708Y169375D01*
X713625Y169000D01*
X715375D01*
G01X717600Y171500D02*
X717267Y171417D01*
X717017Y171208D01*
X716850Y170958D01*
X716725Y170625D01*
X716683Y170250D01*
X716725Y169875D01*
X716850Y169542D01*
X717017Y169292D01*
X717267Y169083D01*
X717600Y169000D01*
X717933Y169083D01*
X718183Y169292D01*
X718350Y169542D01*
X718475Y169875D01*
X718517Y170250D01*
X718475Y170625D01*
X718350Y170958D01*
X718183Y171208D01*
X717933Y171417D01*
X717600Y171500D01*
G01X719992Y169292D02*
X720283Y169083D01*
X720617Y169000D01*
X720950Y169083D01*
X721242Y169333D01*
X721450Y169708D01*
X721533Y170083D01*
Y170542D01*
X721450Y170917D01*
X721242Y171250D01*
X720992Y171417D01*
X720700Y171500D01*
X720367Y171417D01*
X720117Y171250D01*
X719950Y171000D01*
X719867Y170667D01*
X719950Y170375D01*
X720158Y170083D01*
X720408Y169917D01*
X720700Y169875D01*
X721033Y169958D01*
X721283Y170167D01*
X721533Y170542D01*
G01X706100Y177717D02*
X703600D01*
Y178758D01*
X703725Y179092D01*
X703892Y179300D01*
X704225Y179383D01*
X704558Y179300D01*
X704767Y179050D01*
X704892Y178758D01*
Y177717D01*
G01Y178758D02*
X706100Y179383D01*
G01Y181650D02*
X703600D01*
X704100Y181150D01*
G01X706100D02*
Y182150D01*
G01Y184667D02*
X705558Y184750D01*
X705100Y184875D01*
X704683Y185042D01*
X704225Y185250D01*
X703600Y185583D01*
Y183917D01*
G01X705808Y187142D02*
X706017Y187433D01*
X706100Y187767D01*
X706017Y188100D01*
X705767Y188392D01*
X705392Y188600D01*
X705017Y188683D01*
X704558D01*
X704183Y188600D01*
X703850Y188392D01*
X703683Y188142D01*
X703600Y187850D01*
X703683Y187517D01*
X703850Y187267D01*
X704100Y187100D01*
X704433Y187017D01*
X704725Y187100D01*
X705017Y187308D01*
X705183Y187558D01*
X705225Y187850D01*
X705142Y188183D01*
X704933Y188433D01*
X704558Y188683D01*
G01X701900Y177617D02*
X699400D01*
Y178658D01*
X699525Y178992D01*
X699692Y179200D01*
X700025Y179283D01*
X700358Y179200D01*
X700567Y178950D01*
X700692Y178658D01*
Y177617D01*
G01Y178658D02*
X701900Y179283D01*
G01Y181550D02*
X699400D01*
X699900Y181050D01*
G01X701900D02*
Y182050D01*
G01Y184650D02*
X701858Y184942D01*
X701733Y185275D01*
X701525Y185483D01*
X701233Y185567D01*
X700942Y185483D01*
X700692Y185233D01*
X700567Y184858D01*
Y184442D01*
X700483Y184192D01*
X700275Y183983D01*
X699983Y183900D01*
X699692Y184025D01*
X699483Y184317D01*
X699400Y184650D01*
X699483Y184983D01*
X699692Y185275D01*
X699983Y185400D01*
X700275Y185317D01*
X700483Y185108D01*
X700567Y184858D01*
Y184442D01*
X700692Y184067D01*
X700942Y183817D01*
X701233Y183733D01*
X701525Y183817D01*
X701733Y184025D01*
X701858Y184358D01*
X701900Y184650D01*
G01Y188250D02*
X699400D01*
X701192Y186708D01*
Y188792D01*
G01X712000Y175917D02*
X709500D01*
Y176958D01*
X709625Y177292D01*
X709792Y177500D01*
X710125Y177583D01*
X710458Y177500D01*
X710667Y177250D01*
X710792Y176958D01*
Y175917D01*
G01Y176958D02*
X712000Y177583D01*
G01X709917Y179058D02*
X709667Y179308D01*
X709542Y179600D01*
X709500Y179933D01*
X709583Y180350D01*
X709792Y180642D01*
X710042Y180725D01*
X710292Y180683D01*
X710500Y180517D01*
X710917Y179683D01*
X711208Y179308D01*
X711625Y179058D01*
X712000Y178975D01*
Y180725D01*
G01Y182950D02*
X709500D01*
X710000Y182450D01*
G01X712000D02*
Y183450D01*
G01Y185967D02*
X711458Y186050D01*
X711000Y186175D01*
X710583Y186342D01*
X710125Y186550D01*
X709500Y186883D01*
Y185217D01*
G01X708708Y199817D02*
X708583Y199567D01*
X708500Y199275D01*
Y198942D01*
X708625Y198567D01*
X708833Y198275D01*
X709083Y198067D01*
X709500Y197900D01*
X709875Y197858D01*
X710250Y197942D01*
X710500Y198067D01*
X710750Y198317D01*
X710917Y198608D01*
X711000Y198900D01*
Y199192D01*
X710917Y199483D01*
X710792Y199733D01*
X710625Y199942D01*
G01X710708Y201292D02*
X710917Y201583D01*
X711000Y201917D01*
X710917Y202250D01*
X710667Y202542D01*
X710292Y202750D01*
X709917Y202833D01*
X709458D01*
X709083Y202750D01*
X708750Y202542D01*
X708583Y202292D01*
X708500Y202000D01*
X708583Y201667D01*
X708750Y201417D01*
X709000Y201250D01*
X709333Y201167D01*
X709625Y201250D01*
X709917Y201458D01*
X710083Y201708D01*
X710125Y202000D01*
X710042Y202333D01*
X709833Y202583D01*
X709458Y202833D01*
G01X710500Y204183D02*
X710792Y204433D01*
X710958Y204767D01*
X711000Y205142D01*
X710958Y205475D01*
X710750Y205808D01*
X710500Y206017D01*
X710250Y206058D01*
X709958Y205975D01*
X709750Y205683D01*
X709667Y205392D01*
Y205017D01*
G01Y205392D02*
X709542Y205642D01*
X709333Y205850D01*
X709083Y205933D01*
X708833Y205850D01*
X708625Y205642D01*
X708500Y205267D01*
X708542Y204892D01*
X708708Y204517D01*
G01X708208Y190317D02*
X708083Y190067D01*
X708000Y189775D01*
Y189442D01*
X708125Y189067D01*
X708333Y188775D01*
X708583Y188567D01*
X709000Y188400D01*
X709375Y188358D01*
X709750Y188442D01*
X710000Y188567D01*
X710250Y188817D01*
X710417Y189108D01*
X710500Y189400D01*
Y189692D01*
X710417Y189983D01*
X710292Y190233D01*
X710125Y190442D01*
G01X710208Y191792D02*
X710417Y192083D01*
X710500Y192417D01*
X710417Y192750D01*
X710167Y193042D01*
X709792Y193250D01*
X709417Y193333D01*
X708958D01*
X708583Y193250D01*
X708250Y193042D01*
X708083Y192792D01*
X708000Y192500D01*
X708083Y192167D01*
X708250Y191917D01*
X708500Y191750D01*
X708833Y191667D01*
X709125Y191750D01*
X709417Y191958D01*
X709583Y192208D01*
X709625Y192500D01*
X709542Y192833D01*
X709333Y193083D01*
X708958Y193333D01*
G01X710125Y194683D02*
X710333Y194933D01*
X710458Y195225D01*
X710500Y195600D01*
X710417Y195975D01*
X710250Y196267D01*
X709958Y196475D01*
X709625Y196517D01*
X709292Y196433D01*
X709083Y196225D01*
X708917Y195933D01*
X708875Y195642D01*
X708917Y195350D01*
X709083Y194975D01*
X708000Y195100D01*
Y196225D01*
G01X702208Y196817D02*
X702083Y196567D01*
X702000Y196275D01*
Y195942D01*
X702125Y195567D01*
X702333Y195275D01*
X702583Y195067D01*
X703000Y194900D01*
X703375Y194858D01*
X703750Y194942D01*
X704000Y195067D01*
X704250Y195317D01*
X704417Y195608D01*
X704500Y195900D01*
Y196192D01*
X704417Y196483D01*
X704292Y196733D01*
X704125Y196942D01*
G01X704500Y199000D02*
X704458Y199292D01*
X704333Y199625D01*
X704125Y199833D01*
X703833Y199917D01*
X703542Y199833D01*
X703292Y199583D01*
X703167Y199208D01*
Y198792D01*
X703083Y198542D01*
X702875Y198333D01*
X702583Y198250D01*
X702292Y198375D01*
X702083Y198667D01*
X702000Y199000D01*
X702083Y199333D01*
X702292Y199625D01*
X702583Y199750D01*
X702875Y199667D01*
X703083Y199458D01*
X703167Y199208D01*
Y198792D01*
X703292Y198417D01*
X703542Y198167D01*
X703833Y198083D01*
X704125Y198167D01*
X704333Y198375D01*
X704458Y198708D01*
X704500Y199000D01*
G01Y202600D02*
X702000D01*
X703792Y201058D01*
Y203142D01*
G01X699550Y202000D02*
Y206000D01*
X697550Y204000D01*
X699550Y202000D01*
G01X708000Y212017D02*
X705500D01*
Y213058D01*
X705625Y213392D01*
X705792Y213600D01*
X706125Y213683D01*
X706458Y213600D01*
X706667Y213350D01*
X706792Y213058D01*
Y212017D01*
G01Y213058D02*
X708000Y213683D01*
G01Y215950D02*
X705500D01*
X706000Y215450D01*
G01X708000D02*
Y216450D01*
G01Y218967D02*
X707458Y219050D01*
X707000Y219175D01*
X706583Y219342D01*
X706125Y219550D01*
X705500Y219883D01*
Y218217D01*
G01X707500Y221233D02*
X707792Y221483D01*
X707958Y221817D01*
X708000Y222192D01*
X707958Y222525D01*
X707750Y222858D01*
X707500Y223067D01*
X707250Y223108D01*
X706958Y223025D01*
X706750Y222733D01*
X706667Y222442D01*
Y222067D01*
G01Y222442D02*
X706542Y222692D01*
X706333Y222900D01*
X706083Y222983D01*
X705833Y222900D01*
X705625Y222692D01*
X705500Y222317D01*
X705542Y221942D01*
X705708Y221567D01*
G01X704000Y212017D02*
X701500D01*
Y213058D01*
X701625Y213392D01*
X701792Y213600D01*
X702125Y213683D01*
X702458Y213600D01*
X702667Y213350D01*
X702792Y213058D01*
Y212017D01*
G01Y213058D02*
X704000Y213683D01*
G01Y215950D02*
X701500D01*
X702000Y215450D01*
G01X704000D02*
Y216450D01*
G01Y218967D02*
X703458Y219050D01*
X703000Y219175D01*
X702583Y219342D01*
X702125Y219550D01*
X701500Y219883D01*
Y218217D01*
G01X704000Y222150D02*
X701500D01*
X702000Y221650D01*
G01X704000D02*
Y222650D01*
G01X700500Y225000D02*
X711500D01*
G01X710500Y226467D02*
X708000D01*
Y227467D01*
X708125Y227800D01*
X708417Y228050D01*
X708750Y228133D01*
X709083Y228050D01*
X709333Y227842D01*
X709458Y227467D01*
Y226467D01*
G01X710500Y229567D02*
X708000D01*
Y230608D01*
X708125Y230942D01*
X708292Y231150D01*
X708625Y231233D01*
X708958Y231150D01*
X709167Y230900D01*
X709292Y230608D01*
Y229567D01*
G01Y230608D02*
X710500Y231233D01*
G01Y233500D02*
X708000D01*
X708500Y233000D01*
G01X710500D02*
Y234000D01*
G01X708417Y235808D02*
X708167Y236058D01*
X708042Y236350D01*
X708000Y236683D01*
X708083Y237100D01*
X708292Y237392D01*
X708542Y237475D01*
X708792Y237433D01*
X709000Y237267D01*
X709417Y236433D01*
X709708Y236058D01*
X710125Y235808D01*
X710500Y235725D01*
Y237475D01*
G01X710000Y238783D02*
X710292Y239033D01*
X710458Y239367D01*
X710500Y239742D01*
X710458Y240075D01*
X710250Y240408D01*
X710000Y240617D01*
X709750Y240658D01*
X709458Y240575D01*
X709250Y240283D01*
X709167Y239992D01*
Y239617D01*
G01Y239992D02*
X709042Y240242D01*
X708833Y240450D01*
X708583Y240533D01*
X708333Y240450D01*
X708125Y240242D01*
X708000Y239867D01*
X708042Y239492D01*
X708208Y239117D01*
G01X706500Y226467D02*
X704000D01*
Y227467D01*
X704125Y227800D01*
X704417Y228050D01*
X704750Y228133D01*
X705083Y228050D01*
X705333Y227842D01*
X705458Y227467D01*
Y226467D01*
G01X706500Y229567D02*
X704000D01*
Y230608D01*
X704125Y230942D01*
X704292Y231150D01*
X704625Y231233D01*
X704958Y231150D01*
X705167Y230900D01*
X705292Y230608D01*
Y229567D01*
G01Y230608D02*
X706500Y231233D01*
G01Y233500D02*
X704000D01*
X704500Y233000D01*
G01X706500D02*
Y234000D01*
G01X704417Y235808D02*
X704167Y236058D01*
X704042Y236350D01*
X704000Y236683D01*
X704083Y237100D01*
X704292Y237392D01*
X704542Y237475D01*
X704792Y237433D01*
X705000Y237267D01*
X705417Y236433D01*
X705708Y236058D01*
X706125Y235808D01*
X706500Y235725D01*
Y237475D01*
G01X704417Y238908D02*
X704167Y239158D01*
X704042Y239450D01*
X704000Y239783D01*
X704083Y240200D01*
X704292Y240492D01*
X704542Y240575D01*
X704792Y240533D01*
X705000Y240367D01*
X705417Y239533D01*
X705708Y239158D01*
X706125Y238908D01*
X706500Y238825D01*
Y240575D01*
G01X702500Y226467D02*
X700000D01*
Y227467D01*
X700125Y227800D01*
X700417Y228050D01*
X700750Y228133D01*
X701083Y228050D01*
X701333Y227842D01*
X701458Y227467D01*
Y226467D01*
G01X702500Y229567D02*
X700000D01*
Y230608D01*
X700125Y230942D01*
X700292Y231150D01*
X700625Y231233D01*
X700958Y231150D01*
X701167Y230900D01*
X701292Y230608D01*
Y229567D01*
G01Y230608D02*
X702500Y231233D01*
G01Y233500D02*
X700000D01*
X700500Y233000D01*
G01X702500D02*
Y234000D01*
G01X700417Y235808D02*
X700167Y236058D01*
X700042Y236350D01*
X700000Y236683D01*
X700083Y237100D01*
X700292Y237392D01*
X700542Y237475D01*
X700792Y237433D01*
X701000Y237267D01*
X701417Y236433D01*
X701708Y236058D01*
X702125Y235808D01*
X702500Y235725D01*
Y237475D01*
G01Y239700D02*
X700000D01*
X700500Y239200D01*
G01X702500D02*
Y240200D01*
G01X719967Y44500D02*
Y47000D01*
X720967D01*
X721300Y46875D01*
X721550Y46583D01*
X721633Y46250D01*
X721550Y45917D01*
X721342Y45667D01*
X720967Y45542D01*
X719967D01*
G01X724817Y46792D02*
X724567Y46917D01*
X724275Y47000D01*
X723942D01*
X723567Y46875D01*
X723275Y46667D01*
X723067Y46417D01*
X722900Y46000D01*
X722858Y45625D01*
X722942Y45250D01*
X723067Y45000D01*
X723317Y44750D01*
X723608Y44583D01*
X723900Y44500D01*
X724192D01*
X724483Y44583D01*
X724733Y44708D01*
X724942Y44875D01*
G01X727000Y44500D02*
Y47000D01*
X726500Y46500D01*
G01Y44500D02*
X727500D01*
G01X730100D02*
Y47000D01*
X729600Y46500D01*
G01Y44500D02*
X730600D01*
G01X732492Y44792D02*
X732783Y44583D01*
X733117Y44500D01*
X733450Y44583D01*
X733742Y44833D01*
X733950Y45208D01*
X734033Y45583D01*
Y46042D01*
X733950Y46417D01*
X733742Y46750D01*
X733492Y46917D01*
X733200Y47000D01*
X732867Y46917D01*
X732617Y46750D01*
X732450Y46500D01*
X732367Y46167D01*
X732450Y45875D01*
X732658Y45583D01*
X732908Y45417D01*
X733200Y45375D01*
X733533Y45458D01*
X733783Y45667D01*
X734033Y46042D01*
G01X719967Y48500D02*
Y51000D01*
X720967D01*
X721300Y50875D01*
X721550Y50583D01*
X721633Y50250D01*
X721550Y49917D01*
X721342Y49667D01*
X720967Y49542D01*
X719967D01*
G01X724817Y50792D02*
X724567Y50917D01*
X724275Y51000D01*
X723942D01*
X723567Y50875D01*
X723275Y50667D01*
X723067Y50417D01*
X722900Y50000D01*
X722858Y49625D01*
X722942Y49250D01*
X723067Y49000D01*
X723317Y48750D01*
X723608Y48583D01*
X723900Y48500D01*
X724192D01*
X724483Y48583D01*
X724733Y48708D01*
X724942Y48875D01*
G01X727000Y48500D02*
Y51000D01*
X726500Y50500D01*
G01Y48500D02*
X727500D01*
G01X730100D02*
Y51000D01*
X729600Y50500D01*
G01Y48500D02*
X730600D01*
G01X733200D02*
X733492Y48542D01*
X733825Y48667D01*
X734033Y48875D01*
X734117Y49167D01*
X734033Y49458D01*
X733783Y49708D01*
X733408Y49833D01*
X732992D01*
X732742Y49917D01*
X732533Y50125D01*
X732450Y50417D01*
X732575Y50708D01*
X732867Y50917D01*
X733200Y51000D01*
X733533Y50917D01*
X733825Y50708D01*
X733950Y50417D01*
X733867Y50125D01*
X733658Y49917D01*
X733408Y49833D01*
X732992D01*
X732617Y49708D01*
X732367Y49458D01*
X732283Y49167D01*
X732367Y48875D01*
X732575Y48667D01*
X732908Y48542D01*
X733200Y48500D01*
G01X712517Y75000D02*
Y77500D01*
X713517D01*
X713850Y77375D01*
X714100Y77083D01*
X714183Y76750D01*
X714100Y76417D01*
X713892Y76167D01*
X713517Y76042D01*
X712517D01*
G01X715533Y77500D02*
Y75708D01*
X715700Y75333D01*
X716033Y75083D01*
X716450Y75000D01*
X716867Y75083D01*
X717200Y75333D01*
X717367Y75708D01*
Y77500D01*
G01X719550Y75000D02*
Y77500D01*
X719050Y77000D01*
G01Y75000D02*
X720050D01*
G01X721858Y77083D02*
X722108Y77333D01*
X722400Y77458D01*
X722733Y77500D01*
X723150Y77417D01*
X723442Y77208D01*
X723525Y76958D01*
X723483Y76708D01*
X723317Y76500D01*
X722483Y76083D01*
X722108Y75792D01*
X721858Y75375D01*
X721775Y75000D01*
X723525D01*
G01X725300Y98000D02*
X727967D01*
Y95900D01*
X727167Y95200D01*
X726233Y94733D01*
X724900Y94500D01*
X723567Y94733D01*
X722633Y95200D01*
X721833Y95900D01*
X721300Y96717D01*
X721033Y97650D01*
Y98467D01*
X721300Y99167D01*
X721833Y99983D01*
X722633Y100683D01*
X723433Y101150D01*
X724500Y101500D01*
X725433D01*
X726500Y101267D01*
X727300Y100800D01*
G01X725000Y110000D02*
X720500D01*
Y102500D01*
G01X718500Y94567D02*
X716000D01*
Y95567D01*
X716125Y95900D01*
X716417Y96150D01*
X716750Y96233D01*
X717083Y96150D01*
X717333Y95942D01*
X717458Y95567D01*
Y94567D01*
G01X718500Y97667D02*
X716000D01*
Y98708D01*
X716125Y99042D01*
X716292Y99250D01*
X716625Y99333D01*
X716958Y99250D01*
X717167Y99000D01*
X717292Y98708D01*
Y97667D01*
G01Y98708D02*
X718500Y99333D01*
G01Y101600D02*
X716000D01*
X716500Y101100D01*
G01X718500D02*
Y102100D01*
G01X718125Y103783D02*
X718333Y104033D01*
X718458Y104325D01*
X718500Y104700D01*
X718417Y105075D01*
X718250Y105367D01*
X717958Y105575D01*
X717625Y105617D01*
X717292Y105533D01*
X717083Y105325D01*
X716917Y105033D01*
X716875Y104742D01*
X716917Y104450D01*
X717083Y104075D01*
X716000Y104200D01*
Y105325D01*
G01X717458Y107008D02*
X717167Y107300D01*
X717000Y107550D01*
X716917Y107883D01*
X717000Y108175D01*
X717167Y108383D01*
X717417Y108550D01*
X717708Y108592D01*
X717958Y108550D01*
X718208Y108383D01*
X718417Y108133D01*
X718500Y107842D01*
X718417Y107508D01*
X718167Y107217D01*
X717792Y107050D01*
X717375Y107008D01*
X716833Y107092D01*
X716542Y107217D01*
X716250Y107425D01*
X716042Y107717D01*
X716000Y108008D01*
X716083Y108300D01*
X716292Y108508D01*
G01X749500Y153500D02*
Y151500D01*
X743500D01*
Y146000D01*
X733000D01*
Y143000D01*
X727000D01*
Y145000D01*
X723500D01*
G01X719000Y146000D02*
Y155000D01*
X726000D01*
Y162000D01*
X741500D01*
Y165500D01*
G01X712017Y161000D02*
Y163500D01*
X713017D01*
X713350Y163375D01*
X713600Y163083D01*
X713683Y162750D01*
X713600Y162417D01*
X713392Y162167D01*
X713017Y162042D01*
X712017D01*
G01X715033Y163500D02*
Y161708D01*
X715200Y161333D01*
X715533Y161083D01*
X715950Y161000D01*
X716367Y161083D01*
X716700Y161333D01*
X716867Y161708D01*
Y163500D01*
G01X719050Y161000D02*
Y163500D01*
X718550Y163000D01*
G01Y161000D02*
X719550D01*
G01X722067D02*
X722150Y161542D01*
X722275Y162000D01*
X722442Y162417D01*
X722650Y162875D01*
X722983Y163500D01*
X721317D01*
G01X725017Y164000D02*
Y166500D01*
X726058D01*
X726392Y166375D01*
X726600Y166208D01*
X726683Y165875D01*
X726600Y165542D01*
X726350Y165333D01*
X726058Y165208D01*
X725017D01*
G01X726058D02*
X726683Y164000D01*
G01X728158Y166083D02*
X728408Y166333D01*
X728700Y166458D01*
X729033Y166500D01*
X729450Y166417D01*
X729742Y166208D01*
X729825Y165958D01*
X729783Y165708D01*
X729617Y165500D01*
X728783Y165083D01*
X728408Y164792D01*
X728158Y164375D01*
X728075Y164000D01*
X729825D01*
G01X731258Y166083D02*
X731508Y166333D01*
X731800Y166458D01*
X732133Y166500D01*
X732550Y166417D01*
X732842Y166208D01*
X732925Y165958D01*
X732883Y165708D01*
X732717Y165500D01*
X731883Y165083D01*
X731508Y164792D01*
X731258Y164375D01*
X731175Y164000D01*
X732925D01*
G01X734233Y164500D02*
X734483Y164208D01*
X734817Y164042D01*
X735192Y164000D01*
X735525Y164042D01*
X735858Y164250D01*
X736067Y164500D01*
X736108Y164750D01*
X736025Y165042D01*
X735733Y165250D01*
X735442Y165333D01*
X735067D01*
G01X735442D02*
X735692Y165458D01*
X735900Y165667D01*
X735983Y165917D01*
X735900Y166167D01*
X735692Y166375D01*
X735317Y166500D01*
X734942Y166458D01*
X734567Y166292D01*
G01X717000Y173000D02*
X723000D01*
Y169000D01*
G01X716000Y175917D02*
X713500D01*
Y176958D01*
X713625Y177292D01*
X713792Y177500D01*
X714125Y177583D01*
X714458Y177500D01*
X714667Y177250D01*
X714792Y176958D01*
Y175917D01*
G01Y176958D02*
X716000Y177583D01*
G01X713917Y179058D02*
X713667Y179308D01*
X713542Y179600D01*
X713500Y179933D01*
X713583Y180350D01*
X713792Y180642D01*
X714042Y180725D01*
X714292Y180683D01*
X714500Y180517D01*
X714917Y179683D01*
X715208Y179308D01*
X715625Y179058D01*
X716000Y178975D01*
Y180725D01*
G01Y182950D02*
X713500D01*
X714000Y182450D01*
G01X716000D02*
Y183450D01*
G01Y186050D02*
X715958Y186342D01*
X715833Y186675D01*
X715625Y186883D01*
X715333Y186967D01*
X715042Y186883D01*
X714792Y186633D01*
X714667Y186258D01*
Y185842D01*
X714583Y185592D01*
X714375Y185383D01*
X714083Y185300D01*
X713792Y185425D01*
X713583Y185717D01*
X713500Y186050D01*
X713583Y186383D01*
X713792Y186675D01*
X714083Y186800D01*
X714375Y186717D01*
X714583Y186508D01*
X714667Y186258D01*
Y185842D01*
X714792Y185467D01*
X715042Y185217D01*
X715333Y185133D01*
X715625Y185217D01*
X715833Y185425D01*
X715958Y185758D01*
X716000Y186050D01*
G01X721017Y174500D02*
Y177000D01*
X722058D01*
X722392Y176875D01*
X722600Y176708D01*
X722683Y176375D01*
X722600Y176042D01*
X722350Y175833D01*
X722058Y175708D01*
X721017D01*
G01X722058D02*
X722683Y174500D01*
G01X724158Y176583D02*
X724408Y176833D01*
X724700Y176958D01*
X725033Y177000D01*
X725450Y176917D01*
X725742Y176708D01*
X725825Y176458D01*
X725783Y176208D01*
X725617Y176000D01*
X724783Y175583D01*
X724408Y175292D01*
X724158Y174875D01*
X724075Y174500D01*
X725825D01*
G01X727258Y176583D02*
X727508Y176833D01*
X727800Y176958D01*
X728133Y177000D01*
X728550Y176917D01*
X728842Y176708D01*
X728925Y176458D01*
X728883Y176208D01*
X728717Y176000D01*
X727883Y175583D01*
X727508Y175292D01*
X727258Y174875D01*
X727175Y174500D01*
X728925D01*
G01X730358Y176583D02*
X730608Y176833D01*
X730900Y176958D01*
X731233Y177000D01*
X731650Y176917D01*
X731942Y176708D01*
X732025Y176458D01*
X731983Y176208D01*
X731817Y176000D01*
X730983Y175583D01*
X730608Y175292D01*
X730358Y174875D01*
X730275Y174500D01*
X732025D01*
G01X712500Y197983D02*
X714292D01*
X714667Y198150D01*
X714917Y198483D01*
X715000Y198900D01*
X714917Y199317D01*
X714667Y199650D01*
X714292Y199817D01*
X712500D01*
G01X712917Y201208D02*
X712667Y201458D01*
X712542Y201750D01*
X712500Y202083D01*
X712583Y202500D01*
X712792Y202792D01*
X713042Y202875D01*
X713292Y202833D01*
X713500Y202667D01*
X713917Y201833D01*
X714208Y201458D01*
X714625Y201208D01*
X715000Y201125D01*
Y202875D01*
G01X714500Y204183D02*
X714792Y204433D01*
X714958Y204767D01*
X715000Y205142D01*
X714958Y205475D01*
X714750Y205808D01*
X714500Y206017D01*
X714250Y206058D01*
X713958Y205975D01*
X713750Y205683D01*
X713667Y205392D01*
Y205017D01*
G01Y205392D02*
X713542Y205642D01*
X713333Y205850D01*
X713083Y205933D01*
X712833Y205850D01*
X712625Y205642D01*
X712500Y205267D01*
X712542Y204892D01*
X712708Y204517D01*
G01X723760Y196135D02*
Y204035D01*
G01X726360Y196135D02*
X723760D01*
G01X712000Y188483D02*
X713792D01*
X714167Y188650D01*
X714417Y188983D01*
X714500Y189400D01*
X714417Y189817D01*
X714167Y190150D01*
X713792Y190317D01*
X712000D01*
G01X712417Y191708D02*
X712167Y191958D01*
X712042Y192250D01*
X712000Y192583D01*
X712083Y193000D01*
X712292Y193292D01*
X712542Y193375D01*
X712792Y193333D01*
X713000Y193167D01*
X713417Y192333D01*
X713708Y191958D01*
X714125Y191708D01*
X714500Y191625D01*
Y193375D01*
G01X713458Y194808D02*
X713167Y195100D01*
X713000Y195350D01*
X712917Y195683D01*
X713000Y195975D01*
X713167Y196183D01*
X713417Y196350D01*
X713708Y196392D01*
X713958Y196350D01*
X714208Y196183D01*
X714417Y195933D01*
X714500Y195642D01*
X714417Y195308D01*
X714167Y195017D01*
X713792Y194850D01*
X713375Y194808D01*
X712833Y194892D01*
X712542Y195017D01*
X712250Y195225D01*
X712042Y195517D01*
X712000Y195808D01*
X712083Y196100D01*
X712292Y196308D01*
G01X726850Y193950D02*
X723150D01*
G01Y186050D02*
X726850D01*
G01X723150Y193950D02*
Y186050D01*
G01X713208Y209317D02*
X713083Y209067D01*
X713000Y208775D01*
Y208442D01*
X713125Y208067D01*
X713333Y207775D01*
X713583Y207567D01*
X714000Y207400D01*
X714375Y207358D01*
X714750Y207442D01*
X715000Y207567D01*
X715250Y207817D01*
X715417Y208108D01*
X715500Y208400D01*
Y208692D01*
X715417Y208983D01*
X715292Y209233D01*
X715125Y209442D01*
G01X715208Y210792D02*
X715417Y211083D01*
X715500Y211417D01*
X715417Y211750D01*
X715167Y212042D01*
X714792Y212250D01*
X714417Y212333D01*
X713958D01*
X713583Y212250D01*
X713250Y212042D01*
X713083Y211792D01*
X713000Y211500D01*
X713083Y211167D01*
X713250Y210917D01*
X713500Y210750D01*
X713833Y210667D01*
X714125Y210750D01*
X714417Y210958D01*
X714583Y211208D01*
X714625Y211500D01*
X714542Y211833D01*
X714333Y212083D01*
X713958Y212333D01*
G01X713417Y213808D02*
X713167Y214058D01*
X713042Y214350D01*
X713000Y214683D01*
X713083Y215100D01*
X713292Y215392D01*
X713542Y215475D01*
X713792Y215433D01*
X714000Y215267D01*
X714417Y214433D01*
X714708Y214058D01*
X715125Y213808D01*
X715500Y213725D01*
Y215475D01*
G01X723760Y204035D02*
X726360D01*
G01X718500Y228000D02*
X730500D01*
Y232000D01*
G01X716000Y217017D02*
X713500D01*
Y218058D01*
X713625Y218392D01*
X713792Y218600D01*
X714125Y218683D01*
X714458Y218600D01*
X714667Y218350D01*
X714792Y218058D01*
Y217017D01*
G01Y218058D02*
X716000Y218683D01*
G01X713917Y220158D02*
X713667Y220408D01*
X713542Y220700D01*
X713500Y221033D01*
X713583Y221450D01*
X713792Y221742D01*
X714042Y221825D01*
X714292Y221783D01*
X714500Y221617D01*
X714917Y220783D01*
X715208Y220408D01*
X715625Y220158D01*
X716000Y220075D01*
Y221825D01*
G01X713500Y224050D02*
X713583Y223717D01*
X713792Y223467D01*
X714042Y223300D01*
X714375Y223175D01*
X714750Y223133D01*
X715125Y223175D01*
X715458Y223300D01*
X715708Y223467D01*
X715917Y223717D01*
X716000Y224050D01*
X715917Y224383D01*
X715708Y224633D01*
X715458Y224800D01*
X715125Y224925D01*
X714750Y224967D01*
X714375Y224925D01*
X714042Y224800D01*
X713792Y224633D01*
X713583Y224383D01*
X713500Y224050D01*
G01X716000Y227150D02*
X713500D01*
X714000Y226650D01*
G01X716000D02*
Y227650D01*
G01X728000Y216017D02*
X725500D01*
Y217058D01*
X725625Y217392D01*
X725792Y217600D01*
X726125Y217683D01*
X726458Y217600D01*
X726667Y217350D01*
X726792Y217058D01*
Y216017D01*
G01Y217058D02*
X728000Y217683D01*
G01X725917Y219158D02*
X725667Y219408D01*
X725542Y219700D01*
X725500Y220033D01*
X725583Y220450D01*
X725792Y220742D01*
X726042Y220825D01*
X726292Y220783D01*
X726500Y220617D01*
X726917Y219783D01*
X727208Y219408D01*
X727625Y219158D01*
X728000Y219075D01*
Y220825D01*
G01X725500Y223050D02*
X725583Y222717D01*
X725792Y222467D01*
X726042Y222300D01*
X726375Y222175D01*
X726750Y222133D01*
X727125Y222175D01*
X727458Y222300D01*
X727708Y222467D01*
X727917Y222717D01*
X728000Y223050D01*
X727917Y223383D01*
X727708Y223633D01*
X727458Y223800D01*
X727125Y223925D01*
X726750Y223967D01*
X726375Y223925D01*
X726042Y223800D01*
X725792Y223633D01*
X725583Y223383D01*
X725500Y223050D01*
G01Y226150D02*
X725583Y225817D01*
X725792Y225567D01*
X726042Y225400D01*
X726375Y225275D01*
X726750Y225233D01*
X727125Y225275D01*
X727458Y225400D01*
X727708Y225567D01*
X727917Y225817D01*
X728000Y226150D01*
X727917Y226483D01*
X727708Y226733D01*
X727458Y226900D01*
X727125Y227025D01*
X726750Y227067D01*
X726375Y227025D01*
X726042Y226900D01*
X725792Y226733D01*
X725583Y226483D01*
X725500Y226150D01*
G01X717517Y230000D02*
Y232500D01*
X718517D01*
X718850Y232375D01*
X719100Y232083D01*
X719183Y231750D01*
X719100Y231417D01*
X718892Y231167D01*
X718517Y231042D01*
X717517D01*
G01X722367Y232292D02*
X722117Y232417D01*
X721825Y232500D01*
X721492D01*
X721117Y232375D01*
X720825Y232167D01*
X720617Y231917D01*
X720450Y231500D01*
X720408Y231125D01*
X720492Y230750D01*
X720617Y230500D01*
X720867Y230250D01*
X721158Y230083D01*
X721450Y230000D01*
X721742D01*
X722033Y230083D01*
X722283Y230208D01*
X722492Y230375D01*
G01X724550Y230000D02*
X724842Y230042D01*
X725175Y230167D01*
X725383Y230375D01*
X725467Y230667D01*
X725383Y230958D01*
X725133Y231208D01*
X724758Y231333D01*
X724342D01*
X724092Y231417D01*
X723883Y231625D01*
X723800Y231917D01*
X723925Y232208D01*
X724217Y232417D01*
X724550Y232500D01*
X724883Y232417D01*
X725175Y232208D01*
X725300Y231917D01*
X725217Y231625D01*
X725008Y231417D01*
X724758Y231333D01*
X724342D01*
X723967Y231208D01*
X723717Y230958D01*
X723633Y230667D01*
X723717Y230375D01*
X723925Y230167D01*
X724258Y230042D01*
X724550Y230000D01*
G01X727567D02*
X727650Y230542D01*
X727775Y231000D01*
X727942Y231417D01*
X728150Y231875D01*
X728483Y232500D01*
X726817D01*
G01X715000Y229517D02*
X712500D01*
Y230517D01*
X712625Y230850D01*
X712917Y231100D01*
X713250Y231183D01*
X713583Y231100D01*
X713833Y230892D01*
X713958Y230517D01*
Y229517D01*
G01X712708Y234367D02*
X712583Y234117D01*
X712500Y233825D01*
Y233492D01*
X712625Y233117D01*
X712833Y232825D01*
X713083Y232617D01*
X713500Y232450D01*
X713875Y232408D01*
X714250Y232492D01*
X714500Y232617D01*
X714750Y232867D01*
X714917Y233158D01*
X715000Y233450D01*
Y233742D01*
X714917Y234033D01*
X714792Y234283D01*
X714625Y234492D01*
G01X715000Y236550D02*
X714958Y236842D01*
X714833Y237175D01*
X714625Y237383D01*
X714333Y237467D01*
X714042Y237383D01*
X713792Y237133D01*
X713667Y236758D01*
Y236342D01*
X713583Y236092D01*
X713375Y235883D01*
X713083Y235800D01*
X712792Y235925D01*
X712583Y236217D01*
X712500Y236550D01*
X712583Y236883D01*
X712792Y237175D01*
X713083Y237300D01*
X713375Y237217D01*
X713583Y237008D01*
X713667Y236758D01*
Y236342D01*
X713792Y235967D01*
X714042Y235717D01*
X714333Y235633D01*
X714625Y235717D01*
X714833Y235925D01*
X714958Y236258D01*
X715000Y236550D01*
G01X713958Y238858D02*
X713667Y239150D01*
X713500Y239400D01*
X713417Y239733D01*
X713500Y240025D01*
X713667Y240233D01*
X713917Y240400D01*
X714208Y240442D01*
X714458Y240400D01*
X714708Y240233D01*
X714917Y239983D01*
X715000Y239692D01*
X714917Y239358D01*
X714667Y239067D01*
X714292Y238900D01*
X713875Y238858D01*
X713333Y238942D01*
X713042Y239067D01*
X712750Y239275D01*
X712542Y239567D01*
X712500Y239858D01*
X712583Y240150D01*
X712792Y240358D01*
G01X717467Y234000D02*
Y236500D01*
X718467D01*
X718800Y236375D01*
X719050Y236083D01*
X719133Y235750D01*
X719050Y235417D01*
X718842Y235167D01*
X718467Y235042D01*
X717467D01*
G01X720567Y234000D02*
Y236500D01*
X721608D01*
X721942Y236375D01*
X722150Y236208D01*
X722233Y235875D01*
X722150Y235542D01*
X721900Y235333D01*
X721608Y235208D01*
X720567D01*
G01X721608D02*
X722233Y234000D01*
G01X724500D02*
Y236500D01*
X724000Y236000D01*
G01Y234000D02*
X725000D01*
G01X727600D02*
Y236500D01*
X727100Y236000D01*
G01Y234000D02*
X728100D01*
G01X729992Y234292D02*
X730283Y234083D01*
X730617Y234000D01*
X730950Y234083D01*
X731242Y234333D01*
X731450Y234708D01*
X731533Y235083D01*
Y235542D01*
X731450Y235917D01*
X731242Y236250D01*
X730992Y236417D01*
X730700Y236500D01*
X730367Y236417D01*
X730117Y236250D01*
X729950Y236000D01*
X729867Y235667D01*
X729950Y235375D01*
X730158Y235083D01*
X730408Y234917D01*
X730700Y234875D01*
X731033Y234958D01*
X731283Y235167D01*
X731533Y235542D01*
G01X717467Y238000D02*
Y240500D01*
X718467D01*
X718800Y240375D01*
X719050Y240083D01*
X719133Y239750D01*
X719050Y239417D01*
X718842Y239167D01*
X718467Y239042D01*
X717467D01*
G01X720567Y238000D02*
Y240500D01*
X721608D01*
X721942Y240375D01*
X722150Y240208D01*
X722233Y239875D01*
X722150Y239542D01*
X721900Y239333D01*
X721608Y239208D01*
X720567D01*
G01X721608D02*
X722233Y238000D01*
G01X724500D02*
Y240500D01*
X724000Y240000D01*
G01Y238000D02*
X725000D01*
G01X727600D02*
Y240500D01*
X727100Y240000D01*
G01Y238000D02*
X728100D01*
G01X729783Y238375D02*
X730033Y238167D01*
X730325Y238042D01*
X730700Y238000D01*
X731075Y238083D01*
X731367Y238250D01*
X731575Y238542D01*
X731617Y238875D01*
X731533Y239208D01*
X731325Y239417D01*
X731033Y239583D01*
X730742Y239625D01*
X730450Y239583D01*
X730075Y239417D01*
X730200Y240500D01*
X731325D01*
G01X738500Y50467D02*
X736000D01*
Y51467D01*
X736125Y51800D01*
X736417Y52050D01*
X736750Y52133D01*
X737083Y52050D01*
X737333Y51842D01*
X737458Y51467D01*
Y50467D01*
G01X738500Y53567D02*
X736000D01*
Y54608D01*
X736125Y54942D01*
X736292Y55150D01*
X736625Y55233D01*
X736958Y55150D01*
X737167Y54900D01*
X737292Y54608D01*
Y53567D01*
G01Y54608D02*
X738500Y55233D01*
G01Y57500D02*
X736000D01*
X736500Y57000D01*
G01X738500D02*
Y58000D01*
G01Y60517D02*
X737958Y60600D01*
X737500Y60725D01*
X737083Y60892D01*
X736625Y61100D01*
X736000Y61433D01*
Y59767D01*
G01Y63700D02*
X736083Y63367D01*
X736292Y63117D01*
X736542Y62950D01*
X736875Y62825D01*
X737250Y62783D01*
X737625Y62825D01*
X737958Y62950D01*
X738208Y63117D01*
X738417Y63367D01*
X738500Y63700D01*
X738417Y64033D01*
X738208Y64283D01*
X737958Y64450D01*
X737625Y64575D01*
X737250Y64617D01*
X736875Y64575D01*
X736542Y64450D01*
X736292Y64283D01*
X736083Y64033D01*
X736000Y63700D01*
G01X743267Y57292D02*
X743017Y57417D01*
X742725Y57500D01*
X742392D01*
X742017Y57375D01*
X741725Y57167D01*
X741517Y56917D01*
X741350Y56500D01*
X741308Y56125D01*
X741392Y55750D01*
X741517Y55500D01*
X741767Y55250D01*
X742058Y55083D01*
X742350Y55000D01*
X742642D01*
X742933Y55083D01*
X743183Y55208D01*
X743392Y55375D01*
G01X744658Y57083D02*
X744908Y57333D01*
X745200Y57458D01*
X745533Y57500D01*
X745950Y57417D01*
X746242Y57208D01*
X746325Y56958D01*
X746283Y56708D01*
X746117Y56500D01*
X745283Y56083D01*
X744908Y55792D01*
X744658Y55375D01*
X744575Y55000D01*
X746325D01*
G01X747842Y55292D02*
X748133Y55083D01*
X748467Y55000D01*
X748800Y55083D01*
X749092Y55333D01*
X749300Y55708D01*
X749383Y56083D01*
Y56542D01*
X749300Y56917D01*
X749092Y57250D01*
X748842Y57417D01*
X748550Y57500D01*
X748217Y57417D01*
X747967Y57250D01*
X747800Y57000D01*
X747717Y56667D01*
X747800Y56375D01*
X748008Y56083D01*
X748258Y55917D01*
X748550Y55875D01*
X748883Y55958D01*
X749133Y56167D01*
X749383Y56542D01*
G01X751650Y57500D02*
X751317Y57417D01*
X751067Y57208D01*
X750900Y56958D01*
X750775Y56625D01*
X750733Y56250D01*
X750775Y55875D01*
X750900Y55542D01*
X751067Y55292D01*
X751317Y55083D01*
X751650Y55000D01*
X751983Y55083D01*
X752233Y55292D01*
X752400Y55542D01*
X752525Y55875D01*
X752567Y56250D01*
X752525Y56625D01*
X752400Y56958D01*
X752233Y57208D01*
X751983Y57417D01*
X751650Y57500D01*
G01X739000Y85467D02*
X736500D01*
Y86467D01*
X736625Y86800D01*
X736917Y87050D01*
X737250Y87133D01*
X737583Y87050D01*
X737833Y86842D01*
X737958Y86467D01*
Y85467D01*
G01X739000Y88567D02*
X736500D01*
Y89608D01*
X736625Y89942D01*
X736792Y90150D01*
X737125Y90233D01*
X737458Y90150D01*
X737667Y89900D01*
X737792Y89608D01*
Y88567D01*
G01Y89608D02*
X739000Y90233D01*
G01Y92500D02*
X736500D01*
X737000Y92000D01*
G01X739000D02*
Y93000D01*
G01X737958Y94808D02*
X737667Y95100D01*
X737500Y95350D01*
X737417Y95683D01*
X737500Y95975D01*
X737667Y96183D01*
X737917Y96350D01*
X738208Y96392D01*
X738458Y96350D01*
X738708Y96183D01*
X738917Y95933D01*
X739000Y95642D01*
X738917Y95308D01*
X738667Y95017D01*
X738292Y94850D01*
X737875Y94808D01*
X737333Y94892D01*
X737042Y95017D01*
X736750Y95225D01*
X736542Y95517D01*
X736500Y95808D01*
X736583Y96100D01*
X736792Y96308D01*
G01X738625Y97783D02*
X738833Y98033D01*
X738958Y98325D01*
X739000Y98700D01*
X738917Y99075D01*
X738750Y99367D01*
X738458Y99575D01*
X738125Y99617D01*
X737792Y99533D01*
X737583Y99325D01*
X737417Y99033D01*
X737375Y98742D01*
X737417Y98450D01*
X737583Y98075D01*
X736500Y98200D01*
Y99325D01*
G01X735000Y99500D02*
X732500D01*
Y94000D01*
X728000D01*
G01X745500Y100000D02*
X752500D01*
Y117000D01*
X727500D01*
Y113500D01*
G01X738517Y119000D02*
Y121500D01*
X739517D01*
X739850Y121375D01*
X740100Y121083D01*
X740183Y120750D01*
X740100Y120417D01*
X739892Y120167D01*
X739517Y120042D01*
X738517D01*
G01X741533Y121500D02*
Y119708D01*
X741700Y119333D01*
X742033Y119083D01*
X742450Y119000D01*
X742867Y119083D01*
X743200Y119333D01*
X743367Y119708D01*
Y121500D01*
G01X745550Y119000D02*
Y121500D01*
X745050Y121000D01*
G01Y119000D02*
X746050D01*
G01X748650Y121500D02*
X748317Y121417D01*
X748067Y121208D01*
X747900Y120958D01*
X747775Y120625D01*
X747733Y120250D01*
X747775Y119875D01*
X747900Y119542D01*
X748067Y119292D01*
X748317Y119083D01*
X748650Y119000D01*
X748983Y119083D01*
X749233Y119292D01*
X749400Y119542D01*
X749525Y119875D01*
X749567Y120250D01*
X749525Y120625D01*
X749400Y120958D01*
X749233Y121208D01*
X748983Y121417D01*
X748650Y121500D01*
G01X737708Y166317D02*
X737583Y166067D01*
X737500Y165775D01*
Y165442D01*
X737625Y165067D01*
X737833Y164775D01*
X738083Y164567D01*
X738500Y164400D01*
X738875Y164358D01*
X739250Y164442D01*
X739500Y164567D01*
X739750Y164817D01*
X739917Y165108D01*
X740000Y165400D01*
Y165692D01*
X739917Y165983D01*
X739792Y166233D01*
X739625Y166442D01*
G01X739708Y167792D02*
X739917Y168083D01*
X740000Y168417D01*
X739917Y168750D01*
X739667Y169042D01*
X739292Y169250D01*
X738917Y169333D01*
X738458D01*
X738083Y169250D01*
X737750Y169042D01*
X737583Y168792D01*
X737500Y168500D01*
X737583Y168167D01*
X737750Y167917D01*
X738000Y167750D01*
X738333Y167667D01*
X738625Y167750D01*
X738917Y167958D01*
X739083Y168208D01*
X739125Y168500D01*
X739042Y168833D01*
X738833Y169083D01*
X738458Y169333D01*
G01X738958Y170808D02*
X738667Y171100D01*
X738500Y171350D01*
X738417Y171683D01*
X738500Y171975D01*
X738667Y172183D01*
X738917Y172350D01*
X739208Y172392D01*
X739458Y172350D01*
X739708Y172183D01*
X739917Y171933D01*
X740000Y171642D01*
X739917Y171308D01*
X739667Y171017D01*
X739292Y170850D01*
X738875Y170808D01*
X738333Y170892D01*
X738042Y171017D01*
X737750Y171225D01*
X737542Y171517D01*
X737500Y171808D01*
X737583Y172100D01*
X737792Y172308D01*
G01X733000Y181000D02*
Y178500D01*
G01X734000Y176500D02*
X741000D01*
Y177000D01*
G01Y185000D02*
X747500D01*
G01X738300Y186050D02*
X735700D01*
G01X738300Y193950D02*
Y186050D01*
G01X735700Y193950D02*
X738300D01*
G01X735700Y186050D02*
Y193950D01*
G01X726360Y204035D02*
Y196135D01*
G01X726850Y186050D02*
Y193950D01*
G01X732000Y200483D02*
X733792D01*
X734167Y200650D01*
X734417Y200983D01*
X734500Y201400D01*
X734417Y201817D01*
X734167Y202150D01*
X733792Y202317D01*
X732000D01*
G01X732417Y203708D02*
X732167Y203958D01*
X732042Y204250D01*
X732000Y204583D01*
X732083Y205000D01*
X732292Y205292D01*
X732542Y205375D01*
X732792Y205333D01*
X733000Y205167D01*
X733417Y204333D01*
X733708Y203958D01*
X734125Y203708D01*
X734500Y203625D01*
Y205375D01*
G01Y207517D02*
X733958Y207600D01*
X733500Y207725D01*
X733083Y207892D01*
X732625Y208100D01*
X732000Y208433D01*
Y206767D01*
G01X742500Y203517D02*
X740000D01*
Y204558D01*
X740125Y204892D01*
X740292Y205100D01*
X740625Y205183D01*
X740958Y205100D01*
X741167Y204850D01*
X741292Y204558D01*
Y203517D01*
G01Y204558D02*
X742500Y205183D01*
G01X740417Y206658D02*
X740167Y206908D01*
X740042Y207200D01*
X740000Y207533D01*
X740083Y207950D01*
X740292Y208242D01*
X740542Y208325D01*
X740792Y208283D01*
X741000Y208117D01*
X741417Y207283D01*
X741708Y206908D01*
X742125Y206658D01*
X742500Y206575D01*
Y208325D01*
G01X740000Y210550D02*
X740083Y210217D01*
X740292Y209967D01*
X740542Y209800D01*
X740875Y209675D01*
X741250Y209633D01*
X741625Y209675D01*
X741958Y209800D01*
X742208Y209967D01*
X742417Y210217D01*
X742500Y210550D01*
X742417Y210883D01*
X742208Y211133D01*
X741958Y211300D01*
X741625Y211425D01*
X741250Y211467D01*
X740875Y211425D01*
X740542Y211300D01*
X740292Y211133D01*
X740083Y210883D01*
X740000Y210550D01*
G01X742500Y213650D02*
X742458Y213942D01*
X742333Y214275D01*
X742125Y214483D01*
X741833Y214567D01*
X741542Y214483D01*
X741292Y214233D01*
X741167Y213858D01*
Y213442D01*
X741083Y213192D01*
X740875Y212983D01*
X740583Y212900D01*
X740292Y213025D01*
X740083Y213317D01*
X740000Y213650D01*
X740083Y213983D01*
X740292Y214275D01*
X740583Y214400D01*
X740875Y214317D01*
X741083Y214108D01*
X741167Y213858D01*
Y213442D01*
X741292Y213067D01*
X741542Y212817D01*
X741833Y212733D01*
X742125Y212817D01*
X742333Y213025D01*
X742458Y213358D01*
X742500Y213650D01*
G01X738500Y203517D02*
X736000D01*
Y204558D01*
X736125Y204892D01*
X736292Y205100D01*
X736625Y205183D01*
X736958Y205100D01*
X737167Y204850D01*
X737292Y204558D01*
Y203517D01*
G01Y204558D02*
X738500Y205183D01*
G01X736417Y206658D02*
X736167Y206908D01*
X736042Y207200D01*
X736000Y207533D01*
X736083Y207950D01*
X736292Y208242D01*
X736542Y208325D01*
X736792Y208283D01*
X737000Y208117D01*
X737417Y207283D01*
X737708Y206908D01*
X738125Y206658D01*
X738500Y206575D01*
Y208325D01*
G01X736000Y210550D02*
X736083Y210217D01*
X736292Y209967D01*
X736542Y209800D01*
X736875Y209675D01*
X737250Y209633D01*
X737625Y209675D01*
X737958Y209800D01*
X738208Y209967D01*
X738417Y210217D01*
X738500Y210550D01*
X738417Y210883D01*
X738208Y211133D01*
X737958Y211300D01*
X737625Y211425D01*
X737250Y211467D01*
X736875Y211425D01*
X736542Y211300D01*
X736292Y211133D01*
X736083Y210883D01*
X736000Y210550D01*
G01X738208Y212942D02*
X738417Y213233D01*
X738500Y213567D01*
X738417Y213900D01*
X738167Y214192D01*
X737792Y214400D01*
X737417Y214483D01*
X736958D01*
X736583Y214400D01*
X736250Y214192D01*
X736083Y213942D01*
X736000Y213650D01*
X736083Y213317D01*
X736250Y213067D01*
X736500Y212900D01*
X736833Y212817D01*
X737125Y212900D01*
X737417Y213108D01*
X737583Y213358D01*
X737625Y213650D01*
X737542Y213983D01*
X737333Y214233D01*
X736958Y214483D01*
G01X739600Y216567D02*
X737100D01*
Y217608D01*
X737225Y217942D01*
X737392Y218150D01*
X737725Y218233D01*
X738058Y218150D01*
X738267Y217900D01*
X738392Y217608D01*
Y216567D01*
G01Y217608D02*
X739600Y218233D01*
G01X737517Y219708D02*
X737267Y219958D01*
X737142Y220250D01*
X737100Y220583D01*
X737183Y221000D01*
X737392Y221292D01*
X737642Y221375D01*
X737892Y221333D01*
X738100Y221167D01*
X738517Y220333D01*
X738808Y219958D01*
X739225Y219708D01*
X739600Y219625D01*
Y221375D01*
G01X737100Y223600D02*
X737183Y223267D01*
X737392Y223017D01*
X737642Y222850D01*
X737975Y222725D01*
X738350Y222683D01*
X738725Y222725D01*
X739058Y222850D01*
X739308Y223017D01*
X739517Y223267D01*
X739600Y223600D01*
X739517Y223933D01*
X739308Y224183D01*
X739058Y224350D01*
X738725Y224475D01*
X738350Y224517D01*
X737975Y224475D01*
X737642Y224350D01*
X737392Y224183D01*
X737183Y223933D01*
X737100Y223600D01*
G01X739100Y225783D02*
X739392Y226033D01*
X739558Y226367D01*
X739600Y226742D01*
X739558Y227075D01*
X739350Y227408D01*
X739100Y227617D01*
X738850Y227658D01*
X738558Y227575D01*
X738350Y227283D01*
X738267Y226992D01*
Y226617D01*
G01Y226992D02*
X738142Y227242D01*
X737933Y227450D01*
X737683Y227533D01*
X737433Y227450D01*
X737225Y227242D01*
X737100Y226867D01*
X737142Y226492D01*
X737308Y226117D01*
G01X743600Y216567D02*
X741100D01*
Y217608D01*
X741225Y217942D01*
X741392Y218150D01*
X741725Y218233D01*
X742058Y218150D01*
X742267Y217900D01*
X742392Y217608D01*
Y216567D01*
G01Y217608D02*
X743600Y218233D01*
G01X741517Y219708D02*
X741267Y219958D01*
X741142Y220250D01*
X741100Y220583D01*
X741183Y221000D01*
X741392Y221292D01*
X741642Y221375D01*
X741892Y221333D01*
X742100Y221167D01*
X742517Y220333D01*
X742808Y219958D01*
X743225Y219708D01*
X743600Y219625D01*
Y221375D01*
G01X741100Y223600D02*
X741183Y223267D01*
X741392Y223017D01*
X741642Y222850D01*
X741975Y222725D01*
X742350Y222683D01*
X742725Y222725D01*
X743058Y222850D01*
X743308Y223017D01*
X743517Y223267D01*
X743600Y223600D01*
X743517Y223933D01*
X743308Y224183D01*
X743058Y224350D01*
X742725Y224475D01*
X742350Y224517D01*
X741975Y224475D01*
X741642Y224350D01*
X741392Y224183D01*
X741183Y223933D01*
X741100Y223600D01*
G01X743600Y227200D02*
X741100D01*
X742892Y225658D01*
Y227742D01*
G01X735600Y217067D02*
X733100D01*
Y218108D01*
X733225Y218442D01*
X733392Y218650D01*
X733725Y218733D01*
X734058Y218650D01*
X734267Y218400D01*
X734392Y218108D01*
Y217067D01*
G01Y218108D02*
X735600Y218733D01*
G01X733517Y220208D02*
X733267Y220458D01*
X733142Y220750D01*
X733100Y221083D01*
X733183Y221500D01*
X733392Y221792D01*
X733642Y221875D01*
X733892Y221833D01*
X734100Y221667D01*
X734517Y220833D01*
X734808Y220458D01*
X735225Y220208D01*
X735600Y220125D01*
Y221875D01*
G01X733100Y224100D02*
X733183Y223767D01*
X733392Y223517D01*
X733642Y223350D01*
X733975Y223225D01*
X734350Y223183D01*
X734725Y223225D01*
X735058Y223350D01*
X735308Y223517D01*
X735517Y223767D01*
X735600Y224100D01*
X735517Y224433D01*
X735308Y224683D01*
X735058Y224850D01*
X734725Y224975D01*
X734350Y225017D01*
X733975Y224975D01*
X733642Y224850D01*
X733392Y224683D01*
X733183Y224433D01*
X733100Y224100D01*
G01X733517Y226408D02*
X733267Y226658D01*
X733142Y226950D01*
X733100Y227283D01*
X733183Y227700D01*
X733392Y227992D01*
X733642Y228075D01*
X733892Y228033D01*
X734100Y227867D01*
X734517Y227033D01*
X734808Y226658D01*
X735225Y226408D01*
X735600Y226325D01*
Y228075D01*
G01X733708Y231267D02*
X733583Y231017D01*
X733500Y230725D01*
Y230392D01*
X733625Y230017D01*
X733833Y229725D01*
X734083Y229517D01*
X734500Y229350D01*
X734875Y229308D01*
X735250Y229392D01*
X735500Y229517D01*
X735750Y229767D01*
X735917Y230058D01*
X736000Y230350D01*
Y230642D01*
X735917Y230933D01*
X735792Y231183D01*
X735625Y231392D01*
G01X735500Y232533D02*
X735792Y232783D01*
X735958Y233117D01*
X736000Y233492D01*
X735958Y233825D01*
X735750Y234158D01*
X735500Y234367D01*
X735250Y234408D01*
X734958Y234325D01*
X734750Y234033D01*
X734667Y233742D01*
Y233367D01*
G01Y233742D02*
X734542Y233992D01*
X734333Y234200D01*
X734083Y234283D01*
X733833Y234200D01*
X733625Y233992D01*
X733500Y233617D01*
X733542Y233242D01*
X733708Y232867D01*
G01X735625Y235633D02*
X735833Y235883D01*
X735958Y236175D01*
X736000Y236550D01*
X735917Y236925D01*
X735750Y237217D01*
X735458Y237425D01*
X735125Y237467D01*
X734792Y237383D01*
X734583Y237175D01*
X734417Y236883D01*
X734375Y236592D01*
X734417Y236300D01*
X734583Y235925D01*
X733500Y236050D01*
Y237175D01*
G01X735500Y238733D02*
X735792Y238983D01*
X735958Y239317D01*
X736000Y239692D01*
X735958Y240025D01*
X735750Y240358D01*
X735500Y240567D01*
X735250Y240608D01*
X734958Y240525D01*
X734750Y240233D01*
X734667Y239942D01*
Y239567D01*
G01Y239942D02*
X734542Y240192D01*
X734333Y240400D01*
X734083Y240483D01*
X733833Y240400D01*
X733625Y240192D01*
X733500Y239817D01*
X733542Y239442D01*
X733708Y239067D01*
G01X754521Y43648D02*
X756421Y45548D01*
X752621D01*
Y45448D01*
X754471Y43598D01*
Y47998D01*
G01X743458Y49583D02*
X743708Y49833D01*
X744000Y49958D01*
X744333Y50000D01*
X744750Y49917D01*
X745042Y49708D01*
X745125Y49458D01*
X745083Y49208D01*
X744917Y49000D01*
X744083Y48583D01*
X743708Y48292D01*
X743458Y47875D01*
X743375Y47500D01*
X745125D01*
G01X747350Y50000D02*
X747017Y49917D01*
X746767Y49708D01*
X746600Y49458D01*
X746475Y49125D01*
X746433Y48750D01*
X746475Y48375D01*
X746600Y48042D01*
X746767Y47792D01*
X747017Y47583D01*
X747350Y47500D01*
X747683Y47583D01*
X747933Y47792D01*
X748100Y48042D01*
X748225Y48375D01*
X748267Y48750D01*
X748225Y49125D01*
X748100Y49458D01*
X747933Y49708D01*
X747683Y49917D01*
X747350Y50000D01*
G01X750950Y47500D02*
Y50000D01*
X749408Y48208D01*
X751492D01*
G01X750000Y68967D02*
X747500D01*
Y69967D01*
X747625Y70300D01*
X747917Y70550D01*
X748250Y70633D01*
X748583Y70550D01*
X748833Y70342D01*
X748958Y69967D01*
Y68967D01*
G01X747708Y73817D02*
X747583Y73567D01*
X747500Y73275D01*
Y72942D01*
X747625Y72567D01*
X747833Y72275D01*
X748083Y72067D01*
X748500Y71900D01*
X748875Y71858D01*
X749250Y71942D01*
X749500Y72067D01*
X749750Y72317D01*
X749917Y72608D01*
X750000Y72900D01*
Y73192D01*
X749917Y73483D01*
X749792Y73733D01*
X749625Y73942D01*
G01X750000Y76000D02*
X747500D01*
X748000Y75500D01*
G01X750000D02*
Y76500D01*
G01Y79100D02*
X747500D01*
X748000Y78600D01*
G01X750000D02*
Y79600D01*
G01X748958Y81408D02*
X748667Y81700D01*
X748500Y81950D01*
X748417Y82283D01*
X748500Y82575D01*
X748667Y82783D01*
X748917Y82950D01*
X749208Y82992D01*
X749458Y82950D01*
X749708Y82783D01*
X749917Y82533D01*
X750000Y82242D01*
X749917Y81908D01*
X749667Y81617D01*
X749292Y81450D01*
X748875Y81408D01*
X748333Y81492D01*
X748042Y81617D01*
X747750Y81825D01*
X747542Y82117D01*
X747500Y82408D01*
X747583Y82700D01*
X747792Y82908D01*
G01X752100Y84467D02*
X749600D01*
Y85467D01*
X749725Y85800D01*
X750017Y86050D01*
X750350Y86133D01*
X750683Y86050D01*
X750933Y85842D01*
X751058Y85467D01*
Y84467D01*
G01X749808Y89317D02*
X749683Y89067D01*
X749600Y88775D01*
Y88442D01*
X749725Y88067D01*
X749933Y87775D01*
X750183Y87567D01*
X750600Y87400D01*
X750975Y87358D01*
X751350Y87442D01*
X751600Y87567D01*
X751850Y87817D01*
X752017Y88108D01*
X752100Y88400D01*
Y88692D01*
X752017Y88983D01*
X751892Y89233D01*
X751725Y89442D01*
G01X752100Y91500D02*
X749600D01*
X750100Y91000D01*
G01X752100D02*
Y92000D01*
G01Y94600D02*
X749600D01*
X750100Y94100D01*
G01X752100D02*
Y95100D01*
G01Y98200D02*
X749600D01*
X751392Y96658D01*
Y98742D01*
G01X748400Y84467D02*
X745900D01*
Y85467D01*
X746025Y85800D01*
X746317Y86050D01*
X746650Y86133D01*
X746983Y86050D01*
X747233Y85842D01*
X747358Y85467D01*
Y84467D01*
G01X748400Y87567D02*
X745900D01*
Y88608D01*
X746025Y88942D01*
X746192Y89150D01*
X746525Y89233D01*
X746858Y89150D01*
X747067Y88900D01*
X747192Y88608D01*
Y87567D01*
G01Y88608D02*
X748400Y89233D01*
G01Y91500D02*
X745900D01*
X746400Y91000D01*
G01X748400D02*
Y92000D01*
G01X747358Y93808D02*
X747067Y94100D01*
X746900Y94350D01*
X746817Y94683D01*
X746900Y94975D01*
X747067Y95183D01*
X747317Y95350D01*
X747608Y95392D01*
X747858Y95350D01*
X748108Y95183D01*
X748317Y94933D01*
X748400Y94642D01*
X748317Y94308D01*
X748067Y94017D01*
X747692Y93850D01*
X747275Y93808D01*
X746733Y93892D01*
X746442Y94017D01*
X746150Y94225D01*
X745942Y94517D01*
X745900Y94808D01*
X745983Y95100D01*
X746192Y95308D01*
G01X747358Y96908D02*
X747067Y97200D01*
X746900Y97450D01*
X746817Y97783D01*
X746900Y98075D01*
X747067Y98283D01*
X747317Y98450D01*
X747608Y98492D01*
X747858Y98450D01*
X748108Y98283D01*
X748317Y98033D01*
X748400Y97742D01*
X748317Y97408D01*
X748067Y97117D01*
X747692Y96950D01*
X747275Y96908D01*
X746733Y96992D01*
X746442Y97117D01*
X746150Y97325D01*
X745942Y97617D01*
X745900Y97908D01*
X745983Y98200D01*
X746192Y98408D01*
G01X759500Y148467D02*
X757000D01*
Y149467D01*
X757125Y149800D01*
X757417Y150050D01*
X757750Y150133D01*
X758083Y150050D01*
X758333Y149842D01*
X758458Y149467D01*
Y148467D01*
G01X759500Y151567D02*
X757000D01*
Y152608D01*
X757125Y152942D01*
X757292Y153150D01*
X757625Y153233D01*
X757958Y153150D01*
X758167Y152900D01*
X758292Y152608D01*
Y151567D01*
G01Y152608D02*
X759500Y153233D01*
G01Y155500D02*
X757000D01*
X757500Y155000D01*
G01X759500D02*
Y156000D01*
G01X757417Y157808D02*
X757167Y158058D01*
X757042Y158350D01*
X757000Y158683D01*
X757083Y159100D01*
X757292Y159392D01*
X757542Y159475D01*
X757792Y159433D01*
X758000Y159267D01*
X758417Y158433D01*
X758708Y158058D01*
X759125Y157808D01*
X759500Y157725D01*
Y159475D01*
G01X759125Y160783D02*
X759333Y161033D01*
X759458Y161325D01*
X759500Y161700D01*
X759417Y162075D01*
X759250Y162367D01*
X758958Y162575D01*
X758625Y162617D01*
X758292Y162533D01*
X758083Y162325D01*
X757917Y162033D01*
X757875Y161742D01*
X757917Y161450D01*
X758083Y161075D01*
X757000Y161200D01*
Y162325D01*
G01X746250Y168500D02*
Y173500D01*
G01X742750D02*
Y168500D01*
G01Y171000D02*
X746250D01*
G01X749500Y160500D02*
Y162000D01*
X746500D01*
Y163000D01*
G01X747967Y164500D02*
Y167000D01*
X748967D01*
X749300Y166875D01*
X749550Y166583D01*
X749633Y166250D01*
X749550Y165917D01*
X749342Y165667D01*
X748967Y165542D01*
X747967D01*
G01X751067Y164500D02*
Y167000D01*
X752108D01*
X752442Y166875D01*
X752650Y166708D01*
X752733Y166375D01*
X752650Y166042D01*
X752400Y165833D01*
X752108Y165708D01*
X751067D01*
G01X752108D02*
X752733Y164500D01*
G01X755000D02*
Y167000D01*
X754500Y166500D01*
G01Y164500D02*
X755500D01*
G01X757308Y166583D02*
X757558Y166833D01*
X757850Y166958D01*
X758183Y167000D01*
X758600Y166917D01*
X758892Y166708D01*
X758975Y166458D01*
X758933Y166208D01*
X758767Y166000D01*
X757933Y165583D01*
X757558Y165292D01*
X757308Y164875D01*
X757225Y164500D01*
X758975D01*
G01X761700D02*
Y167000D01*
X760158Y165208D01*
X762242D01*
G01X742833Y178000D02*
X743250Y177500D01*
X743750Y177167D01*
X744333Y177000D01*
X745000Y177167D01*
X745500Y177500D01*
X746000Y178000D01*
X746167Y178667D01*
Y182000D01*
G01X742000Y176000D02*
X748000D01*
G01X743708Y196817D02*
X743583Y196567D01*
X743500Y196275D01*
Y195942D01*
X743625Y195567D01*
X743833Y195275D01*
X744083Y195067D01*
X744500Y194900D01*
X744875Y194858D01*
X745250Y194942D01*
X745500Y195067D01*
X745750Y195317D01*
X745917Y195608D01*
X746000Y195900D01*
Y196192D01*
X745917Y196483D01*
X745792Y196733D01*
X745625Y196942D01*
G01X745708Y198292D02*
X745917Y198583D01*
X746000Y198917D01*
X745917Y199250D01*
X745667Y199542D01*
X745292Y199750D01*
X744917Y199833D01*
X744458D01*
X744083Y199750D01*
X743750Y199542D01*
X743583Y199292D01*
X743500Y199000D01*
X743583Y198667D01*
X743750Y198417D01*
X744000Y198250D01*
X744333Y198167D01*
X744625Y198250D01*
X744917Y198458D01*
X745083Y198708D01*
X745125Y199000D01*
X745042Y199333D01*
X744833Y199583D01*
X744458Y199833D01*
G01X746000Y202600D02*
X743500D01*
X745292Y201058D01*
Y203142D01*
G01X743708Y230867D02*
X743583Y230617D01*
X743500Y230325D01*
Y229992D01*
X743625Y229617D01*
X743833Y229325D01*
X744083Y229117D01*
X744500Y228950D01*
X744875Y228908D01*
X745250Y228992D01*
X745500Y229117D01*
X745750Y229367D01*
X745917Y229658D01*
X746000Y229950D01*
Y230242D01*
X745917Y230533D01*
X745792Y230783D01*
X745625Y230992D01*
G01X743917Y232258D02*
X743667Y232508D01*
X743542Y232800D01*
X743500Y233133D01*
X743583Y233550D01*
X743792Y233842D01*
X744042Y233925D01*
X744292Y233883D01*
X744500Y233717D01*
X744917Y232883D01*
X745208Y232508D01*
X745625Y232258D01*
X746000Y232175D01*
Y233925D01*
G01X752250Y288500D02*
Y286000D01*
X752750Y286500D01*
G01Y288500D02*
X751750D01*
G01X748616Y283398D02*
Y283448D01*
X750566Y285398D01*
X750466Y285498D01*
X746666D01*
Y285298D01*
X748616Y283348D01*
Y287598D01*
G01X769967Y120500D02*
Y123000D01*
X770967D01*
X771300Y122875D01*
X771550Y122583D01*
X771633Y122250D01*
X771550Y121917D01*
X771342Y121667D01*
X770967Y121542D01*
X769967D01*
G01X773067Y120500D02*
Y123000D01*
X774108D01*
X774442Y122875D01*
X774650Y122708D01*
X774733Y122375D01*
X774650Y122042D01*
X774400Y121833D01*
X774108Y121708D01*
X773067D01*
G01X774108D02*
X774733Y120500D01*
G01X777000D02*
Y123000D01*
X776500Y122500D01*
G01Y120500D02*
X777500D01*
G01X779183Y121000D02*
X779433Y120708D01*
X779767Y120542D01*
X780142Y120500D01*
X780475Y120542D01*
X780808Y120750D01*
X781017Y121000D01*
X781058Y121250D01*
X780975Y121542D01*
X780683Y121750D01*
X780392Y121833D01*
X780017D01*
G01X780392D02*
X780642Y121958D01*
X780850Y122167D01*
X780933Y122417D01*
X780850Y122667D01*
X780642Y122875D01*
X780267Y123000D01*
X779892Y122958D01*
X779517Y122792D01*
G01X782492Y120792D02*
X782783Y120583D01*
X783117Y120500D01*
X783450Y120583D01*
X783742Y120833D01*
X783950Y121208D01*
X784033Y121583D01*
Y122042D01*
X783950Y122417D01*
X783742Y122750D01*
X783492Y122917D01*
X783200Y123000D01*
X782867Y122917D01*
X782617Y122750D01*
X782450Y122500D01*
X782367Y122167D01*
X782450Y121875D01*
X782658Y121583D01*
X782908Y121417D01*
X783200Y121375D01*
X783533Y121458D01*
X783783Y121667D01*
X784033Y122042D01*
G01X770017Y124000D02*
Y126500D01*
X771017D01*
X771350Y126375D01*
X771600Y126083D01*
X771683Y125750D01*
X771600Y125417D01*
X771392Y125167D01*
X771017Y125042D01*
X770017D01*
G01X774867Y126292D02*
X774617Y126417D01*
X774325Y126500D01*
X773992D01*
X773617Y126375D01*
X773325Y126167D01*
X773117Y125917D01*
X772950Y125500D01*
X772908Y125125D01*
X772992Y124750D01*
X773117Y124500D01*
X773367Y124250D01*
X773658Y124083D01*
X773950Y124000D01*
X774242D01*
X774533Y124083D01*
X774783Y124208D01*
X774992Y124375D01*
G01X776342Y124292D02*
X776633Y124083D01*
X776967Y124000D01*
X777300Y124083D01*
X777592Y124333D01*
X777800Y124708D01*
X777883Y125083D01*
Y125542D01*
X777800Y125917D01*
X777592Y126250D01*
X777342Y126417D01*
X777050Y126500D01*
X776717Y126417D01*
X776467Y126250D01*
X776300Y126000D01*
X776217Y125667D01*
X776300Y125375D01*
X776508Y125083D01*
X776758Y124917D01*
X777050Y124875D01*
X777383Y124958D01*
X777633Y125167D01*
X777883Y125542D01*
G01X779233Y124375D02*
X779483Y124167D01*
X779775Y124042D01*
X780150Y124000D01*
X780525Y124083D01*
X780817Y124250D01*
X781025Y124542D01*
X781067Y124875D01*
X780983Y125208D01*
X780775Y125417D01*
X780483Y125583D01*
X780192Y125625D01*
X779900Y125583D01*
X779525Y125417D01*
X779650Y126500D01*
X780775D01*
G01X760000Y124467D02*
X757500D01*
Y125467D01*
X757625Y125800D01*
X757917Y126050D01*
X758250Y126133D01*
X758583Y126050D01*
X758833Y125842D01*
X758958Y125467D01*
Y124467D01*
G01X760000Y127567D02*
X757500D01*
Y128608D01*
X757625Y128942D01*
X757792Y129150D01*
X758125Y129233D01*
X758458Y129150D01*
X758667Y128900D01*
X758792Y128608D01*
Y127567D01*
G01Y128608D02*
X760000Y129233D01*
G01Y131500D02*
X757500D01*
X758000Y131000D01*
G01X760000D02*
Y132000D01*
G01Y135100D02*
X757500D01*
X759292Y133558D01*
Y135642D01*
G01X759500Y136783D02*
X759792Y137033D01*
X759958Y137367D01*
X760000Y137742D01*
X759958Y138075D01*
X759750Y138408D01*
X759500Y138617D01*
X759250Y138658D01*
X758958Y138575D01*
X758750Y138283D01*
X758667Y137992D01*
Y137617D01*
G01Y137992D02*
X758542Y138242D01*
X758333Y138450D01*
X758083Y138533D01*
X757833Y138450D01*
X757625Y138242D01*
X757500Y137867D01*
X757542Y137492D01*
X757708Y137117D01*
G01X771500Y141967D02*
X769000D01*
Y142967D01*
X769125Y143300D01*
X769417Y143550D01*
X769750Y143633D01*
X770083Y143550D01*
X770333Y143342D01*
X770458Y142967D01*
Y141967D01*
G01X771500Y145067D02*
X769000D01*
Y146108D01*
X769125Y146442D01*
X769292Y146650D01*
X769625Y146733D01*
X769958Y146650D01*
X770167Y146400D01*
X770292Y146108D01*
Y145067D01*
G01Y146108D02*
X771500Y146733D01*
G01Y149000D02*
X769000D01*
X769500Y148500D01*
G01X771500D02*
Y149500D01*
G01X771000Y151183D02*
X771292Y151433D01*
X771458Y151767D01*
X771500Y152142D01*
X771458Y152475D01*
X771250Y152808D01*
X771000Y153017D01*
X770750Y153058D01*
X770458Y152975D01*
X770250Y152683D01*
X770167Y152392D01*
Y152017D01*
G01Y152392D02*
X770042Y152642D01*
X769833Y152850D01*
X769583Y152933D01*
X769333Y152850D01*
X769125Y152642D01*
X769000Y152267D01*
X769042Y151892D01*
X769208Y151517D01*
G01X771500Y155117D02*
X770958Y155200D01*
X770500Y155325D01*
X770083Y155492D01*
X769625Y155700D01*
X769000Y156033D01*
Y154367D01*
G01X764517Y164500D02*
Y167000D01*
X765517D01*
X765850Y166875D01*
X766100Y166583D01*
X766183Y166250D01*
X766100Y165917D01*
X765892Y165667D01*
X765517Y165542D01*
X764517D01*
G01X769367Y166792D02*
X769117Y166917D01*
X768825Y167000D01*
X768492D01*
X768117Y166875D01*
X767825Y166667D01*
X767617Y166417D01*
X767450Y166000D01*
X767408Y165625D01*
X767492Y165250D01*
X767617Y165000D01*
X767867Y164750D01*
X768158Y164583D01*
X768450Y164500D01*
X768742D01*
X769033Y164583D01*
X769283Y164708D01*
X769492Y164875D01*
G01X770842Y164792D02*
X771133Y164583D01*
X771467Y164500D01*
X771800Y164583D01*
X772092Y164833D01*
X772300Y165208D01*
X772383Y165583D01*
Y166042D01*
X772300Y166417D01*
X772092Y166750D01*
X771842Y166917D01*
X771550Y167000D01*
X771217Y166917D01*
X770967Y166750D01*
X770800Y166500D01*
X770717Y166167D01*
X770800Y165875D01*
X771008Y165583D01*
X771258Y165417D01*
X771550Y165375D01*
X771883Y165458D01*
X772133Y165667D01*
X772383Y166042D01*
G01X773733Y165000D02*
X773983Y164708D01*
X774317Y164542D01*
X774692Y164500D01*
X775025Y164542D01*
X775358Y164750D01*
X775567Y165000D01*
X775608Y165250D01*
X775525Y165542D01*
X775233Y165750D01*
X774942Y165833D01*
X774567D01*
G01X774942D02*
X775192Y165958D01*
X775400Y166167D01*
X775483Y166417D01*
X775400Y166667D01*
X775192Y166875D01*
X774817Y167000D01*
X774442Y166958D01*
X774067Y166792D01*
G01X761467Y160500D02*
Y163000D01*
X762467D01*
X762800Y162875D01*
X763050Y162583D01*
X763133Y162250D01*
X763050Y161917D01*
X762842Y161667D01*
X762467Y161542D01*
X761467D01*
G01X764567Y160500D02*
Y163000D01*
X765608D01*
X765942Y162875D01*
X766150Y162708D01*
X766233Y162375D01*
X766150Y162042D01*
X765900Y161833D01*
X765608Y161708D01*
X764567D01*
G01X765608D02*
X766233Y160500D01*
G01X768500D02*
Y163000D01*
X768000Y162500D01*
G01Y160500D02*
X769000D01*
G01X770683Y161000D02*
X770933Y160708D01*
X771267Y160542D01*
X771642Y160500D01*
X771975Y160542D01*
X772308Y160750D01*
X772517Y161000D01*
X772558Y161250D01*
X772475Y161542D01*
X772183Y161750D01*
X771892Y161833D01*
X771517D01*
G01X771892D02*
X772142Y161958D01*
X772350Y162167D01*
X772433Y162417D01*
X772350Y162667D01*
X772142Y162875D01*
X771767Y163000D01*
X771392Y162958D01*
X771017Y162792D01*
G01X773783Y161000D02*
X774033Y160708D01*
X774367Y160542D01*
X774742Y160500D01*
X775075Y160542D01*
X775408Y160750D01*
X775617Y161000D01*
X775658Y161250D01*
X775575Y161542D01*
X775283Y161750D01*
X774992Y161833D01*
X774617D01*
G01X774992D02*
X775242Y161958D01*
X775450Y162167D01*
X775533Y162417D01*
X775450Y162667D01*
X775242Y162875D01*
X774867Y163000D01*
X774492Y162958D01*
X774117Y162792D01*
G01X772500Y279500D02*
X794500D01*
Y265500D01*
X769500D01*
Y279500D01*
X773000D01*
G01X786317Y7792D02*
X786067Y7917D01*
X785775Y8000D01*
X785442D01*
X785067Y7875D01*
X784775Y7667D01*
X784567Y7417D01*
X784400Y7000D01*
X784358Y6625D01*
X784442Y6250D01*
X784567Y6000D01*
X784817Y5750D01*
X785108Y5583D01*
X785400Y5500D01*
X785692D01*
X785983Y5583D01*
X786233Y5708D01*
X786442Y5875D01*
G01X788500Y5500D02*
X788792Y5542D01*
X789125Y5667D01*
X789333Y5875D01*
X789417Y6167D01*
X789333Y6458D01*
X789083Y6708D01*
X788708Y6833D01*
X788292D01*
X788042Y6917D01*
X787833Y7125D01*
X787750Y7417D01*
X787875Y7708D01*
X788167Y7917D01*
X788500Y8000D01*
X788833Y7917D01*
X789125Y7708D01*
X789250Y7417D01*
X789167Y7125D01*
X788958Y6917D01*
X788708Y6833D01*
X788292D01*
X787917Y6708D01*
X787667Y6458D01*
X787583Y6167D01*
X787667Y5875D01*
X787875Y5667D01*
X788208Y5542D01*
X788500Y5500D01*
G01X791517D02*
X791600Y6042D01*
X791725Y6500D01*
X791892Y6917D01*
X792100Y7375D01*
X792433Y8000D01*
X790767D01*
G01X786317Y3792D02*
X786067Y3917D01*
X785775Y4000D01*
X785442D01*
X785067Y3875D01*
X784775Y3667D01*
X784567Y3417D01*
X784400Y3000D01*
X784358Y2625D01*
X784442Y2250D01*
X784567Y2000D01*
X784817Y1750D01*
X785108Y1583D01*
X785400Y1500D01*
X785692D01*
X785983Y1583D01*
X786233Y1708D01*
X786442Y1875D01*
G01X787792Y1792D02*
X788083Y1583D01*
X788417Y1500D01*
X788750Y1583D01*
X789042Y1833D01*
X789250Y2208D01*
X789333Y2583D01*
Y3042D01*
X789250Y3417D01*
X789042Y3750D01*
X788792Y3917D01*
X788500Y4000D01*
X788167Y3917D01*
X787917Y3750D01*
X787750Y3500D01*
X787667Y3167D01*
X787750Y2875D01*
X787958Y2583D01*
X788208Y2417D01*
X788500Y2375D01*
X788833Y2458D01*
X789083Y2667D01*
X789333Y3042D01*
G01X791600Y4000D02*
X791267Y3917D01*
X791017Y3708D01*
X790850Y3458D01*
X790725Y3125D01*
X790683Y2750D01*
X790725Y2375D01*
X790850Y2042D01*
X791017Y1792D01*
X791267Y1583D01*
X791600Y1500D01*
X791933Y1583D01*
X792183Y1792D01*
X792350Y2042D01*
X792475Y2375D01*
X792517Y2750D01*
X792475Y3125D01*
X792350Y3458D01*
X792183Y3708D01*
X791933Y3917D01*
X791600Y4000D01*
G01X776817Y3292D02*
X776567Y3417D01*
X776275Y3500D01*
X775942D01*
X775567Y3375D01*
X775275Y3167D01*
X775067Y2917D01*
X774900Y2500D01*
X774858Y2125D01*
X774942Y1750D01*
X775067Y1500D01*
X775317Y1250D01*
X775608Y1083D01*
X775900Y1000D01*
X776192D01*
X776483Y1083D01*
X776733Y1208D01*
X776942Y1375D01*
G01X778292Y1292D02*
X778583Y1083D01*
X778917Y1000D01*
X779250Y1083D01*
X779542Y1333D01*
X779750Y1708D01*
X779833Y2083D01*
Y2542D01*
X779750Y2917D01*
X779542Y3250D01*
X779292Y3417D01*
X779000Y3500D01*
X778667Y3417D01*
X778417Y3250D01*
X778250Y3000D01*
X778167Y2667D01*
X778250Y2375D01*
X778458Y2083D01*
X778708Y1917D01*
X779000Y1875D01*
X779333Y1958D01*
X779583Y2167D01*
X779833Y2542D01*
G01X782100Y1000D02*
Y3500D01*
X781600Y3000D01*
G01Y1000D02*
X782600D01*
G01X784017Y9500D02*
Y12000D01*
X785058D01*
X785392Y11875D01*
X785600Y11708D01*
X785683Y11375D01*
X785600Y11042D01*
X785350Y10833D01*
X785058Y10708D01*
X784017D01*
G01X785058D02*
X785683Y9500D01*
G01X787033Y10000D02*
X787283Y9708D01*
X787617Y9542D01*
X787992Y9500D01*
X788325Y9542D01*
X788658Y9750D01*
X788867Y10000D01*
X788908Y10250D01*
X788825Y10542D01*
X788533Y10750D01*
X788242Y10833D01*
X787867D01*
G01X788242D02*
X788492Y10958D01*
X788700Y11167D01*
X788783Y11417D01*
X788700Y11667D01*
X788492Y11875D01*
X788117Y12000D01*
X787742Y11958D01*
X787367Y11792D01*
G01X791050Y9500D02*
X791342Y9542D01*
X791675Y9667D01*
X791883Y9875D01*
X791967Y10167D01*
X791883Y10458D01*
X791633Y10708D01*
X791258Y10833D01*
X790842D01*
X790592Y10917D01*
X790383Y11125D01*
X790300Y11417D01*
X790425Y11708D01*
X790717Y11917D01*
X791050Y12000D01*
X791383Y11917D01*
X791675Y11708D01*
X791800Y11417D01*
X791717Y11125D01*
X791508Y10917D01*
X791258Y10833D01*
X790842D01*
X790467Y10708D01*
X790217Y10458D01*
X790133Y10167D01*
X790217Y9875D01*
X790425Y9667D01*
X790758Y9542D01*
X791050Y9500D01*
G01X793442Y9792D02*
X793733Y9583D01*
X794067Y9500D01*
X794400Y9583D01*
X794692Y9833D01*
X794900Y10208D01*
X794983Y10583D01*
Y11042D01*
X794900Y11417D01*
X794692Y11750D01*
X794442Y11917D01*
X794150Y12000D01*
X793817Y11917D01*
X793567Y11750D01*
X793400Y11500D01*
X793317Y11167D01*
X793400Y10875D01*
X793608Y10583D01*
X793858Y10417D01*
X794150Y10375D01*
X794483Y10458D01*
X794733Y10667D01*
X794983Y11042D01*
G01X780500Y40517D02*
X778000D01*
Y41558D01*
X778125Y41892D01*
X778292Y42100D01*
X778625Y42183D01*
X778958Y42100D01*
X779167Y41850D01*
X779292Y41558D01*
Y40517D01*
G01Y41558D02*
X780500Y42183D01*
G01X780000Y43533D02*
X780292Y43783D01*
X780458Y44117D01*
X780500Y44492D01*
X780458Y44825D01*
X780250Y45158D01*
X780000Y45367D01*
X779750Y45408D01*
X779458Y45325D01*
X779250Y45033D01*
X779167Y44742D01*
Y44367D01*
G01Y44742D02*
X779042Y44992D01*
X778833Y45200D01*
X778583Y45283D01*
X778333Y45200D01*
X778125Y44992D01*
X778000Y44617D01*
X778042Y44242D01*
X778208Y43867D01*
G01X780000Y46633D02*
X780292Y46883D01*
X780458Y47217D01*
X780500Y47592D01*
X780458Y47925D01*
X780250Y48258D01*
X780000Y48467D01*
X779750Y48508D01*
X779458Y48425D01*
X779250Y48133D01*
X779167Y47842D01*
Y47467D01*
G01Y47842D02*
X779042Y48092D01*
X778833Y48300D01*
X778583Y48383D01*
X778333Y48300D01*
X778125Y48092D01*
X778000Y47717D01*
X778042Y47342D01*
X778208Y46967D01*
G01X780208Y49942D02*
X780417Y50233D01*
X780500Y50567D01*
X780417Y50900D01*
X780167Y51192D01*
X779792Y51400D01*
X779417Y51483D01*
X778958D01*
X778583Y51400D01*
X778250Y51192D01*
X778083Y50942D01*
X778000Y50650D01*
X778083Y50317D01*
X778250Y50067D01*
X778500Y49900D01*
X778833Y49817D01*
X779125Y49900D01*
X779417Y50108D01*
X779583Y50358D01*
X779625Y50650D01*
X779542Y50983D01*
X779333Y51233D01*
X778958Y51483D01*
G01X786000Y209383D02*
X783500D01*
Y210217D01*
X783625Y210550D01*
X783792Y210800D01*
X784042Y211008D01*
X784333Y211175D01*
X784750Y211217D01*
X785167Y211175D01*
X785458Y211008D01*
X785708Y210800D01*
X785875Y210550D01*
X786000Y210217D01*
Y209383D01*
G01X783500Y212900D02*
Y213900D01*
G01Y213400D02*
X786000D01*
G01Y212900D02*
Y213900D01*
G01Y215417D02*
X783500D01*
X785583Y216500D01*
X783500Y217583D01*
X786000D01*
G01Y218517D02*
X783500D01*
X785583Y219600D01*
X783500Y220683D01*
X786000D01*
G01X783917Y221908D02*
X783667Y222158D01*
X783542Y222450D01*
X783500Y222783D01*
X783583Y223200D01*
X783792Y223492D01*
X784042Y223575D01*
X784292Y223533D01*
X784500Y223367D01*
X784917Y222533D01*
X785208Y222158D01*
X785625Y221908D01*
X786000Y221825D01*
Y223575D01*
G01X785833Y269900D02*
X786500Y269200D01*
X787300Y268733D01*
X788233Y268500D01*
X789300Y268733D01*
X790100Y269200D01*
X790900Y269900D01*
X791167Y270833D01*
Y275500D01*
G01X783000Y267017D02*
X780500D01*
Y268058D01*
X780625Y268392D01*
X780792Y268600D01*
X781125Y268683D01*
X781458Y268600D01*
X781667Y268350D01*
X781792Y268058D01*
Y267017D01*
G01Y268058D02*
X783000Y268683D01*
G01X780917Y270158D02*
X780667Y270408D01*
X780542Y270700D01*
X780500Y271033D01*
X780583Y271450D01*
X780792Y271742D01*
X781042Y271825D01*
X781292Y271783D01*
X781500Y271617D01*
X781917Y270783D01*
X782208Y270408D01*
X782625Y270158D01*
X783000Y270075D01*
Y271825D01*
G01X780917Y273258D02*
X780667Y273508D01*
X780542Y273800D01*
X780500Y274133D01*
X780583Y274550D01*
X780792Y274842D01*
X781042Y274925D01*
X781292Y274883D01*
X781500Y274717D01*
X781917Y273883D01*
X782208Y273508D01*
X782625Y273258D01*
X783000Y273175D01*
Y274925D01*
G01X780500Y277150D02*
X780583Y276817D01*
X780792Y276567D01*
X781042Y276400D01*
X781375Y276275D01*
X781750Y276233D01*
X782125Y276275D01*
X782458Y276400D01*
X782708Y276567D01*
X782917Y276817D01*
X783000Y277150D01*
X782917Y277483D01*
X782708Y277733D01*
X782458Y277900D01*
X782125Y278025D01*
X781750Y278067D01*
X781375Y278025D01*
X781042Y277900D01*
X780792Y277733D01*
X780583Y277483D01*
X780500Y277150D01*
G01X775000Y267017D02*
X772500D01*
Y268058D01*
X772625Y268392D01*
X772792Y268600D01*
X773125Y268683D01*
X773458Y268600D01*
X773667Y268350D01*
X773792Y268058D01*
Y267017D01*
G01Y268058D02*
X775000Y268683D01*
G01X772917Y270158D02*
X772667Y270408D01*
X772542Y270700D01*
X772500Y271033D01*
X772583Y271450D01*
X772792Y271742D01*
X773042Y271825D01*
X773292Y271783D01*
X773500Y271617D01*
X773917Y270783D01*
X774208Y270408D01*
X774625Y270158D01*
X775000Y270075D01*
Y271825D01*
G01Y274050D02*
X772500D01*
X773000Y273550D01*
G01X775000D02*
Y274550D01*
G01X774708Y276442D02*
X774917Y276733D01*
X775000Y277067D01*
X774917Y277400D01*
X774667Y277692D01*
X774292Y277900D01*
X773917Y277983D01*
X773458D01*
X773083Y277900D01*
X772750Y277692D01*
X772583Y277442D01*
X772500Y277150D01*
X772583Y276817D01*
X772750Y276567D01*
X773000Y276400D01*
X773333Y276317D01*
X773625Y276400D01*
X773917Y276608D01*
X774083Y276858D01*
X774125Y277150D01*
X774042Y277483D01*
X773833Y277733D01*
X773458Y277983D01*
G01X772967Y261100D02*
Y263600D01*
X773967D01*
X774300Y263475D01*
X774550Y263183D01*
X774633Y262850D01*
X774550Y262517D01*
X774342Y262267D01*
X773967Y262142D01*
X772967D01*
G01X777817Y263392D02*
X777567Y263517D01*
X777275Y263600D01*
X776942D01*
X776567Y263475D01*
X776275Y263267D01*
X776067Y263017D01*
X775900Y262600D01*
X775858Y262225D01*
X775942Y261850D01*
X776067Y261600D01*
X776317Y261350D01*
X776608Y261183D01*
X776900Y261100D01*
X777192D01*
X777483Y261183D01*
X777733Y261308D01*
X777942Y261475D01*
G01X780000Y261100D02*
Y263600D01*
X779500Y263100D01*
G01Y261100D02*
X780500D01*
G01X783017D02*
X783100Y261642D01*
X783225Y262100D01*
X783392Y262517D01*
X783600Y262975D01*
X783933Y263600D01*
X782267D01*
G01X786200Y261100D02*
Y263600D01*
X785700Y263100D01*
G01Y261100D02*
X786700D01*
G01X779000Y267017D02*
X776500D01*
Y268058D01*
X776625Y268392D01*
X776792Y268600D01*
X777125Y268683D01*
X777458Y268600D01*
X777667Y268350D01*
X777792Y268058D01*
Y267017D01*
G01Y268058D02*
X779000Y268683D01*
G01X776917Y270158D02*
X776667Y270408D01*
X776542Y270700D01*
X776500Y271033D01*
X776583Y271450D01*
X776792Y271742D01*
X777042Y271825D01*
X777292Y271783D01*
X777500Y271617D01*
X777917Y270783D01*
X778208Y270408D01*
X778625Y270158D01*
X779000Y270075D01*
Y271825D01*
G01X776917Y273258D02*
X776667Y273508D01*
X776542Y273800D01*
X776500Y274133D01*
X776583Y274550D01*
X776792Y274842D01*
X777042Y274925D01*
X777292Y274883D01*
X777500Y274717D01*
X777917Y273883D01*
X778208Y273508D01*
X778625Y273258D01*
X779000Y273175D01*
Y274925D01*
G01Y277150D02*
X776500D01*
X777000Y276650D01*
G01X779000D02*
Y277650D01*
G01X788232Y72532D02*
Y21532D01*
X809832D01*
Y72532D01*
X788232D01*
G01X802300Y81267D02*
X799800D01*
Y82267D01*
X799925Y82600D01*
X800217Y82850D01*
X800550Y82933D01*
X800883Y82850D01*
X801133Y82642D01*
X801258Y82267D01*
Y81267D01*
G01X799800Y84367D02*
X802300D01*
Y86033D01*
G01Y88217D02*
X801758Y88300D01*
X801300Y88425D01*
X800883Y88592D01*
X800425Y88800D01*
X799800Y89133D01*
Y87467D01*
G01X801500Y97967D02*
X799000D01*
Y98967D01*
X799125Y99300D01*
X799417Y99550D01*
X799750Y99633D01*
X800083Y99550D01*
X800333Y99342D01*
X800458Y98967D01*
Y97967D01*
G01X799208Y102817D02*
X799083Y102567D01*
X799000Y102275D01*
Y101942D01*
X799125Y101567D01*
X799333Y101275D01*
X799583Y101067D01*
X800000Y100900D01*
X800375Y100858D01*
X800750Y100942D01*
X801000Y101067D01*
X801250Y101317D01*
X801417Y101608D01*
X801500Y101900D01*
Y102192D01*
X801417Y102483D01*
X801292Y102733D01*
X801125Y102942D01*
G01X801500Y105000D02*
X799000D01*
X799500Y104500D01*
G01X801500D02*
Y105500D01*
G01Y108100D02*
X801458Y108392D01*
X801333Y108725D01*
X801125Y108933D01*
X800833Y109017D01*
X800542Y108933D01*
X800292Y108683D01*
X800167Y108308D01*
Y107892D01*
X800083Y107642D01*
X799875Y107433D01*
X799583Y107350D01*
X799292Y107475D01*
X799083Y107767D01*
X799000Y108100D01*
X799083Y108433D01*
X799292Y108725D01*
X799583Y108850D01*
X799875Y108767D01*
X800083Y108558D01*
X800167Y108308D01*
Y107892D01*
X800292Y107517D01*
X800542Y107267D01*
X800833Y107183D01*
X801125Y107267D01*
X801333Y107475D01*
X801458Y107808D01*
X801500Y108100D01*
G01X801000Y110283D02*
X801292Y110533D01*
X801458Y110867D01*
X801500Y111242D01*
X801458Y111575D01*
X801250Y111908D01*
X801000Y112117D01*
X800750Y112158D01*
X800458Y112075D01*
X800250Y111783D01*
X800167Y111492D01*
Y111117D01*
G01Y111492D02*
X800042Y111742D01*
X799833Y111950D01*
X799583Y112033D01*
X799333Y111950D01*
X799125Y111742D01*
X799000Y111367D01*
X799042Y110992D01*
X799208Y110617D01*
G01X798467Y126500D02*
Y129000D01*
X799467D01*
X799800Y128875D01*
X800050Y128583D01*
X800133Y128250D01*
X800050Y127917D01*
X799842Y127667D01*
X799467Y127542D01*
X798467D01*
G01X801567Y126500D02*
Y129000D01*
X802608D01*
X802942Y128875D01*
X803150Y128708D01*
X803233Y128375D01*
X803150Y128042D01*
X802900Y127833D01*
X802608Y127708D01*
X801567D01*
G01X802608D02*
X803233Y126500D01*
G01X805500D02*
Y129000D01*
X805000Y128500D01*
G01Y126500D02*
X806000D01*
G01X808600Y129000D02*
X808267Y128917D01*
X808017Y128708D01*
X807850Y128458D01*
X807725Y128125D01*
X807683Y127750D01*
X807725Y127375D01*
X807850Y127042D01*
X808017Y126792D01*
X808267Y126583D01*
X808600Y126500D01*
X808933Y126583D01*
X809183Y126792D01*
X809350Y127042D01*
X809475Y127375D01*
X809517Y127750D01*
X809475Y128125D01*
X809350Y128458D01*
X809183Y128708D01*
X808933Y128917D01*
X808600Y129000D01*
G01X810992Y126792D02*
X811283Y126583D01*
X811617Y126500D01*
X811950Y126583D01*
X812242Y126833D01*
X812450Y127208D01*
X812533Y127583D01*
Y128042D01*
X812450Y128417D01*
X812242Y128750D01*
X811992Y128917D01*
X811700Y129000D01*
X811367Y128917D01*
X811117Y128750D01*
X810950Y128500D01*
X810867Y128167D01*
X810950Y127875D01*
X811158Y127583D01*
X811408Y127417D01*
X811700Y127375D01*
X812033Y127458D01*
X812283Y127667D01*
X812533Y128042D01*
G01X798467Y122500D02*
Y125000D01*
X799467D01*
X799800Y124875D01*
X800050Y124583D01*
X800133Y124250D01*
X800050Y123917D01*
X799842Y123667D01*
X799467Y123542D01*
X798467D01*
G01X801567Y122500D02*
Y125000D01*
X802608D01*
X802942Y124875D01*
X803150Y124708D01*
X803233Y124375D01*
X803150Y124042D01*
X802900Y123833D01*
X802608Y123708D01*
X801567D01*
G01X802608D02*
X803233Y122500D01*
G01X805500D02*
Y125000D01*
X805000Y124500D01*
G01Y122500D02*
X806000D01*
G01X808600D02*
Y125000D01*
X808100Y124500D01*
G01Y122500D02*
X809100D01*
G01X811700Y125000D02*
X811367Y124917D01*
X811117Y124708D01*
X810950Y124458D01*
X810825Y124125D01*
X810783Y123750D01*
X810825Y123375D01*
X810950Y123042D01*
X811117Y122792D01*
X811367Y122583D01*
X811700Y122500D01*
X812033Y122583D01*
X812283Y122792D01*
X812450Y123042D01*
X812575Y123375D01*
X812617Y123750D01*
X812575Y124125D01*
X812450Y124458D01*
X812283Y124708D01*
X812033Y124917D01*
X811700Y125000D01*
G01X809700Y4600D02*
Y12400D01*
X822300D01*
Y4600D01*
X809700D01*
G01X813200Y11000D02*
X812600Y10900D01*
X812100Y10400D01*
X811700Y9900D01*
X811500Y9300D01*
X811400Y8500D01*
X811500Y7800D01*
X811700Y7100D01*
X812100Y6600D01*
X812600Y6200D01*
X813200Y6000D01*
X813900Y6200D01*
X814400Y6600D01*
X814700Y7100D01*
X815000Y7800D01*
X815100Y8500D01*
X815000Y9300D01*
X814700Y9900D01*
X814400Y10400D01*
X813900Y10900D01*
X813200Y11000D01*
G01X818800Y6000D02*
Y11000D01*
X817800Y10000D01*
G01Y6000D02*
X819800D01*
G01X812517Y21500D02*
Y24000D01*
X813558D01*
X813892Y23875D01*
X814100Y23708D01*
X814183Y23375D01*
X814100Y23042D01*
X813850Y22833D01*
X813558Y22708D01*
X812517D01*
G01X813558D02*
X814183Y21500D01*
G01X815533Y22000D02*
X815783Y21708D01*
X816117Y21542D01*
X816492Y21500D01*
X816825Y21542D01*
X817158Y21750D01*
X817367Y22000D01*
X817408Y22250D01*
X817325Y22542D01*
X817033Y22750D01*
X816742Y22833D01*
X816367D01*
G01X816742D02*
X816992Y22958D01*
X817200Y23167D01*
X817283Y23417D01*
X817200Y23667D01*
X816992Y23875D01*
X816617Y24000D01*
X816242Y23958D01*
X815867Y23792D01*
G01X818842Y21792D02*
X819133Y21583D01*
X819467Y21500D01*
X819800Y21583D01*
X820092Y21833D01*
X820300Y22208D01*
X820383Y22583D01*
Y23042D01*
X820300Y23417D01*
X820092Y23750D01*
X819842Y23917D01*
X819550Y24000D01*
X819217Y23917D01*
X818967Y23750D01*
X818800Y23500D01*
X818717Y23167D01*
X818800Y22875D01*
X819008Y22583D01*
X819258Y22417D01*
X819550Y22375D01*
X819883Y22458D01*
X820133Y22667D01*
X820383Y23042D01*
G01X822650Y24000D02*
X822317Y23917D01*
X822067Y23708D01*
X821900Y23458D01*
X821775Y23125D01*
X821733Y22750D01*
X821775Y22375D01*
X821900Y22042D01*
X822067Y21792D01*
X822317Y21583D01*
X822650Y21500D01*
X822983Y21583D01*
X823233Y21792D01*
X823400Y22042D01*
X823525Y22375D01*
X823567Y22750D01*
X823525Y23125D01*
X823400Y23458D01*
X823233Y23708D01*
X822983Y23917D01*
X822650Y24000D01*
G01X812517Y25500D02*
Y28000D01*
X813558D01*
X813892Y27875D01*
X814100Y27708D01*
X814183Y27375D01*
X814100Y27042D01*
X813850Y26833D01*
X813558Y26708D01*
X812517D01*
G01X813558D02*
X814183Y25500D01*
G01X815533Y26000D02*
X815783Y25708D01*
X816117Y25542D01*
X816492Y25500D01*
X816825Y25542D01*
X817158Y25750D01*
X817367Y26000D01*
X817408Y26250D01*
X817325Y26542D01*
X817033Y26750D01*
X816742Y26833D01*
X816367D01*
G01X816742D02*
X816992Y26958D01*
X817200Y27167D01*
X817283Y27417D01*
X817200Y27667D01*
X816992Y27875D01*
X816617Y28000D01*
X816242Y27958D01*
X815867Y27792D01*
G01X819550Y25500D02*
X819842Y25542D01*
X820175Y25667D01*
X820383Y25875D01*
X820467Y26167D01*
X820383Y26458D01*
X820133Y26708D01*
X819758Y26833D01*
X819342D01*
X819092Y26917D01*
X818883Y27125D01*
X818800Y27417D01*
X818925Y27708D01*
X819217Y27917D01*
X819550Y28000D01*
X819883Y27917D01*
X820175Y27708D01*
X820300Y27417D01*
X820217Y27125D01*
X820008Y26917D01*
X819758Y26833D01*
X819342D01*
X818967Y26708D01*
X818717Y26458D01*
X818633Y26167D01*
X818717Y25875D01*
X818925Y25667D01*
X819258Y25542D01*
X819550Y25500D01*
G01X822650D02*
X822942Y25542D01*
X823275Y25667D01*
X823483Y25875D01*
X823567Y26167D01*
X823483Y26458D01*
X823233Y26708D01*
X822858Y26833D01*
X822442D01*
X822192Y26917D01*
X821983Y27125D01*
X821900Y27417D01*
X822025Y27708D01*
X822317Y27917D01*
X822650Y28000D01*
X822983Y27917D01*
X823275Y27708D01*
X823400Y27417D01*
X823317Y27125D01*
X823108Y26917D01*
X822858Y26833D01*
X822442D01*
X822067Y26708D01*
X821817Y26458D01*
X821733Y26167D01*
X821817Y25875D01*
X822025Y25667D01*
X822358Y25542D01*
X822650Y25500D01*
G01X815000Y33517D02*
X812500D01*
Y34558D01*
X812625Y34892D01*
X812792Y35100D01*
X813125Y35183D01*
X813458Y35100D01*
X813667Y34850D01*
X813792Y34558D01*
Y33517D01*
G01Y34558D02*
X815000Y35183D01*
G01X814500Y36533D02*
X814792Y36783D01*
X814958Y37117D01*
X815000Y37492D01*
X814958Y37825D01*
X814750Y38158D01*
X814500Y38367D01*
X814250Y38408D01*
X813958Y38325D01*
X813750Y38033D01*
X813667Y37742D01*
Y37367D01*
G01Y37742D02*
X813542Y37992D01*
X813333Y38200D01*
X813083Y38283D01*
X812833Y38200D01*
X812625Y37992D01*
X812500Y37617D01*
X812542Y37242D01*
X812708Y36867D01*
G01X814708Y39842D02*
X814917Y40133D01*
X815000Y40467D01*
X814917Y40800D01*
X814667Y41092D01*
X814292Y41300D01*
X813917Y41383D01*
X813458D01*
X813083Y41300D01*
X812750Y41092D01*
X812583Y40842D01*
X812500Y40550D01*
X812583Y40217D01*
X812750Y39967D01*
X813000Y39800D01*
X813333Y39717D01*
X813625Y39800D01*
X813917Y40008D01*
X814083Y40258D01*
X814125Y40550D01*
X814042Y40883D01*
X813833Y41133D01*
X813458Y41383D01*
G01X815000Y43650D02*
X812500D01*
X813000Y43150D01*
G01X815000D02*
Y44150D01*
G01X819000Y33517D02*
X816500D01*
Y34558D01*
X816625Y34892D01*
X816792Y35100D01*
X817125Y35183D01*
X817458Y35100D01*
X817667Y34850D01*
X817792Y34558D01*
Y33517D01*
G01Y34558D02*
X819000Y35183D01*
G01X818500Y36533D02*
X818792Y36783D01*
X818958Y37117D01*
X819000Y37492D01*
X818958Y37825D01*
X818750Y38158D01*
X818500Y38367D01*
X818250Y38408D01*
X817958Y38325D01*
X817750Y38033D01*
X817667Y37742D01*
Y37367D01*
G01Y37742D02*
X817542Y37992D01*
X817333Y38200D01*
X817083Y38283D01*
X816833Y38200D01*
X816625Y37992D01*
X816500Y37617D01*
X816542Y37242D01*
X816708Y36867D01*
G01X818708Y39842D02*
X818917Y40133D01*
X819000Y40467D01*
X818917Y40800D01*
X818667Y41092D01*
X818292Y41300D01*
X817917Y41383D01*
X817458D01*
X817083Y41300D01*
X816750Y41092D01*
X816583Y40842D01*
X816500Y40550D01*
X816583Y40217D01*
X816750Y39967D01*
X817000Y39800D01*
X817333Y39717D01*
X817625Y39800D01*
X817917Y40008D01*
X818083Y40258D01*
X818125Y40550D01*
X818042Y40883D01*
X817833Y41133D01*
X817458Y41383D01*
G01X816917Y42858D02*
X816667Y43108D01*
X816542Y43400D01*
X816500Y43733D01*
X816583Y44150D01*
X816792Y44442D01*
X817042Y44525D01*
X817292Y44483D01*
X817500Y44317D01*
X817917Y43483D01*
X818208Y43108D01*
X818625Y42858D01*
X819000Y42775D01*
Y44525D01*
G01X812517Y29500D02*
Y32000D01*
X813558D01*
X813892Y31875D01*
X814100Y31708D01*
X814183Y31375D01*
X814100Y31042D01*
X813850Y30833D01*
X813558Y30708D01*
X812517D01*
G01X813558D02*
X814183Y29500D01*
G01X815533Y30000D02*
X815783Y29708D01*
X816117Y29542D01*
X816492Y29500D01*
X816825Y29542D01*
X817158Y29750D01*
X817367Y30000D01*
X817408Y30250D01*
X817325Y30542D01*
X817033Y30750D01*
X816742Y30833D01*
X816367D01*
G01X816742D02*
X816992Y30958D01*
X817200Y31167D01*
X817283Y31417D01*
X817200Y31667D01*
X816992Y31875D01*
X816617Y32000D01*
X816242Y31958D01*
X815867Y31792D01*
G01X819550Y29500D02*
X819842Y29542D01*
X820175Y29667D01*
X820383Y29875D01*
X820467Y30167D01*
X820383Y30458D01*
X820133Y30708D01*
X819758Y30833D01*
X819342D01*
X819092Y30917D01*
X818883Y31125D01*
X818800Y31417D01*
X818925Y31708D01*
X819217Y31917D01*
X819550Y32000D01*
X819883Y31917D01*
X820175Y31708D01*
X820300Y31417D01*
X820217Y31125D01*
X820008Y30917D01*
X819758Y30833D01*
X819342D01*
X818967Y30708D01*
X818717Y30458D01*
X818633Y30167D01*
X818717Y29875D01*
X818925Y29667D01*
X819258Y29542D01*
X819550Y29500D01*
G01X822567D02*
X822650Y30042D01*
X822775Y30500D01*
X822942Y30917D01*
X823150Y31375D01*
X823483Y32000D01*
X821817D01*
G01X815000Y45958D02*
X812500D01*
Y47542D01*
G01X813708Y46958D02*
Y45958D01*
G01X815000Y49017D02*
X812500D01*
Y50017D01*
X812625Y50350D01*
X812917Y50600D01*
X813250Y50683D01*
X813583Y50600D01*
X813833Y50392D01*
X813958Y50017D01*
Y49017D01*
G01X813750Y53200D02*
Y54033D01*
X814500D01*
X814750Y53783D01*
X814917Y53492D01*
X815000Y53075D01*
X814917Y52658D01*
X814750Y52367D01*
X814500Y52117D01*
X814208Y51950D01*
X813875Y51867D01*
X813583D01*
X813333Y51950D01*
X813042Y52117D01*
X812792Y52367D01*
X812625Y52617D01*
X812500Y52950D01*
Y53242D01*
X812583Y53575D01*
X812750Y53825D01*
G01X815000Y55008D02*
X812500Y56050D01*
X815000Y57092D01*
G01X814125Y56717D02*
Y55383D01*
G01X814500Y61417D02*
X814750Y61625D01*
X814917Y61875D01*
X815000Y62167D01*
X814917Y62500D01*
X814750Y62750D01*
X814500Y63000D01*
X814167Y63083D01*
X812500D01*
G01Y65350D02*
X815000D01*
G01X812500Y64392D02*
Y66308D01*
G01X815000Y67408D02*
X812500Y68450D01*
X815000Y69492D01*
G01X814125Y69117D02*
Y67783D01*
G01X813750Y71800D02*
Y72633D01*
X814500D01*
X814750Y72383D01*
X814917Y72092D01*
X815000Y71675D01*
X814917Y71258D01*
X814750Y70967D01*
X814500Y70717D01*
X814208Y70550D01*
X813875Y70467D01*
X813583D01*
X813333Y70550D01*
X813042Y70717D01*
X812792Y70967D01*
X812625Y71217D01*
X812500Y71550D01*
Y71842D01*
X812583Y72175D01*
X812750Y72425D01*
G01X817708Y57817D02*
X817583Y57567D01*
X817500Y57275D01*
Y56942D01*
X817625Y56567D01*
X817833Y56275D01*
X818083Y56067D01*
X818500Y55900D01*
X818875Y55858D01*
X819250Y55942D01*
X819500Y56067D01*
X819750Y56317D01*
X819917Y56608D01*
X820000Y56900D01*
Y57192D01*
X819917Y57483D01*
X819792Y57733D01*
X819625Y57942D01*
G01X820000Y59042D02*
X817500D01*
X820000Y60958D01*
X817500D01*
G01X819500Y62183D02*
X819792Y62433D01*
X819958Y62767D01*
X820000Y63142D01*
X819958Y63475D01*
X819750Y63808D01*
X819500Y64017D01*
X819250Y64058D01*
X818958Y63975D01*
X818750Y63683D01*
X818667Y63392D01*
Y63017D01*
G01Y63392D02*
X818542Y63642D01*
X818333Y63850D01*
X818083Y63933D01*
X817833Y63850D01*
X817625Y63642D01*
X817500Y63267D01*
X817542Y62892D01*
X817708Y62517D01*
G01X811550Y92500D02*
Y90000D01*
G01X810592Y92500D02*
X812508D01*
G01X813817Y90000D02*
Y92500D01*
X814817D01*
X815150Y92375D01*
X815400Y92083D01*
X815483Y91750D01*
X815400Y91417D01*
X815192Y91167D01*
X814817Y91042D01*
X813817D01*
G01X817750Y90000D02*
Y92500D01*
X817250Y92000D01*
G01Y90000D02*
X818250D01*
G01X819933Y90375D02*
X820183Y90167D01*
X820475Y90042D01*
X820850Y90000D01*
X821225Y90083D01*
X821517Y90250D01*
X821725Y90542D01*
X821767Y90875D01*
X821683Y91208D01*
X821475Y91417D01*
X821183Y91583D01*
X820892Y91625D01*
X820600Y91583D01*
X820225Y91417D01*
X820350Y92500D01*
X821475D01*
G01X813400Y76517D02*
X810900D01*
Y77558D01*
X811025Y77892D01*
X811192Y78100D01*
X811525Y78183D01*
X811858Y78100D01*
X812067Y77850D01*
X812192Y77558D01*
Y76517D01*
G01Y77558D02*
X813400Y78183D01*
G01X811317Y79658D02*
X811067Y79908D01*
X810942Y80200D01*
X810900Y80533D01*
X810983Y80950D01*
X811192Y81242D01*
X811442Y81325D01*
X811692Y81283D01*
X811900Y81117D01*
X812317Y80283D01*
X812608Y79908D01*
X813025Y79658D01*
X813400Y79575D01*
Y81325D01*
G01X811317Y82758D02*
X811067Y83008D01*
X810942Y83300D01*
X810900Y83633D01*
X810983Y84050D01*
X811192Y84342D01*
X811442Y84425D01*
X811692Y84383D01*
X811900Y84217D01*
X812317Y83383D01*
X812608Y83008D01*
X813025Y82758D01*
X813400Y82675D01*
Y84425D01*
G01Y87150D02*
X810900D01*
X812692Y85608D01*
Y87692D01*
G01X811550Y98500D02*
Y96000D01*
G01X810592Y98500D02*
X812508D01*
G01X813817Y96000D02*
Y98500D01*
X814817D01*
X815150Y98375D01*
X815400Y98083D01*
X815483Y97750D01*
X815400Y97417D01*
X815192Y97167D01*
X814817Y97042D01*
X813817D01*
G01X817750Y96000D02*
Y98500D01*
X817250Y98000D01*
G01Y96000D02*
X818250D01*
G01X820058Y97042D02*
X820350Y97333D01*
X820600Y97500D01*
X820933Y97583D01*
X821225Y97500D01*
X821433Y97333D01*
X821600Y97083D01*
X821642Y96792D01*
X821600Y96542D01*
X821433Y96292D01*
X821183Y96083D01*
X820892Y96000D01*
X820558Y96083D01*
X820267Y96333D01*
X820100Y96708D01*
X820058Y97125D01*
X820142Y97667D01*
X820267Y97958D01*
X820475Y98250D01*
X820767Y98458D01*
X821058Y98500D01*
X821350Y98417D01*
X821558Y98208D01*
G01X811550Y104500D02*
Y102000D01*
G01X810592Y104500D02*
X812508D01*
G01X813817Y102000D02*
Y104500D01*
X814817D01*
X815150Y104375D01*
X815400Y104083D01*
X815483Y103750D01*
X815400Y103417D01*
X815192Y103167D01*
X814817Y103042D01*
X813817D01*
G01X817750Y102000D02*
Y104500D01*
X817250Y104000D01*
G01Y102000D02*
X818250D01*
G01X820850D02*
X821142Y102042D01*
X821475Y102167D01*
X821683Y102375D01*
X821767Y102667D01*
X821683Y102958D01*
X821433Y103208D01*
X821058Y103333D01*
X820642D01*
X820392Y103417D01*
X820183Y103625D01*
X820100Y103917D01*
X820225Y104208D01*
X820517Y104417D01*
X820850Y104500D01*
X821183Y104417D01*
X821475Y104208D01*
X821600Y103917D01*
X821517Y103625D01*
X821308Y103417D01*
X821058Y103333D01*
X820642D01*
X820267Y103208D01*
X820017Y102958D01*
X819933Y102667D01*
X820017Y102375D01*
X820225Y102167D01*
X820558Y102042D01*
X820850Y102000D01*
G01X811550Y110500D02*
Y108000D01*
G01X810592Y110500D02*
X812508D01*
G01X813817Y108000D02*
Y110500D01*
X814817D01*
X815150Y110375D01*
X815400Y110083D01*
X815483Y109750D01*
X815400Y109417D01*
X815192Y109167D01*
X814817Y109042D01*
X813817D01*
G01X817750Y108000D02*
Y110500D01*
X817250Y110000D01*
G01Y108000D02*
X818250D01*
G01X820767D02*
X820850Y108542D01*
X820975Y109000D01*
X821142Y109417D01*
X821350Y109875D01*
X821683Y110500D01*
X820017D01*
G01X805667Y114200D02*
Y116700D01*
X806667D01*
X807000Y116575D01*
X807250Y116283D01*
X807333Y115950D01*
X807250Y115617D01*
X807042Y115367D01*
X806667Y115242D01*
X805667D01*
G01X810517Y116492D02*
X810267Y116617D01*
X809975Y116700D01*
X809642D01*
X809267Y116575D01*
X808975Y116367D01*
X808767Y116117D01*
X808600Y115700D01*
X808558Y115325D01*
X808642Y114950D01*
X808767Y114700D01*
X809017Y114450D01*
X809308Y114283D01*
X809600Y114200D01*
X809892D01*
X810183Y114283D01*
X810433Y114408D01*
X810642Y114575D01*
G01X812700Y114200D02*
Y116700D01*
X812200Y116200D01*
G01Y114200D02*
X813200D01*
G01X815717D02*
X815800Y114742D01*
X815925Y115200D01*
X816092Y115617D01*
X816300Y116075D01*
X816633Y116700D01*
X814967D01*
G01X817983Y114575D02*
X818233Y114367D01*
X818525Y114242D01*
X818900Y114200D01*
X819275Y114283D01*
X819567Y114450D01*
X819775Y114742D01*
X819817Y115075D01*
X819733Y115408D01*
X819525Y115617D01*
X819233Y115783D01*
X818942Y115825D01*
X818650Y115783D01*
X818275Y115617D01*
X818400Y116700D01*
X819525D01*
G01X806067Y118300D02*
Y120800D01*
X807067D01*
X807400Y120675D01*
X807650Y120383D01*
X807733Y120050D01*
X807650Y119717D01*
X807442Y119467D01*
X807067Y119342D01*
X806067D01*
G01X810917Y120592D02*
X810667Y120717D01*
X810375Y120800D01*
X810042D01*
X809667Y120675D01*
X809375Y120467D01*
X809167Y120217D01*
X809000Y119800D01*
X808958Y119425D01*
X809042Y119050D01*
X809167Y118800D01*
X809417Y118550D01*
X809708Y118383D01*
X810000Y118300D01*
X810292D01*
X810583Y118383D01*
X810833Y118508D01*
X811042Y118675D01*
G01X813100Y118300D02*
Y120800D01*
X812600Y120300D01*
G01Y118300D02*
X813600D01*
G01X815408Y119342D02*
X815700Y119633D01*
X815950Y119800D01*
X816283Y119883D01*
X816575Y119800D01*
X816783Y119633D01*
X816950Y119383D01*
X816992Y119092D01*
X816950Y118842D01*
X816783Y118592D01*
X816533Y118383D01*
X816242Y118300D01*
X815908Y118383D01*
X815617Y118633D01*
X815450Y119008D01*
X815408Y119425D01*
X815492Y119967D01*
X815617Y120258D01*
X815825Y120550D01*
X816117Y120758D01*
X816408Y120800D01*
X816700Y120717D01*
X816908Y120508D01*
G01X818383Y118675D02*
X818633Y118467D01*
X818925Y118342D01*
X819300Y118300D01*
X819675Y118383D01*
X819967Y118550D01*
X820175Y118842D01*
X820217Y119175D01*
X820133Y119508D01*
X819925Y119717D01*
X819633Y119883D01*
X819342Y119925D01*
X819050Y119883D01*
X818675Y119717D01*
X818800Y120800D01*
X819925D01*
G01X808017Y137000D02*
Y139500D01*
X809017D01*
X809350Y139375D01*
X809600Y139083D01*
X809683Y138750D01*
X809600Y138417D01*
X809392Y138167D01*
X809017Y138042D01*
X808017D01*
G01X812867Y139292D02*
X812617Y139417D01*
X812325Y139500D01*
X811992D01*
X811617Y139375D01*
X811325Y139167D01*
X811117Y138917D01*
X810950Y138500D01*
X810908Y138125D01*
X810992Y137750D01*
X811117Y137500D01*
X811367Y137250D01*
X811658Y137083D01*
X811950Y137000D01*
X812242D01*
X812533Y137083D01*
X812783Y137208D01*
X812992Y137375D01*
G01X815050Y137000D02*
X815342Y137042D01*
X815675Y137167D01*
X815883Y137375D01*
X815967Y137667D01*
X815883Y137958D01*
X815633Y138208D01*
X815258Y138333D01*
X814842D01*
X814592Y138417D01*
X814383Y138625D01*
X814300Y138917D01*
X814425Y139208D01*
X814717Y139417D01*
X815050Y139500D01*
X815383Y139417D01*
X815675Y139208D01*
X815800Y138917D01*
X815717Y138625D01*
X815508Y138417D01*
X815258Y138333D01*
X814842D01*
X814467Y138208D01*
X814217Y137958D01*
X814133Y137667D01*
X814217Y137375D01*
X814425Y137167D01*
X814758Y137042D01*
X815050Y137000D01*
G01X817358Y139083D02*
X817608Y139333D01*
X817900Y139458D01*
X818233Y139500D01*
X818650Y139417D01*
X818942Y139208D01*
X819025Y138958D01*
X818983Y138708D01*
X818817Y138500D01*
X817983Y138083D01*
X817608Y137792D01*
X817358Y137375D01*
X817275Y137000D01*
X819025D01*
G01X808017Y132500D02*
Y135000D01*
X809017D01*
X809350Y134875D01*
X809600Y134583D01*
X809683Y134250D01*
X809600Y133917D01*
X809392Y133667D01*
X809017Y133542D01*
X808017D01*
G01X811117Y132500D02*
Y135000D01*
X812158D01*
X812492Y134875D01*
X812700Y134708D01*
X812783Y134375D01*
X812700Y134042D01*
X812450Y133833D01*
X812158Y133708D01*
X811117D01*
G01X812158D02*
X812783Y132500D01*
G01X815050Y135000D02*
Y132500D01*
G01X814092Y135000D02*
X816008D01*
G01X817358Y134583D02*
X817608Y134833D01*
X817900Y134958D01*
X818233Y135000D01*
X818650Y134917D01*
X818942Y134708D01*
X819025Y134458D01*
X818983Y134208D01*
X818817Y134000D01*
X817983Y133583D01*
X817608Y133292D01*
X817358Y132875D01*
X817275Y132500D01*
X819025D01*
G01X820000Y149067D02*
X817500D01*
Y150067D01*
X817625Y150400D01*
X817917Y150650D01*
X818250Y150733D01*
X818583Y150650D01*
X818833Y150442D01*
X818958Y150067D01*
Y149067D01*
G01X817500Y152083D02*
X819292D01*
X819667Y152250D01*
X819917Y152583D01*
X820000Y153000D01*
X819917Y153417D01*
X819667Y153750D01*
X819292Y153917D01*
X817500D01*
G01X818958Y155308D02*
X818667Y155600D01*
X818500Y155850D01*
X818417Y156183D01*
X818500Y156475D01*
X818667Y156683D01*
X818917Y156850D01*
X819208Y156892D01*
X819458Y156850D01*
X819708Y156683D01*
X819917Y156433D01*
X820000Y156142D01*
X819917Y155808D01*
X819667Y155517D01*
X819292Y155350D01*
X818875Y155308D01*
X818333Y155392D01*
X818042Y155517D01*
X817750Y155725D01*
X817542Y156017D01*
X817500Y156308D01*
X817583Y156600D01*
X817792Y156808D01*
G01X804517Y148500D02*
Y151000D01*
X805517D01*
X805850Y150875D01*
X806100Y150583D01*
X806183Y150250D01*
X806100Y149917D01*
X805892Y149667D01*
X805517Y149542D01*
X804517D01*
G01X807617Y148500D02*
Y151000D01*
X808658D01*
X808992Y150875D01*
X809200Y150708D01*
X809283Y150375D01*
X809200Y150042D01*
X808950Y149833D01*
X808658Y149708D01*
X807617D01*
G01X808658D02*
X809283Y148500D01*
G01X810842Y148792D02*
X811133Y148583D01*
X811467Y148500D01*
X811800Y148583D01*
X812092Y148833D01*
X812300Y149208D01*
X812383Y149583D01*
Y150042D01*
X812300Y150417D01*
X812092Y150750D01*
X811842Y150917D01*
X811550Y151000D01*
X811217Y150917D01*
X810967Y150750D01*
X810800Y150500D01*
X810717Y150167D01*
X810800Y149875D01*
X811008Y149583D01*
X811258Y149417D01*
X811550Y149375D01*
X811883Y149458D01*
X812133Y149667D01*
X812383Y150042D01*
G01X814650Y148500D02*
Y151000D01*
X814150Y150500D01*
G01Y148500D02*
X815150D01*
G01X823500Y162500D02*
X823417Y161833D01*
X823083Y161250D01*
X822583Y160750D01*
X822000Y160417D01*
X821333Y160250D01*
X820667D01*
X820000Y160417D01*
X819417Y160750D01*
X818917Y161250D01*
X818583Y161833D01*
X818500Y162500D01*
X818583Y163167D01*
X818917Y163750D01*
X819417Y164250D01*
X820000Y164583D01*
X820667Y164750D01*
X821333D01*
X822000Y164583D01*
X822583Y164250D01*
X823083Y163750D01*
X823417Y163167D01*
X823500Y162500D01*
G01X822833Y166350D02*
X823250Y167017D01*
X823500Y167767D01*
Y168433D01*
X823250Y169100D01*
X822833Y169600D01*
X822250Y169850D01*
X821667Y169683D01*
X821167Y169267D01*
X820833Y168517D01*
X820667Y167517D01*
X820333Y166933D01*
X819750Y166683D01*
X819167Y166850D01*
X818750Y167267D01*
X818500Y167850D01*
Y168433D01*
X818667Y169017D01*
X819083Y169517D01*
G01X818917Y175533D02*
X818667Y175033D01*
X818500Y174450D01*
Y173783D01*
X818750Y173033D01*
X819167Y172450D01*
X819667Y172033D01*
X820500Y171700D01*
X821250Y171617D01*
X822000Y171783D01*
X822500Y172033D01*
X823000Y172533D01*
X823333Y173117D01*
X823500Y173700D01*
Y174283D01*
X823333Y174867D01*
X823083Y175367D01*
X822750Y175783D01*
G01X823500Y179300D02*
X818500D01*
X819500Y178300D01*
G01X823500D02*
Y180300D01*
G01X823667Y184900D02*
X823583Y184733D01*
X823417D01*
X823333Y184900D01*
X823417Y185067D01*
X823583D01*
X823667Y184900D01*
G01X821417D02*
X821333Y184733D01*
X821167D01*
X821083Y184900D01*
X821167Y185067D01*
X821333D01*
X821417Y184900D01*
G01X822750Y188667D02*
X823167Y189167D01*
X823417Y189750D01*
X823500Y190500D01*
X823333Y191250D01*
X823000Y191833D01*
X822417Y192250D01*
X821750Y192333D01*
X821083Y192167D01*
X820667Y191750D01*
X820333Y191167D01*
X820250Y190583D01*
X820333Y190000D01*
X820667Y189250D01*
X818500Y189500D01*
Y191750D01*
G01X823500Y193933D02*
X818500D01*
X822667Y196100D01*
X818500Y198267D01*
X823500D01*
G01Y199950D02*
X818500D01*
G01Y203450D02*
X823500D01*
G01X821000D02*
Y199950D01*
G01X818500Y205717D02*
Y208883D01*
X823500Y205717D01*
Y208883D01*
G01X804617Y154600D02*
Y157100D01*
X805617D01*
X805950Y156975D01*
X806200Y156683D01*
X806283Y156350D01*
X806200Y156017D01*
X805992Y155767D01*
X805617Y155642D01*
X804617D01*
G01X807717Y154600D02*
Y157100D01*
X808758D01*
X809092Y156975D01*
X809300Y156808D01*
X809383Y156475D01*
X809300Y156142D01*
X809050Y155933D01*
X808758Y155808D01*
X807717D01*
G01X808758D02*
X809383Y154600D01*
G01X810942Y154892D02*
X811233Y154683D01*
X811567Y154600D01*
X811900Y154683D01*
X812192Y154933D01*
X812400Y155308D01*
X812483Y155683D01*
Y156142D01*
X812400Y156517D01*
X812192Y156850D01*
X811942Y157017D01*
X811650Y157100D01*
X811317Y157017D01*
X811067Y156850D01*
X810900Y156600D01*
X810817Y156267D01*
X810900Y155975D01*
X811108Y155683D01*
X811358Y155517D01*
X811650Y155475D01*
X811983Y155558D01*
X812233Y155767D01*
X812483Y156142D01*
G01X814667Y154600D02*
X814750Y155142D01*
X814875Y155600D01*
X815042Y156017D01*
X815250Y156475D01*
X815583Y157100D01*
X813917D01*
G01X812500Y166067D02*
X810000D01*
Y167067D01*
X810125Y167400D01*
X810417Y167650D01*
X810750Y167733D01*
X811083Y167650D01*
X811333Y167442D01*
X811458Y167067D01*
Y166067D01*
G01X811250Y170250D02*
Y171083D01*
X812000D01*
X812250Y170833D01*
X812417Y170542D01*
X812500Y170125D01*
X812417Y169708D01*
X812250Y169417D01*
X812000Y169167D01*
X811708Y169000D01*
X811375Y168917D01*
X811083D01*
X810833Y169000D01*
X810542Y169167D01*
X810292Y169417D01*
X810125Y169667D01*
X810000Y170000D01*
Y170292D01*
X810083Y170625D01*
X810250Y170875D01*
G01X812000Y172183D02*
X812292Y172433D01*
X812458Y172767D01*
X812500Y173142D01*
X812458Y173475D01*
X812250Y173808D01*
X812000Y174017D01*
X811750Y174058D01*
X811458Y173975D01*
X811250Y173683D01*
X811167Y173392D01*
Y173017D01*
G01Y173392D02*
X811042Y173642D01*
X810833Y173850D01*
X810583Y173933D01*
X810333Y173850D01*
X810125Y173642D01*
X810000Y173267D01*
X810042Y172892D01*
X810208Y172517D01*
G01X812500Y177067D02*
X810000D01*
Y178067D01*
X810125Y178400D01*
X810417Y178650D01*
X810750Y178733D01*
X811083Y178650D01*
X811333Y178442D01*
X811458Y178067D01*
Y177067D01*
G01X811250Y181250D02*
Y182083D01*
X812000D01*
X812250Y181833D01*
X812417Y181542D01*
X812500Y181125D01*
X812417Y180708D01*
X812250Y180417D01*
X812000Y180167D01*
X811708Y180000D01*
X811375Y179917D01*
X811083D01*
X810833Y180000D01*
X810542Y180167D01*
X810292Y180417D01*
X810125Y180667D01*
X810000Y181000D01*
Y181292D01*
X810083Y181625D01*
X810250Y181875D01*
G01X810417Y183308D02*
X810167Y183558D01*
X810042Y183850D01*
X810000Y184183D01*
X810083Y184600D01*
X810292Y184892D01*
X810542Y184975D01*
X810792Y184933D01*
X811000Y184767D01*
X811417Y183933D01*
X811708Y183558D01*
X812125Y183308D01*
X812500Y183225D01*
Y184975D01*
G01X813000Y192067D02*
X810500D01*
Y193067D01*
X810625Y193400D01*
X810917Y193650D01*
X811250Y193733D01*
X811583Y193650D01*
X811833Y193442D01*
X811958Y193067D01*
Y192067D01*
G01X810500Y195167D02*
X813000D01*
Y196833D01*
G01X810917Y198308D02*
X810667Y198558D01*
X810542Y198850D01*
X810500Y199183D01*
X810583Y199600D01*
X810792Y199892D01*
X811042Y199975D01*
X811292Y199933D01*
X811500Y199767D01*
X811917Y198933D01*
X812208Y198558D01*
X812625Y198308D01*
X813000Y198225D01*
Y199975D01*
G01X814933Y231000D02*
Y238000D01*
X821067Y231000D01*
Y238000D01*
G01X808467Y215500D02*
Y218000D01*
X809467D01*
X809800Y217875D01*
X810050Y217583D01*
X810133Y217250D01*
X810050Y216917D01*
X809842Y216667D01*
X809467Y216542D01*
X808467D01*
G01X813317Y217792D02*
X813067Y217917D01*
X812775Y218000D01*
X812442D01*
X812067Y217875D01*
X811775Y217667D01*
X811567Y217417D01*
X811400Y217000D01*
X811358Y216625D01*
X811442Y216250D01*
X811567Y216000D01*
X811817Y215750D01*
X812108Y215583D01*
X812400Y215500D01*
X812692D01*
X812983Y215583D01*
X813233Y215708D01*
X813442Y215875D01*
G01X815500Y215500D02*
Y218000D01*
X815000Y217500D01*
G01Y215500D02*
X816000D01*
G01X818600D02*
X818892Y215542D01*
X819225Y215667D01*
X819433Y215875D01*
X819517Y216167D01*
X819433Y216458D01*
X819183Y216708D01*
X818808Y216833D01*
X818392D01*
X818142Y216917D01*
X817933Y217125D01*
X817850Y217417D01*
X817975Y217708D01*
X818267Y217917D01*
X818600Y218000D01*
X818933Y217917D01*
X819225Y217708D01*
X819350Y217417D01*
X819267Y217125D01*
X819058Y216917D01*
X818808Y216833D01*
X818392D01*
X818017Y216708D01*
X817767Y216458D01*
X817683Y216167D01*
X817767Y215875D01*
X817975Y215667D01*
X818308Y215542D01*
X818600Y215500D01*
G01X821700Y218000D02*
X821367Y217917D01*
X821117Y217708D01*
X820950Y217458D01*
X820825Y217125D01*
X820783Y216750D01*
X820825Y216375D01*
X820950Y216042D01*
X821117Y215792D01*
X821367Y215583D01*
X821700Y215500D01*
X822033Y215583D01*
X822283Y215792D01*
X822450Y216042D01*
X822575Y216375D01*
X822617Y216750D01*
X822575Y217125D01*
X822450Y217458D01*
X822283Y217708D01*
X822033Y217917D01*
X821700Y218000D01*
G01X808467Y224000D02*
Y226500D01*
X809467D01*
X809800Y226375D01*
X810050Y226083D01*
X810133Y225750D01*
X810050Y225417D01*
X809842Y225167D01*
X809467Y225042D01*
X808467D01*
G01X813317Y226292D02*
X813067Y226417D01*
X812775Y226500D01*
X812442D01*
X812067Y226375D01*
X811775Y226167D01*
X811567Y225917D01*
X811400Y225500D01*
X811358Y225125D01*
X811442Y224750D01*
X811567Y224500D01*
X811817Y224250D01*
X812108Y224083D01*
X812400Y224000D01*
X812692D01*
X812983Y224083D01*
X813233Y224208D01*
X813442Y224375D01*
G01X815500Y224000D02*
Y226500D01*
X815000Y226000D01*
G01Y224000D02*
X816000D01*
G01X818517D02*
X818600Y224542D01*
X818725Y225000D01*
X818892Y225417D01*
X819100Y225875D01*
X819433Y226500D01*
X817767D01*
G01X821700D02*
X821367Y226417D01*
X821117Y226208D01*
X820950Y225958D01*
X820825Y225625D01*
X820783Y225250D01*
X820825Y224875D01*
X820950Y224542D01*
X821117Y224292D01*
X821367Y224083D01*
X821700Y224000D01*
X822033Y224083D01*
X822283Y224292D01*
X822450Y224542D01*
X822575Y224875D01*
X822617Y225250D01*
X822575Y225625D01*
X822450Y225958D01*
X822283Y226208D01*
X822033Y226417D01*
X821700Y226500D01*
G01X808467Y220000D02*
Y222500D01*
X809467D01*
X809800Y222375D01*
X810050Y222083D01*
X810133Y221750D01*
X810050Y221417D01*
X809842Y221167D01*
X809467Y221042D01*
X808467D01*
G01X813317Y222292D02*
X813067Y222417D01*
X812775Y222500D01*
X812442D01*
X812067Y222375D01*
X811775Y222167D01*
X811567Y221917D01*
X811400Y221500D01*
X811358Y221125D01*
X811442Y220750D01*
X811567Y220500D01*
X811817Y220250D01*
X812108Y220083D01*
X812400Y220000D01*
X812692D01*
X812983Y220083D01*
X813233Y220208D01*
X813442Y220375D01*
G01X815500Y220000D02*
Y222500D01*
X815000Y222000D01*
G01Y220000D02*
X816000D01*
G01X817808Y221042D02*
X818100Y221333D01*
X818350Y221500D01*
X818683Y221583D01*
X818975Y221500D01*
X819183Y221333D01*
X819350Y221083D01*
X819392Y220792D01*
X819350Y220542D01*
X819183Y220292D01*
X818933Y220083D01*
X818642Y220000D01*
X818308Y220083D01*
X818017Y220333D01*
X817850Y220708D01*
X817808Y221125D01*
X817892Y221667D01*
X818017Y221958D01*
X818225Y222250D01*
X818517Y222458D01*
X818808Y222500D01*
X819100Y222417D01*
X819308Y222208D01*
G01X820908Y222083D02*
X821158Y222333D01*
X821450Y222458D01*
X821783Y222500D01*
X822200Y222417D01*
X822492Y222208D01*
X822575Y221958D01*
X822533Y221708D01*
X822367Y221500D01*
X821533Y221083D01*
X821158Y220792D01*
X820908Y220375D01*
X820825Y220000D01*
X822575D01*
G01X824000Y248000D02*
Y229500D01*
X812000D01*
Y259500D01*
X825000D01*
G01X810500Y235117D02*
X808000D01*
Y236117D01*
X808125Y236450D01*
X808417Y236700D01*
X808750Y236783D01*
X809083Y236700D01*
X809333Y236492D01*
X809458Y236117D01*
Y235117D01*
G01X808000Y239050D02*
X810500D01*
G01X808000Y238092D02*
Y240008D01*
G01X808208Y243067D02*
X808083Y242817D01*
X808000Y242525D01*
Y242192D01*
X808125Y241817D01*
X808333Y241525D01*
X808583Y241317D01*
X809000Y241150D01*
X809375Y241108D01*
X809750Y241192D01*
X810000Y241317D01*
X810250Y241567D01*
X810417Y241858D01*
X810500Y242150D01*
Y242442D01*
X810417Y242733D01*
X810292Y242983D01*
X810125Y243192D01*
G01X810000Y244333D02*
X810292Y244583D01*
X810458Y244917D01*
X810500Y245292D01*
X810458Y245625D01*
X810250Y245958D01*
X810000Y246167D01*
X809750Y246208D01*
X809458Y246125D01*
X809250Y245833D01*
X809167Y245542D01*
Y245167D01*
G01Y245542D02*
X809042Y245792D01*
X808833Y246000D01*
X808583Y246083D01*
X808333Y246000D01*
X808125Y245792D01*
X808000Y245417D01*
X808042Y245042D01*
X808208Y244667D01*
G01X814067Y239500D02*
Y242000D01*
X815108D01*
X815442Y241875D01*
X815650Y241708D01*
X815733Y241375D01*
X815650Y241042D01*
X815400Y240833D01*
X815108Y240708D01*
X814067D01*
G01X815108D02*
X815733Y239500D01*
G01X817292Y239792D02*
X817583Y239583D01*
X817917Y239500D01*
X818250Y239583D01*
X818542Y239833D01*
X818750Y240208D01*
X818833Y240583D01*
Y241042D01*
X818750Y241417D01*
X818542Y241750D01*
X818292Y241917D01*
X818000Y242000D01*
X817667Y241917D01*
X817417Y241750D01*
X817250Y241500D01*
X817167Y241167D01*
X817250Y240875D01*
X817458Y240583D01*
X817708Y240417D01*
X818000Y240375D01*
X818333Y240458D01*
X818583Y240667D01*
X818833Y241042D01*
G01X821100Y239500D02*
Y242000D01*
X820600Y241500D01*
G01Y239500D02*
X821600D01*
G01X814067Y243500D02*
Y246000D01*
X815108D01*
X815442Y245875D01*
X815650Y245708D01*
X815733Y245375D01*
X815650Y245042D01*
X815400Y244833D01*
X815108Y244708D01*
X814067D01*
G01X815108D02*
X815733Y243500D01*
G01X818000D02*
X818292Y243542D01*
X818625Y243667D01*
X818833Y243875D01*
X818917Y244167D01*
X818833Y244458D01*
X818583Y244708D01*
X818208Y244833D01*
X817792D01*
X817542Y244917D01*
X817333Y245125D01*
X817250Y245417D01*
X817375Y245708D01*
X817667Y245917D01*
X818000Y246000D01*
X818333Y245917D01*
X818625Y245708D01*
X818750Y245417D01*
X818667Y245125D01*
X818458Y244917D01*
X818208Y244833D01*
X817792D01*
X817417Y244708D01*
X817167Y244458D01*
X817083Y244167D01*
X817167Y243875D01*
X817375Y243667D01*
X817708Y243542D01*
X818000Y243500D01*
G01X821017D02*
X821100Y244042D01*
X821225Y244500D01*
X821392Y244917D01*
X821600Y245375D01*
X821933Y246000D01*
X820267D01*
G01X815767Y253792D02*
X815517Y253917D01*
X815225Y254000D01*
X814892D01*
X814517Y253875D01*
X814225Y253667D01*
X814017Y253417D01*
X813850Y253000D01*
X813808Y252625D01*
X813892Y252250D01*
X814017Y252000D01*
X814267Y251750D01*
X814558Y251583D01*
X814850Y251500D01*
X815142D01*
X815433Y251583D01*
X815683Y251708D01*
X815892Y251875D01*
G01X817033Y252000D02*
X817283Y251708D01*
X817617Y251542D01*
X817992Y251500D01*
X818325Y251542D01*
X818658Y251750D01*
X818867Y252000D01*
X818908Y252250D01*
X818825Y252542D01*
X818533Y252750D01*
X818242Y252833D01*
X817867D01*
G01X818242D02*
X818492Y252958D01*
X818700Y253167D01*
X818783Y253417D01*
X818700Y253667D01*
X818492Y253875D01*
X818117Y254000D01*
X817742Y253958D01*
X817367Y253792D01*
G01X820133Y251875D02*
X820383Y251667D01*
X820675Y251542D01*
X821050Y251500D01*
X821425Y251583D01*
X821717Y251750D01*
X821925Y252042D01*
X821967Y252375D01*
X821883Y252708D01*
X821675Y252917D01*
X821383Y253083D01*
X821092Y253125D01*
X820800Y253083D01*
X820425Y252917D01*
X820550Y254000D01*
X821675D01*
G01X823358Y252542D02*
X823650Y252833D01*
X823900Y253000D01*
X824233Y253083D01*
X824525Y253000D01*
X824733Y252833D01*
X824900Y252583D01*
X824942Y252292D01*
X824900Y252042D01*
X824733Y251792D01*
X824483Y251583D01*
X824192Y251500D01*
X823858Y251583D01*
X823567Y251833D01*
X823400Y252208D01*
X823358Y252625D01*
X823442Y253167D01*
X823567Y253458D01*
X823775Y253750D01*
X824067Y253958D01*
X824358Y254000D01*
X824650Y253917D01*
X824858Y253708D01*
G01X814017Y255500D02*
Y258000D01*
X815058D01*
X815392Y257875D01*
X815600Y257708D01*
X815683Y257375D01*
X815600Y257042D01*
X815350Y256833D01*
X815058Y256708D01*
X814017D01*
G01X815058D02*
X815683Y255500D01*
G01X817950D02*
Y258000D01*
X817450Y257500D01*
G01Y255500D02*
X818450D01*
G01X820258Y257583D02*
X820508Y257833D01*
X820800Y257958D01*
X821133Y258000D01*
X821550Y257917D01*
X821842Y257708D01*
X821925Y257458D01*
X821883Y257208D01*
X821717Y257000D01*
X820883Y256583D01*
X820508Y256292D01*
X820258Y255875D01*
X820175Y255500D01*
X821925D01*
G01X823233Y256000D02*
X823483Y255708D01*
X823817Y255542D01*
X824192Y255500D01*
X824525Y255542D01*
X824858Y255750D01*
X825067Y256000D01*
X825108Y256250D01*
X825025Y256542D01*
X824733Y256750D01*
X824442Y256833D01*
X824067D01*
G01X824442D02*
X824692Y256958D01*
X824900Y257167D01*
X824983Y257417D01*
X824900Y257667D01*
X824692Y257875D01*
X824317Y258000D01*
X823942Y257958D01*
X823567Y257792D01*
G01X814067Y247500D02*
Y250000D01*
X815108D01*
X815442Y249875D01*
X815650Y249708D01*
X815733Y249375D01*
X815650Y249042D01*
X815400Y248833D01*
X815108Y248708D01*
X814067D01*
G01X815108D02*
X815733Y247500D01*
G01X817917D02*
X818000Y248042D01*
X818125Y248500D01*
X818292Y248917D01*
X818500Y249375D01*
X818833Y250000D01*
X817167D01*
G01X821600Y247500D02*
Y250000D01*
X820058Y248208D01*
X822142D01*
G01X809967Y267100D02*
Y269600D01*
X810967D01*
X811300Y269475D01*
X811550Y269183D01*
X811633Y268850D01*
X811550Y268517D01*
X811342Y268267D01*
X810967Y268142D01*
X809967D01*
G01X814817Y269392D02*
X814567Y269517D01*
X814275Y269600D01*
X813942D01*
X813567Y269475D01*
X813275Y269267D01*
X813067Y269017D01*
X812900Y268600D01*
X812858Y268225D01*
X812942Y267850D01*
X813067Y267600D01*
X813317Y267350D01*
X813608Y267183D01*
X813900Y267100D01*
X814192D01*
X814483Y267183D01*
X814733Y267308D01*
X814942Y267475D01*
G01X817000Y267100D02*
Y269600D01*
X816500Y269100D01*
G01Y267100D02*
X817500D01*
G01X820017D02*
X820100Y267642D01*
X820225Y268100D01*
X820392Y268517D01*
X820600Y268975D01*
X820933Y269600D01*
X819267D01*
G01X822492Y267392D02*
X822783Y267183D01*
X823117Y267100D01*
X823450Y267183D01*
X823742Y267433D01*
X823950Y267808D01*
X824033Y268183D01*
Y268642D01*
X823950Y269017D01*
X823742Y269350D01*
X823492Y269517D01*
X823200Y269600D01*
X822867Y269517D01*
X822617Y269350D01*
X822450Y269100D01*
X822367Y268767D01*
X822450Y268475D01*
X822658Y268183D01*
X822908Y268017D01*
X823200Y267975D01*
X823533Y268058D01*
X823783Y268267D01*
X824033Y268642D01*
G01X809967Y271100D02*
Y273600D01*
X810967D01*
X811300Y273475D01*
X811550Y273183D01*
X811633Y272850D01*
X811550Y272517D01*
X811342Y272267D01*
X810967Y272142D01*
X809967D01*
G01X814817Y273392D02*
X814567Y273517D01*
X814275Y273600D01*
X813942D01*
X813567Y273475D01*
X813275Y273267D01*
X813067Y273017D01*
X812900Y272600D01*
X812858Y272225D01*
X812942Y271850D01*
X813067Y271600D01*
X813317Y271350D01*
X813608Y271183D01*
X813900Y271100D01*
X814192D01*
X814483Y271183D01*
X814733Y271308D01*
X814942Y271475D01*
G01X817000Y271100D02*
Y273600D01*
X816500Y273100D01*
G01Y271100D02*
X817500D01*
G01X820017D02*
X820100Y271642D01*
X820225Y272100D01*
X820392Y272517D01*
X820600Y272975D01*
X820933Y273600D01*
X819267D01*
G01X823200Y271100D02*
X823492Y271142D01*
X823825Y271267D01*
X824033Y271475D01*
X824117Y271767D01*
X824033Y272058D01*
X823783Y272308D01*
X823408Y272433D01*
X822992D01*
X822742Y272517D01*
X822533Y272725D01*
X822450Y273017D01*
X822575Y273308D01*
X822867Y273517D01*
X823200Y273600D01*
X823533Y273517D01*
X823825Y273308D01*
X823950Y273017D01*
X823867Y272725D01*
X823658Y272517D01*
X823408Y272433D01*
X822992D01*
X822617Y272308D01*
X822367Y272058D01*
X822283Y271767D01*
X822367Y271475D01*
X822575Y271267D01*
X822908Y271142D01*
X823200Y271100D01*
G01X809967Y263100D02*
Y265600D01*
X810967D01*
X811300Y265475D01*
X811550Y265183D01*
X811633Y264850D01*
X811550Y264517D01*
X811342Y264267D01*
X810967Y264142D01*
X809967D01*
G01X814817Y265392D02*
X814567Y265517D01*
X814275Y265600D01*
X813942D01*
X813567Y265475D01*
X813275Y265267D01*
X813067Y265017D01*
X812900Y264600D01*
X812858Y264225D01*
X812942Y263850D01*
X813067Y263600D01*
X813317Y263350D01*
X813608Y263183D01*
X813900Y263100D01*
X814192D01*
X814483Y263183D01*
X814733Y263308D01*
X814942Y263475D01*
G01X817000Y263100D02*
Y265600D01*
X816500Y265100D01*
G01Y263100D02*
X817500D01*
G01X819308Y264142D02*
X819600Y264433D01*
X819850Y264600D01*
X820183Y264683D01*
X820475Y264600D01*
X820683Y264433D01*
X820850Y264183D01*
X820892Y263892D01*
X820850Y263642D01*
X820683Y263392D01*
X820433Y263183D01*
X820142Y263100D01*
X819808Y263183D01*
X819517Y263433D01*
X819350Y263808D01*
X819308Y264225D01*
X819392Y264767D01*
X819517Y265058D01*
X819725Y265350D01*
X820017Y265558D01*
X820308Y265600D01*
X820600Y265517D01*
X820808Y265308D01*
G01X822492Y263392D02*
X822783Y263183D01*
X823117Y263100D01*
X823450Y263183D01*
X823742Y263433D01*
X823950Y263808D01*
X824033Y264183D01*
Y264642D01*
X823950Y265017D01*
X823742Y265350D01*
X823492Y265517D01*
X823200Y265600D01*
X822867Y265517D01*
X822617Y265350D01*
X822450Y265100D01*
X822367Y264767D01*
X822450Y264475D01*
X822658Y264183D01*
X822908Y264017D01*
X823200Y263975D01*
X823533Y264058D01*
X823783Y264267D01*
X824033Y264642D01*
G54D18*
G01X17000Y161000D02*
X6500D01*
Y151000D01*
X31500D01*
Y130000D01*
X40500D01*
G01X58000Y141000D02*
X57500D01*
Y161500D01*
X52500D01*
Y160500D01*
X33500D01*
Y159000D01*
X29000D01*
G01X58000Y129000D02*
Y141000D01*
X77500D01*
G01X66000Y123500D02*
Y128500D01*
X62000D01*
G01X70500D02*
X66000D01*
Y123500D01*
G01X76500Y141000D02*
X86500D01*
Y140000D01*
G01D02*
Y138000D01*
X95500D01*
Y133500D01*
X121500D01*
Y149000D01*
G01X175500Y240500D02*
X177500D01*
G54D19*
G01X26900Y100500D02*
X27750D01*
G01X24400D02*
X25300D01*
G01X18400Y113500D02*
X21600D01*
G01X19200Y127000D02*
X18350D01*
G01X21700D02*
X20800D01*
G01X73400Y173000D02*
X70200D01*
G01X71600Y200600D02*
X70750D01*
G01X74100D02*
X73200D01*
G01X76600D02*
X75750D01*
G01X79100D02*
X78200D01*
G01X107750Y144000D02*
X106900D01*
G01X110250D02*
X109350D01*
G01X106600Y223400D02*
Y222550D01*
G01Y225900D02*
Y225000D01*
G01Y218300D02*
Y217450D01*
G01Y220800D02*
Y219900D01*
G01X101800Y246100D02*
X102650D01*
G01X99300D02*
X100200D01*
G01X100220Y255400D02*
X101070D01*
G01X97720D02*
X98620D01*
G01X107000Y269300D02*
Y270150D01*
G01Y266800D02*
Y267700D01*
G01X123500Y119300D02*
Y120200D01*
G01Y121800D02*
Y122650D01*
G01X136300Y152700D02*
X137150D01*
G01X133800D02*
X134700D01*
G01X147000Y194400D02*
Y197600D01*
G01X168500Y59300D02*
Y60200D01*
G01Y61800D02*
Y62650D01*
G01X161300Y198500D02*
X162150D01*
G01X158800D02*
X159700D01*
G01X178000Y62600D02*
Y59400D01*
G01X176200Y137500D02*
X175350D01*
G01X178700D02*
X177800D01*
G01X186200Y213450D02*
Y214350D01*
G01Y215950D02*
Y216800D01*
G01X203200Y200000D02*
X202350D01*
G01X196600Y200001D02*
X199800D01*
G01X193251Y211750D02*
Y208550D01*
G01X195700Y216750D02*
Y213550D01*
G01X197700Y256000D02*
X196850D01*
G01X200200D02*
X199300D01*
G01X205700Y200000D02*
X204800D01*
G01X252000Y207800D02*
Y208650D01*
G01Y205300D02*
Y206200D01*
G01X254200Y223000D02*
X253350D01*
G01X256700D02*
X255800D01*
G01X286700Y157500D02*
X285850D01*
G01X289200D02*
X288300D01*
G01X429700Y74700D02*
Y73850D01*
G01Y77200D02*
Y76300D01*
G01X429996Y231263D02*
Y230413D01*
G01Y233763D02*
Y232863D01*
G01X439000Y73800D02*
Y74700D01*
G01Y76300D02*
Y77150D01*
G01X439496Y231263D02*
Y230413D01*
G01Y233763D02*
Y232863D01*
G01X514300Y191000D02*
X515150D01*
G01X511800D02*
X512700D01*
G01X521700Y222000D02*
X520850D01*
G01X524200D02*
X523300D01*
G01X554480Y231782D02*
Y232632D01*
G01Y229282D02*
Y230182D01*
G01X661000Y89300D02*
Y90200D01*
G01Y91800D02*
Y92650D01*
G01X660000Y119900D02*
Y120750D01*
G01Y117400D02*
Y118300D01*
G01X661000Y110700D02*
Y109850D01*
G01Y113200D02*
Y112300D01*
G01Y138700D02*
Y137850D01*
G01Y141200D02*
Y140300D01*
G01X668000Y151800D02*
Y152700D01*
G01Y154300D02*
Y155150D01*
G01X721500Y89200D02*
Y88350D01*
G01Y91700D02*
Y90800D01*
G01X740800Y63500D02*
X741700D01*
G01X743300D02*
X744150D01*
G01X776700Y132200D02*
Y131350D01*
G01Y134700D02*
Y133800D01*
G01X776500Y153700D02*
Y152850D01*
G01Y156200D02*
Y155300D01*
M02*
